(kicad_pcb
	(version 20260206)
	(generator "pcbnew")
	(generator_version "10.0")
	(general
		(thickness 1.6)
		(legacy_teardrops no)
	)
	(paper "A4")
	(layers
		(0 "F.Cu" signal "TOP")
		(4 "In1.Cu" signal "GND")
		(6 "In2.Cu" signal "IN1")
		(8 "In3.Cu" signal "GND1")
		(10 "In4.Cu" signal "IN2")
		(12 "In5.Cu" signal "GND2")
		(14 "In6.Cu" signal "IN3")
		(16 "In7.Cu" signal "GND3")
		(18 "In8.Cu" signal "VCC")
		(20 "In9.Cu" signal "VCC1")
		(22 "In10.Cu" signal "GND4")
		(24 "In11.Cu" signal "IN4")
		(26 "In12.Cu" signal "GND5")
		(28 "In13.Cu" signal "IN5")
		(30 "In14.Cu" signal "GND6")
		(32 "In15.Cu" signal "IN6")
		(34 "In16.Cu" signal "GND7")
		(2 "B.Cu" signal "BOTTOM")
		(9 "F.Adhes" user "F.Adhesive")
		(11 "B.Adhes" user "B.Adhesive")
		(13 "F.Paste" user "Package Geometry/Pastemask Top")
		(15 "B.Paste" user "Package Geometry/Pastemask Bottom")
		(5 "F.SilkS" user "Ref Des/Silkscreen Top")
		(7 "B.SilkS" user "Ref Des/Silkscreen Bottom")
		(1 "F.Mask" user "Board Geometry/Soldermask Top")
		(3 "B.Mask" user "Board Geometry/Soldermask Bottom")
		(17 "Dwgs.User" user "User.Drawings")
		(19 "Cmts.User" user "User.Comments")
		(21 "Eco1.User" user "User.Eco1")
		(23 "Eco2.User" user "User.Eco2")
		(25 "Edge.Cuts" user "Board Geometry/Outline")
		(27 "Margin" user)
		(31 "F.CrtYd" user "Package Geometry/Place Bound Top")
		(29 "B.CrtYd" user "Package Geometry/Place Bound Bottom")
		(35 "F.Fab" user "Ref Des/Assembly Top")
		(33 "B.Fab" user "Ref Des/Assembly Bottom")
	)
	(setup
		(pad_to_mask_clearance 0)
		(allow_soldermask_bridges_in_footprints no)
		(tenting
			(front yes)
			(back yes)
		)
		(covering
			(front no)
			(back no)
		)
		(plugging
			(front no)
			(back no)
		)
		(capping no)
		(filling no)
		(pcbplotparams
			(layerselection 0x00000000_00000000_55555555_5755f5ff)
			(plot_on_all_layers_selection 0x00000000_00000000_00000000_00000000)
			(disableapertmacros no)
			(usegerberextensions no)
			(usegerberattributes yes)
			(usegerberadvancedattributes yes)
			(creategerberjobfile yes)
			(dashed_line_dash_ratio 12)
			(dashed_line_gap_ratio 3)
			(svgprecision 4)
			(plotframeref no)
			(mode 1)
			(useauxorigin no)
			(pdf_front_fp_property_popups yes)
			(pdf_back_fp_property_popups yes)
			(pdf_metadata yes)
			(pdf_single_document no)
			(dxfpolygonmode yes)
			(dxfimperialunits yes)
			(dxfusepcbnewfont yes)
			(psnegative no)
			(psa4output no)
			(plot_black_and_white yes)
			(sketchpadsonfab no)
			(plotpadnumbers no)
			(hidednponfab no)
			(sketchdnponfab yes)
			(crossoutdnponfab yes)
			(subtractmaskfromsilk no)
			(outputformat 1)
			(mirror no)
			(drillshape 1)
			(scaleselection 1)
			(outputdirectory "")
		)
	)
	(zone
		(layer "In1.Cu")
		(hatch none 0.5)
		(connect_pads
			(clearance 0)
		)
		(min_thickness 0.25)
		(keepout
			(tracks not_allowed)
			(vias allowed)
			(pads allowed)
			(copperpour not_allowed)
			(footprints allowed)
		)
		(placement
			(enabled no)
			(sheetname "")
		)
		(fill
			(thermal_gap 0.5)
			(thermal_bridge_width 0.5)
			(island_removal_mode 0)
		)
		(polygon
			(pts
				(arc
					(start 293.029386 -197.582282)
					(mid 293.025666 -197.591262)
					(end 293.016686 -197.594982)
				)
				(arc
					(start 291.543486 -197.594982)
					(mid 291.534506 -197.591262)
					(end 291.530786 -197.582282)
				)
				(arc
					(start 291.530786 -197.087744)
					(mid 291.534506 -197.078764)
					(end 291.543486 -197.075044)
				)
				(arc
					(start 293.016686 -197.075044)
					(mid 293.025666 -197.078764)
					(end 293.029386 -197.087744)
				)
			)
		)
	)
	(zone
		(layer "In1.Cu")
		(hatch none 0.5)
		(connect_pads
			(clearance 0)
		)
		(min_thickness 0.25)
		(keepout
			(tracks not_allowed)
			(vias allowed)
			(pads allowed)
			(copperpour not_allowed)
			(footprints allowed)
		)
		(placement
			(enabled no)
			(sheetname "")
		)
		(fill
			(thermal_gap 0.5)
			(thermal_bridge_width 0.5)
			(island_removal_mode 0)
		)
		(polygon
			(pts
				(arc
					(start 420.661338 -202.682094)
					(mid 420.657618 -202.691074)
					(end 420.648638 -202.694794)
				)
				(arc
					(start 419.175438 -202.694794)
					(mid 419.166458 -202.691074)
					(end 419.162738 -202.682094)
				)
				(arc
					(start 419.162738 -202.187556)
					(mid 419.166458 -202.178576)
					(end 419.175438 -202.174856)
				)
				(arc
					(start 420.648638 -202.174856)
					(mid 420.657618 -202.178576)
					(end 420.661338 -202.187556)
				)
			)
		)
	)
	(zone
		(layer "In1.Cu")
		(hatch none 0.5)
		(connect_pads
			(clearance 0)
		)
		(min_thickness 0.25)
		(keepout
			(tracks not_allowed)
			(vias allowed)
			(pads allowed)
			(copperpour not_allowed)
			(footprints allowed)
		)
		(placement
			(enabled no)
			(sheetname "")
		)
		(fill
			(thermal_gap 0.5)
			(thermal_bridge_width 0.5)
			(island_removal_mode 0)
		)
		(polygon
			(pts
				(arc
					(start 33.445196 -226.482402)
					(mid 33.441476 -226.491382)
					(end 33.432496 -226.495102)
				)
				(arc
					(start 31.959296 -226.495102)
					(mid 31.950316 -226.491382)
					(end 31.946596 -226.482402)
				)
				(arc
					(start 31.946596 -225.987864)
					(mid 31.950316 -225.978884)
					(end 31.959296 -225.975164)
				)
				(arc
					(start 33.432496 -225.975164)
					(mid 33.441476 -225.978884)
					(end 33.445196 -225.987864)
				)
			)
		)
	)
	(zone
		(layer "In1.Cu")
		(hatch none 0.5)
		(connect_pads
			(clearance 0)
		)
		(min_thickness 0.25)
		(keepout
			(tracks not_allowed)
			(vias allowed)
			(pads allowed)
			(copperpour not_allowed)
			(footprints allowed)
		)
		(placement
			(enabled no)
			(sheetname "")
		)
		(fill
			(thermal_gap 0.5)
			(thermal_bridge_width 0.5)
			(island_removal_mode 0)
		)
		(polygon
			(pts
				(arc
					(start 25.901396 -273.232372)
					(mid 25.897676 -273.241352)
					(end 25.888696 -273.245072)
				)
				(arc
					(start 24.415496 -273.245072)
					(mid 24.406516 -273.241352)
					(end 24.402796 -273.232372)
				)
				(arc
					(start 24.402796 -272.737834)
					(mid 24.406516 -272.728854)
					(end 24.415496 -272.725134)
				)
				(arc
					(start 25.888696 -272.725134)
					(mid 25.897676 -272.728854)
					(end 25.901396 -272.737834)
				)
			)
		)
	)
	(zone
		(layer "In1.Cu")
		(hatch none 0.5)
		(connect_pads
			(clearance 0)
		)
		(min_thickness 0.25)
		(keepout
			(tracks not_allowed)
			(vias allowed)
			(pads allowed)
			(copperpour not_allowed)
			(footprints allowed)
		)
		(placement
			(enabled no)
			(sheetname "")
		)
		(fill
			(thermal_gap 0.5)
			(thermal_bridge_width 0.5)
			(island_removal_mode 0)
		)
		(polygon
			(pts
				(arc
					(start 187.809378 -273.232372)
					(mid 187.805658 -273.241352)
					(end 187.796678 -273.245072)
				)
				(arc
					(start 186.323478 -273.245072)
					(mid 186.314498 -273.241352)
					(end 186.310778 -273.232372)
				)
				(arc
					(start 186.310778 -272.737834)
					(mid 186.314498 -272.728854)
					(end 186.323478 -272.725134)
				)
				(arc
					(start 187.796678 -272.725134)
					(mid 187.805658 -272.728854)
					(end 187.809378 -272.737834)
				)
			)
		)
	)
	(zone
		(layer "In1.Cu")
		(hatch none 0.5)
		(connect_pads
			(clearance 0)
		)
		(min_thickness 0.25)
		(keepout
			(tracks not_allowed)
			(vias allowed)
			(pads allowed)
			(copperpour not_allowed)
			(footprints allowed)
		)
		(placement
			(enabled no)
			(sheetname "")
		)
		(fill
			(thermal_gap 0.5)
			(thermal_bridge_width 0.5)
			(island_removal_mode 0)
		)
		(polygon
			(pts
				(arc
					(start 288.929318 -237.532164)
					(mid 288.925598 -237.541144)
					(end 288.916618 -237.544864)
				)
				(arc
					(start 287.443418 -237.544864)
					(mid 287.434438 -237.541144)
					(end 287.430718 -237.532164)
				)
				(arc
					(start 287.430718 -237.037626)
					(mid 287.434438 -237.028646)
					(end 287.443418 -237.024926)
				)
				(arc
					(start 288.916618 -237.024926)
					(mid 288.925598 -237.028646)
					(end 288.929318 -237.037626)
				)
			)
		)
	)
	(zone
		(layer "In1.Cu")
		(hatch none 0.5)
		(connect_pads
			(clearance 0)
		)
		(min_thickness 0.25)
		(keepout
			(tracks not_allowed)
			(vias allowed)
			(pads allowed)
			(copperpour not_allowed)
			(footprints allowed)
		)
		(placement
			(enabled no)
			(sheetname "")
		)
		(fill
			(thermal_gap 0.5)
			(thermal_bridge_width 0.5)
			(island_removal_mode 0)
		)
		(polygon
			(pts
				(arc
					(start 169.277284 -216.282524)
					(mid 169.273564 -216.291504)
					(end 169.264584 -216.295224)
				)
				(arc
					(start 167.791384 -216.295224)
					(mid 167.782404 -216.291504)
					(end 167.778684 -216.282524)
				)
				(arc
					(start 167.778684 -215.787986)
					(mid 167.782404 -215.779006)
					(end 167.791384 -215.775286)
				)
				(arc
					(start 169.264584 -215.775286)
					(mid 169.273564 -215.779006)
					(end 169.277284 -215.787986)
				)
			)
		)
	)
	(zone
		(layer "In1.Cu")
		(hatch none 0.5)
		(connect_pads
			(clearance 0)
		)
		(min_thickness 0.25)
		(keepout
			(tracks not_allowed)
			(vias allowed)
			(pads allowed)
			(copperpour not_allowed)
			(footprints allowed)
		)
		(placement
			(enabled no)
			(sheetname "")
		)
		(fill
			(thermal_gap 0.5)
			(thermal_bridge_width 0.5)
			(island_removal_mode 0)
		)
		(polygon
			(pts
				(arc
					(start 92.71889 -383.440686)
					(mid 92.84589 -383.567686)
					(end 92.97289 -383.440686)
				)
				(arc
					(start 92.97289 -383.364486)
					(mid 92.84589 -383.237486)
					(end 92.71889 -383.364486)
				)
			)
		)
	)
	(zone
		(layer "In1.Cu")
		(hatch none 0.5)
		(connect_pads
			(clearance 0)
		)
		(min_thickness 0.25)
		(keepout
			(tracks not_allowed)
			(vias allowed)
			(pads allowed)
			(copperpour not_allowed)
			(footprints allowed)
		)
		(placement
			(enabled no)
			(sheetname "")
		)
		(fill
			(thermal_gap 0.5)
			(thermal_bridge_width 0.5)
			(island_removal_mode 0)
		)
		(polygon
			(pts
				(arc
					(start 60.177426 -315.732414)
					(mid 60.173706 -315.741394)
					(end 60.164726 -315.745114)
				)
				(arc
					(start 58.691526 -315.745114)
					(mid 58.682546 -315.741394)
					(end 58.678826 -315.732414)
				)
				(arc
					(start 58.678826 -315.237876)
					(mid 58.682546 -315.228896)
					(end 58.691526 -315.225176)
				)
				(arc
					(start 60.164726 -315.225176)
					(mid 60.173706 -315.228896)
					(end 60.177426 -315.237876)
				)
			)
		)
	)
	(zone
		(layer "In1.Cu")
		(hatch none 0.5)
		(connect_pads
			(clearance 0)
		)
		(min_thickness 0.25)
		(keepout
			(tracks not_allowed)
			(vias allowed)
			(pads allowed)
			(copperpour not_allowed)
			(footprints allowed)
		)
		(placement
			(enabled no)
			(sheetname "")
		)
		(fill
			(thermal_gap 0.5)
			(thermal_bridge_width 0.5)
			(island_removal_mode 0)
		)
		(polygon
			(pts
				(arc
					(start 296.473372 -307.232304)
					(mid 296.469652 -307.241284)
					(end 296.460672 -307.245004)
				)
				(arc
					(start 294.987472 -307.245004)
					(mid 294.978492 -307.241284)
					(end 294.974772 -307.232304)
				)
				(arc
					(start 294.974772 -306.737766)
					(mid 294.978492 -306.728786)
					(end 294.987472 -306.725066)
				)
				(arc
					(start 296.460672 -306.725066)
					(mid 296.469652 -306.728786)
					(end 296.473372 -306.737766)
				)
			)
		)
	)
	(zone
		(layer "In1.Cu")
		(hatch none 0.5)
		(connect_pads
			(clearance 0)
		)
		(min_thickness 0.25)
		(keepout
			(tracks not_allowed)
			(vias allowed)
			(pads allowed)
			(copperpour not_allowed)
			(footprints allowed)
		)
		(placement
			(enabled no)
			(sheetname "")
		)
		(fill
			(thermal_gap 0.5)
			(thermal_bridge_width 0.5)
			(island_removal_mode 0)
		)
		(polygon
			(pts
				(arc
					(start 435.749446 -232.432098)
					(mid 435.745726 -232.441078)
					(end 435.736746 -232.444798)
				)
				(arc
					(start 434.263546 -232.444798)
					(mid 434.254566 -232.441078)
					(end 434.250846 -232.432098)
				)
				(arc
					(start 434.250846 -231.93756)
					(mid 434.254566 -231.92858)
					(end 434.263546 -231.92486)
				)
				(arc
					(start 435.736746 -231.92486)
					(mid 435.745726 -231.92858)
					(end 435.749446 -231.93756)
				)
			)
		)
	)
	(zone
		(layer "In1.Cu")
		(hatch none 0.5)
		(connect_pads
			(clearance 0)
		)
		(min_thickness 0.25)
		(keepout
			(tracks not_allowed)
			(vias allowed)
			(pads allowed)
			(copperpour not_allowed)
			(footprints allowed)
		)
		(placement
			(enabled no)
			(sheetname "")
		)
		(fill
			(thermal_gap 0.5)
			(thermal_bridge_width 0.5)
			(island_removal_mode 0)
		)
		(polygon
			(pts
				(arc
					(start 273.841464 -204.382116)
					(mid 273.837744 -204.391096)
					(end 273.828764 -204.394816)
				)
				(arc
					(start 272.355564 -204.394816)
					(mid 272.346584 -204.391096)
					(end 272.342864 -204.382116)
				)
				(arc
					(start 272.342864 -203.887578)
					(mid 272.346584 -203.878598)
					(end 272.355564 -203.874878)
				)
				(arc
					(start 273.828764 -203.874878)
					(mid 273.837744 -203.878598)
					(end 273.841464 -203.887578)
				)
			)
		)
	)
	(zone
		(layer "In1.Cu")
		(hatch none 0.5)
		(connect_pads
			(clearance 0)
		)
		(min_thickness 0.25)
		(keepout
			(tracks not_allowed)
			(vias allowed)
			(pads allowed)
			(copperpour not_allowed)
			(footprints allowed)
		)
		(placement
			(enabled no)
			(sheetname "")
		)
		(fill
			(thermal_gap 0.5)
			(thermal_bridge_width 0.5)
			(island_removal_mode 0)
		)
		(polygon
			(pts
				(arc
					(start 439.849514 -219.682314)
					(mid 439.845794 -219.691294)
					(end 439.836814 -219.695014)
				)
				(arc
					(start 438.363614 -219.695014)
					(mid 438.354634 -219.691294)
					(end 438.350914 -219.682314)
				)
				(arc
					(start 438.350914 -219.187776)
					(mid 438.354634 -219.178796)
					(end 438.363614 -219.175076)
				)
				(arc
					(start 439.836814 -219.175076)
					(mid 439.845794 -219.178796)
					(end 439.849514 -219.187776)
				)
			)
		)
	)
	(zone
		(layer "In1.Cu")
		(hatch none 0.5)
		(connect_pads
			(clearance 0)
		)
		(min_thickness 0.25)
		(keepout
			(tracks not_allowed)
			(vias allowed)
			(pads allowed)
			(copperpour not_allowed)
			(footprints allowed)
		)
		(placement
			(enabled no)
			(sheetname "")
		)
		(fill
			(thermal_gap 0.5)
			(thermal_bridge_width 0.5)
			(island_removal_mode 0)
		)
		(polygon
			(pts
				(arc
					(start 428.205392 -253.682246)
					(mid 428.201672 -253.691226)
					(end 428.192692 -253.694946)
				)
				(arc
					(start 426.719492 -253.694946)
					(mid 426.710512 -253.691226)
					(end 426.706792 -253.682246)
				)
				(arc
					(start 426.706792 -253.187708)
					(mid 426.710512 -253.178728)
					(end 426.719492 -253.175008)
				)
				(arc
					(start 428.192692 -253.175008)
					(mid 428.201672 -253.178728)
					(end 428.205392 -253.187708)
				)
			)
		)
	)
	(zone
		(layer "In1.Cu")
		(hatch none 0.5)
		(connect_pads
			(clearance 0)
		)
		(min_thickness 0.25)
		(keepout
			(tracks not_allowed)
			(vias allowed)
			(pads allowed)
			(copperpour not_allowed)
			(footprints allowed)
		)
		(placement
			(enabled no)
			(sheetname "")
		)
		(fill
			(thermal_gap 0.5)
			(thermal_bridge_width 0.5)
			(island_removal_mode 0)
		)
		(polygon
			(pts
				(arc
					(start 180.265324 -293.632382)
					(mid 180.261604 -293.641362)
					(end 180.252624 -293.645082)
				)
				(arc
					(start 178.779424 -293.645082)
					(mid 178.770444 -293.641362)
					(end 178.766724 -293.632382)
				)
				(arc
					(start 178.766724 -293.137844)
					(mid 178.770444 -293.128864)
					(end 178.779424 -293.125144)
				)
				(arc
					(start 180.252624 -293.125144)
					(mid 180.261604 -293.128864)
					(end 180.265324 -293.137844)
				)
			)
		)
	)
	(zone
		(layer "In1.Cu")
		(hatch none 0.5)
		(connect_pads
			(clearance 0)
		)
		(min_thickness 0.25)
		(keepout
			(tracks not_allowed)
			(vias allowed)
			(pads allowed)
			(copperpour not_allowed)
			(footprints allowed)
		)
		(placement
			(enabled no)
			(sheetname "")
		)
		(fill
			(thermal_gap 0.5)
			(thermal_bridge_width 0.5)
			(island_removal_mode 0)
		)
		(polygon
			(pts
				(arc
					(start 116.961158 -385.31038)
					(mid 116.580158 -385.31038)
					(end 116.961158 -385.31038)
				)
			)
		)
	)
	(zone
		(layer "In1.Cu")
		(hatch none 0.5)
		(connect_pads
			(clearance 0)
		)
		(min_thickness 0.25)
		(keepout
			(tracks not_allowed)
			(vias allowed)
			(pads allowed)
			(copperpour not_allowed)
			(footprints allowed)
		)
		(placement
			(enabled no)
			(sheetname "")
		)
		(fill
			(thermal_gap 0.5)
			(thermal_bridge_width 0.5)
			(island_removal_mode 0)
		)
		(polygon
			(pts
				(arc
					(start 202.897232 -276.632416)
					(mid 202.893512 -276.641396)
					(end 202.884532 -276.645116)
				)
				(arc
					(start 201.411332 -276.645116)
					(mid 201.402352 -276.641396)
					(end 201.398632 -276.632416)
				)
				(arc
					(start 201.398632 -276.137878)
					(mid 201.402352 -276.128898)
					(end 201.411332 -276.125178)
				)
				(arc
					(start 202.884532 -276.125178)
					(mid 202.893512 -276.128898)
					(end 202.897232 -276.137878)
				)
			)
		)
	)
	(zone
		(layer "In1.Cu")
		(hatch none 0.5)
		(connect_pads
			(clearance 0)
		)
		(min_thickness 0.25)
		(keepout
			(tracks not_allowed)
			(vias allowed)
			(pads allowed)
			(copperpour not_allowed)
			(footprints allowed)
		)
		(placement
			(enabled no)
			(sheetname "")
		)
		(fill
			(thermal_gap 0.5)
			(thermal_bridge_width 0.5)
			(island_removal_mode 0)
		)
		(polygon
			(pts
				(arc
					(start 308.370224 -399.143474)
					(mid 308.065424 -399.143474)
					(end 308.370224 -399.143474)
				)
			)
		)
	)
	(zone
		(layer "In1.Cu")
		(hatch none 0.5)
		(connect_pads
			(clearance 0)
		)
		(min_thickness 0.25)
		(keepout
			(tracks not_allowed)
			(vias allowed)
			(pads allowed)
			(copperpour not_allowed)
			(footprints allowed)
		)
		(placement
			(enabled no)
			(sheetname "")
		)
		(fill
			(thermal_gap 0.5)
			(thermal_bridge_width 0.5)
			(island_removal_mode 0)
		)
		(polygon
			(pts
				(arc
					(start 277.941532 -274.082256)
					(mid 277.937812 -274.091236)
					(end 277.928832 -274.094956)
				)
				(arc
					(start 276.455632 -274.094956)
					(mid 276.446652 -274.091236)
					(end 276.442932 -274.082256)
				)
				(arc
					(start 276.442932 -273.587718)
					(mid 276.446652 -273.578738)
					(end 276.455632 -273.575018)
				)
				(arc
					(start 277.928832 -273.575018)
					(mid 277.937812 -273.578738)
					(end 277.941532 -273.587718)
				)
			)
		)
	)
	(zone
		(layer "In1.Cu")
		(hatch none 0.5)
		(connect_pads
			(clearance 0)
		)
		(min_thickness 0.25)
		(keepout
			(tracks not_allowed)
			(vias allowed)
			(pads allowed)
			(copperpour not_allowed)
			(footprints allowed)
		)
		(placement
			(enabled no)
			(sheetname "")
		)
		(fill
			(thermal_gap 0.5)
			(thermal_bridge_width 0.5)
			(island_removal_mode 0)
		)
		(polygon
			(pts
				(arc
					(start 450.8373 -250.282202)
					(mid 450.83358 -250.291182)
					(end 450.8246 -250.294902)
				)
				(arc
					(start 449.3514 -250.294902)
					(mid 449.34242 -250.291182)
					(end 449.3387 -250.282202)
				)
				(arc
					(start 449.3387 -249.787664)
					(mid 449.34242 -249.778684)
					(end 449.3514 -249.774964)
				)
				(arc
					(start 450.8246 -249.774964)
					(mid 450.83358 -249.778684)
					(end 450.8373 -249.787664)
				)
			)
		)
	)
	(zone
		(layer "In1.Cu")
		(hatch none 0.5)
		(connect_pads
			(clearance 0)
		)
		(min_thickness 0.25)
		(keepout
			(tracks not_allowed)
			(vias allowed)
			(pads allowed)
			(copperpour not_allowed)
			(footprints allowed)
		)
		(placement
			(enabled no)
			(sheetname "")
		)
		(fill
			(thermal_gap 0.5)
			(thermal_bridge_width 0.5)
			(island_removal_mode 0)
		)
		(polygon
			(pts
				(arc
					(start 122.961146 -385.31038)
					(mid 122.580146 -385.31038)
					(end 122.961146 -385.31038)
				)
			)
		)
	)
	(zone
		(layer "In1.Cu")
		(hatch none 0.5)
		(connect_pads
			(clearance 0)
		)
		(min_thickness 0.25)
		(keepout
			(tracks not_allowed)
			(vias allowed)
			(pads allowed)
			(copperpour not_allowed)
			(footprints allowed)
		)
		(placement
			(enabled no)
			(sheetname "")
		)
		(fill
			(thermal_gap 0.5)
			(thermal_bridge_width 0.5)
			(island_removal_mode 0)
		)
		(polygon
			(pts
				(arc
					(start 348.718632 -391.822686)
					(mid 348.845632 -391.949686)
					(end 348.972632 -391.822686)
				)
				(arc
					(start 348.972632 -391.746486)
					(mid 348.845632 -391.619486)
					(end 348.718632 -391.746486)
				)
			)
		)
	)
	(zone
		(layer "In1.Cu")
		(hatch none 0.5)
		(connect_pads
			(clearance 0)
		)
		(min_thickness 0.25)
		(keepout
			(tracks not_allowed)
			(vias allowed)
			(pads allowed)
			(copperpour not_allowed)
			(footprints allowed)
		)
		(placement
			(enabled no)
			(sheetname "")
		)
		(fill
			(thermal_gap 0.5)
			(thermal_bridge_width 0.5)
			(island_removal_mode 0)
		)
		(polygon
			(pts
				(arc
					(start 266.29741 -200.132188)
					(mid 266.29369 -200.141168)
					(end 266.28471 -200.144888)
				)
				(arc
					(start 264.81151 -200.144888)
					(mid 264.80253 -200.141168)
					(end 264.79881 -200.132188)
				)
				(arc
					(start 264.79881 -199.63765)
					(mid 264.80253 -199.62867)
					(end 264.81151 -199.62495)
				)
				(arc
					(start 266.28471 -199.62495)
					(mid 266.29369 -199.62867)
					(end 266.29741 -199.63765)
				)
			)
		)
	)
	(zone
		(layer "In1.Cu")
		(hatch none 0.5)
		(connect_pads
			(clearance 0)
		)
		(min_thickness 0.25)
		(keepout
			(tracks not_allowed)
			(vias allowed)
			(pads allowed)
			(copperpour not_allowed)
			(footprints allowed)
		)
		(placement
			(enabled no)
			(sheetname "")
		)
		(fill
			(thermal_gap 0.5)
			(thermal_bridge_width 0.5)
			(island_removal_mode 0)
		)
		(polygon
			(pts
				(arc
					(start 420.661338 -207.78216)
					(mid 420.657618 -207.79114)
					(end 420.648638 -207.79486)
				)
				(arc
					(start 419.175438 -207.79486)
					(mid 419.166458 -207.79114)
					(end 419.162738 -207.78216)
				)
				(arc
					(start 419.162738 -207.287622)
					(mid 419.166458 -207.278642)
					(end 419.175438 -207.274922)
				)
				(arc
					(start 420.648638 -207.274922)
					(mid 420.657618 -207.278642)
					(end 420.661338 -207.287622)
				)
			)
		)
	)
	(zone
		(layer "In1.Cu")
		(hatch none 0.5)
		(connect_pads
			(clearance 0)
		)
		(min_thickness 0.25)
		(keepout
			(tracks not_allowed)
			(vias allowed)
			(pads allowed)
			(copperpour not_allowed)
			(footprints allowed)
		)
		(placement
			(enabled no)
			(sheetname "")
		)
		(fill
			(thermal_gap 0.5)
			(thermal_bridge_width 0.5)
			(island_removal_mode 0)
		)
		(polygon
			(pts
				(arc
					(start 447.393568 -236.68228)
					(mid 447.389848 -236.69126)
					(end 447.380868 -236.69498)
				)
				(arc
					(start 445.907668 -236.69498)
					(mid 445.898688 -236.69126)
					(end 445.894968 -236.68228)
				)
				(arc
					(start 445.894968 -236.187742)
					(mid 445.898688 -236.178762)
					(end 445.907668 -236.175042)
				)
				(arc
					(start 447.380868 -236.175042)
					(mid 447.389848 -236.178762)
					(end 447.393568 -236.187742)
				)
			)
		)
	)
	(zone
		(layer "In1.Cu")
		(hatch none 0.5)
		(connect_pads
			(clearance 0)
		)
		(min_thickness 0.25)
		(keepout
			(tracks not_allowed)
			(vias allowed)
			(pads allowed)
			(copperpour not_allowed)
			(footprints allowed)
		)
		(placement
			(enabled no)
			(sheetname "")
		)
		(fill
			(thermal_gap 0.5)
			(thermal_bridge_width 0.5)
			(island_removal_mode 0)
		)
		(polygon
			(pts
				(arc
					(start 176.821338 -211.182458)
					(mid 176.817618 -211.191438)
					(end 176.808638 -211.195158)
				)
				(arc
					(start 175.335438 -211.195158)
					(mid 175.326458 -211.191438)
					(end 175.322738 -211.182458)
				)
				(arc
					(start 175.322738 -210.68792)
					(mid 175.326458 -210.67894)
					(end 175.335438 -210.67522)
				)
				(arc
					(start 176.808638 -210.67522)
					(mid 176.817618 -210.67894)
					(end 176.821338 -210.68792)
				)
			)
		)
	)
	(zone
		(layer "In1.Cu")
		(hatch none 0.5)
		(connect_pads
			(clearance 0)
		)
		(min_thickness 0.25)
		(keepout
			(tracks not_allowed)
			(vias allowed)
			(pads allowed)
			(copperpour not_allowed)
			(footprints allowed)
		)
		(placement
			(enabled no)
			(sheetname "")
		)
		(fill
			(thermal_gap 0.5)
			(thermal_bridge_width 0.5)
			(island_removal_mode 0)
		)
		(polygon
			(pts
				(arc
					(start 206.9973 -199.282558)
					(mid 206.99358 -199.291538)
					(end 206.9846 -199.295258)
				)
				(arc
					(start 205.5114 -199.295258)
					(mid 205.50242 -199.291538)
					(end 205.4987 -199.282558)
				)
				(arc
					(start 205.4987 -198.78802)
					(mid 205.50242 -198.77904)
					(end 205.5114 -198.77532)
				)
				(arc
					(start 206.9846 -198.77532)
					(mid 206.99358 -198.77904)
					(end 206.9973 -198.78802)
				)
			)
		)
	)
	(zone
		(layer "In1.Cu")
		(hatch none 0.5)
		(connect_pads
			(clearance 0)
		)
		(min_thickness 0.25)
		(keepout
			(tracks not_allowed)
			(vias allowed)
			(pads allowed)
			(copperpour not_allowed)
			(footprints allowed)
		)
		(placement
			(enabled no)
			(sheetname "")
		)
		(fill
			(thermal_gap 0.5)
			(thermal_bridge_width 0.5)
			(island_removal_mode 0)
		)
		(polygon
			(pts
				(arc
					(start 202.897232 -308.93258)
					(mid 202.893512 -308.94156)
					(end 202.884532 -308.94528)
				)
				(arc
					(start 201.411332 -308.94528)
					(mid 201.402352 -308.94156)
					(end 201.398632 -308.93258)
				)
				(arc
					(start 201.398632 -308.438042)
					(mid 201.402352 -308.429062)
					(end 201.411332 -308.425342)
				)
				(arc
					(start 202.884532 -308.425342)
					(mid 202.893512 -308.429062)
					(end 202.897232 -308.438042)
				)
			)
		)
	)
	(zone
		(layer "In1.Cu")
		(hatch none 0.5)
		(connect_pads
			(clearance 0)
		)
		(min_thickness 0.25)
		(keepout
			(tracks not_allowed)
			(vias allowed)
			(pads allowed)
			(copperpour not_allowed)
			(footprints allowed)
		)
		(placement
			(enabled no)
			(sheetname "")
		)
		(fill
			(thermal_gap 0.5)
			(thermal_bridge_width 0.5)
			(island_removal_mode 0)
		)
		(polygon
			(pts
				(arc
					(start 270.397478 -208.632298)
					(mid 270.393758 -208.641278)
					(end 270.384778 -208.644998)
				)
				(arc
					(start 268.911578 -208.644998)
					(mid 268.902598 -208.641278)
					(end 268.898878 -208.632298)
				)
				(arc
					(start 268.898878 -208.13776)
					(mid 268.902598 -208.12878)
					(end 268.911578 -208.12506)
				)
				(arc
					(start 270.384778 -208.12506)
					(mid 270.393758 -208.12878)
					(end 270.397478 -208.13776)
				)
			)
		)
	)
	(zone
		(layer "In1.Cu")
		(hatch none 0.5)
		(connect_pads
			(clearance 0)
		)
		(min_thickness 0.25)
		(keepout
			(tracks not_allowed)
			(vias allowed)
			(pads allowed)
			(copperpour not_allowed)
			(footprints allowed)
		)
		(placement
			(enabled no)
			(sheetname "")
		)
		(fill
			(thermal_gap 0.5)
			(thermal_bridge_width 0.5)
			(island_removal_mode 0)
		)
		(polygon
			(pts
				(arc
					(start 413.998156 -392.30427)
					(mid 413.693356 -392.30427)
					(end 413.998156 -392.30427)
				)
			)
		)
	)
	(zone
		(layer "In1.Cu")
		(hatch none 0.5)
		(connect_pads
			(clearance 0)
		)
		(min_thickness 0.25)
		(keepout
			(tracks not_allowed)
			(vias allowed)
			(pads allowed)
			(copperpour not_allowed)
			(footprints allowed)
		)
		(placement
			(enabled no)
			(sheetname "")
		)
		(fill
			(thermal_gap 0.5)
			(thermal_bridge_width 0.5)
			(island_removal_mode 0)
		)
		(polygon
			(pts
				(arc
					(start 417.217352 -272.382234)
					(mid 417.213632 -272.391214)
					(end 417.204652 -272.394934)
				)
				(arc
					(start 415.731452 -272.394934)
					(mid 415.722472 -272.391214)
					(end 415.718752 -272.382234)
				)
				(arc
					(start 415.718752 -271.887696)
					(mid 415.722472 -271.878716)
					(end 415.731452 -271.874996)
				)
				(arc
					(start 417.204652 -271.874996)
					(mid 417.213632 -271.878716)
					(end 417.217352 -271.887696)
				)
			)
		)
	)
	(zone
		(layer "In1.Cu")
		(hatch none 0.5)
		(connect_pads
			(clearance 0)
		)
		(min_thickness 0.25)
		(keepout
			(tracks not_allowed)
			(vias allowed)
			(pads allowed)
			(copperpour not_allowed)
			(footprints allowed)
		)
		(placement
			(enabled no)
			(sheetname "")
		)
		(fill
			(thermal_gap 0.5)
			(thermal_bridge_width 0.5)
			(island_removal_mode 0)
		)
		(polygon
			(pts
				(arc
					(start 176.821338 -252.832362)
					(mid 176.817618 -252.841342)
					(end 176.808638 -252.845062)
				)
				(arc
					(start 175.335438 -252.845062)
					(mid 175.326458 -252.841342)
					(end 175.322738 -252.832362)
				)
				(arc
					(start 175.322738 -252.337824)
					(mid 175.326458 -252.328844)
					(end 175.335438 -252.325124)
				)
				(arc
					(start 176.808638 -252.325124)
					(mid 176.817618 -252.328844)
					(end 176.821338 -252.337824)
				)
			)
		)
	)
	(zone
		(layer "In1.Cu")
		(hatch none 0.5)
		(connect_pads
			(clearance 0)
		)
		(min_thickness 0.25)
		(keepout
			(tracks not_allowed)
			(vias allowed)
			(pads allowed)
			(copperpour not_allowed)
			(footprints allowed)
		)
		(placement
			(enabled no)
			(sheetname "")
		)
		(fill
			(thermal_gap 0.5)
			(thermal_bridge_width 0.5)
			(island_removal_mode 0)
		)
		(polygon
			(pts
				(arc
					(start 315.314584 5.633974)
					(mid 315.336902 5.687856)
					(end 315.390784 5.710174)
				)
				(arc
					(start 316.002924 5.710174)
					(mid 316.056806 5.687856)
					(end 316.079124 5.633974)
				)
				(arc
					(start 316.079124 4.536694)
					(mid 316.056806 4.482812)
					(end 316.002924 4.460494)
				)
				(arc
					(start 315.390784 4.460494)
					(mid 315.336902 4.482812)
					(end 315.314584 4.536694)
				)
			)
		)
	)
	(zone
		(layer "In1.Cu")
		(hatch none 0.5)
		(connect_pads
			(clearance 0)
		)
		(min_thickness 0.25)
		(keepout
			(tracks not_allowed)
			(vias allowed)
			(pads allowed)
			(copperpour not_allowed)
			(footprints allowed)
		)
		(placement
			(enabled no)
			(sheetname "")
		)
		(fill
			(thermal_gap 0.5)
			(thermal_bridge_width 0.5)
			(island_removal_mode 0)
		)
		(polygon
			(pts
				(arc
					(start 424.761406 -302.132238)
					(mid 424.757686 -302.141218)
					(end 424.748706 -302.144938)
				)
				(arc
					(start 423.275506 -302.144938)
					(mid 423.266526 -302.141218)
					(end 423.262806 -302.132238)
				)
				(arc
					(start 423.262806 -301.6377)
					(mid 423.266526 -301.62872)
					(end 423.275506 -301.625)
				)
				(arc
					(start 424.748706 -301.625)
					(mid 424.757686 -301.62872)
					(end 424.761406 -301.6377)
				)
			)
		)
	)
	(zone
		(layer "In1.Cu")
		(hatch none 0.5)
		(connect_pads
			(clearance 0)
		)
		(min_thickness 0.25)
		(keepout
			(tracks not_allowed)
			(vias allowed)
			(pads allowed)
			(copperpour not_allowed)
			(footprints allowed)
		)
		(placement
			(enabled no)
			(sheetname "")
		)
		(fill
			(thermal_gap 0.5)
			(thermal_bridge_width 0.5)
			(island_removal_mode 0)
		)
		(polygon
			(pts
				(arc
					(start 304.017426 -254.53213)
					(mid 304.013706 -254.54111)
					(end 304.004726 -254.54483)
				)
				(arc
					(start 302.531526 -254.54483)
					(mid 302.522546 -254.54111)
					(end 302.518826 -254.53213)
				)
				(arc
					(start 302.518826 -254.037592)
					(mid 302.522546 -254.028612)
					(end 302.531526 -254.024892)
				)
				(arc
					(start 304.004726 -254.024892)
					(mid 304.013706 -254.028612)
					(end 304.017426 -254.037592)
				)
			)
		)
	)
	(zone
		(layer "In1.Cu")
		(hatch none 0.5)
		(connect_pads
			(clearance 0)
		)
		(min_thickness 0.25)
		(keepout
			(tracks not_allowed)
			(vias allowed)
			(pads allowed)
			(copperpour not_allowed)
			(footprints allowed)
		)
		(placement
			(enabled no)
			(sheetname "")
		)
		(fill
			(thermal_gap 0.5)
			(thermal_bridge_width 0.5)
			(island_removal_mode 0)
		)
		(polygon
			(pts
				(arc
					(start 152.618694 -391.319258)
					(mid 152.745694 -391.446258)
					(end 152.872694 -391.319258)
				)
				(arc
					(start 152.872694 -391.243058)
					(mid 152.745694 -391.116058)
					(end 152.618694 -391.243058)
				)
			)
		)
	)
	(zone
		(layer "In1.Cu")
		(hatch none 0.5)
		(connect_pads
			(clearance 0)
		)
		(min_thickness 0.25)
		(keepout
			(tracks not_allowed)
			(vias allowed)
			(pads allowed)
			(copperpour not_allowed)
			(footprints allowed)
		)
		(placement
			(enabled no)
			(sheetname "")
		)
		(fill
			(thermal_gap 0.5)
			(thermal_bridge_width 0.5)
			(island_removal_mode 0)
		)
		(polygon
			(pts
				(arc
					(start 285.485332 -297.032172)
					(mid 285.481612 -297.041152)
					(end 285.472632 -297.044872)
				)
				(arc
					(start 283.999432 -297.044872)
					(mid 283.990452 -297.041152)
					(end 283.986732 -297.032172)
				)
				(arc
					(start 283.986732 -296.537634)
					(mid 283.990452 -296.528654)
					(end 283.999432 -296.524934)
				)
				(arc
					(start 285.472632 -296.524934)
					(mid 285.481612 -296.528654)
					(end 285.485332 -296.537634)
				)
			)
		)
	)
	(zone
		(layer "In1.Cu")
		(hatch none 0.5)
		(connect_pads
			(clearance 0)
		)
		(min_thickness 0.25)
		(keepout
			(tracks not_allowed)
			(vias allowed)
			(pads allowed)
			(copperpour not_allowed)
			(footprints allowed)
		)
		(placement
			(enabled no)
			(sheetname "")
		)
		(fill
			(thermal_gap 0.5)
			(thermal_bridge_width 0.5)
			(island_removal_mode 0)
		)
		(polygon
			(pts
				(arc
					(start 199.4535 -292.782498)
					(mid 199.44978 -292.791478)
					(end 199.4408 -292.795198)
				)
				(arc
					(start 197.9676 -292.795198)
					(mid 197.95862 -292.791478)
					(end 197.9549 -292.782498)
				)
				(arc
					(start 197.9549 -292.28796)
					(mid 197.95862 -292.27898)
					(end 197.9676 -292.27526)
				)
				(arc
					(start 199.4408 -292.27526)
					(mid 199.44978 -292.27898)
					(end 199.4535 -292.28796)
				)
			)
		)
	)
	(zone
		(layer "In1.Cu")
		(hatch none 0.5)
		(connect_pads
			(clearance 0)
		)
		(min_thickness 0.25)
		(keepout
			(tracks not_allowed)
			(vias allowed)
			(pads allowed)
			(copperpour not_allowed)
			(footprints allowed)
		)
		(placement
			(enabled no)
			(sheetname "")
		)
		(fill
			(thermal_gap 0.5)
			(thermal_bridge_width 0.5)
			(island_removal_mode 0)
		)
		(polygon
			(pts
				(arc
					(start 40.98925 -288.53257)
					(mid 40.98553 -288.54155)
					(end 40.97655 -288.54527)
				)
				(arc
					(start 39.50335 -288.54527)
					(mid 39.49437 -288.54155)
					(end 39.49065 -288.53257)
				)
				(arc
					(start 39.49065 -288.038032)
					(mid 39.49437 -288.029052)
					(end 39.50335 -288.025332)
				)
				(arc
					(start 40.97655 -288.025332)
					(mid 40.98553 -288.029052)
					(end 40.98925 -288.038032)
				)
			)
		)
	)
	(zone
		(layer "In1.Cu")
		(hatch none 0.5)
		(connect_pads
			(clearance 0)
		)
		(min_thickness 0.25)
		(keepout
			(tracks not_allowed)
			(vias allowed)
			(pads allowed)
			(copperpour not_allowed)
			(footprints allowed)
		)
		(placement
			(enabled no)
			(sheetname "")
		)
		(fill
			(thermal_gap 0.5)
			(thermal_bridge_width 0.5)
			(island_removal_mode 0)
		)
		(polygon
			(pts
				(arc
					(start 52.633372 -297.032426)
					(mid 52.629652 -297.041406)
					(end 52.620672 -297.045126)
				)
				(arc
					(start 51.147472 -297.045126)
					(mid 51.138492 -297.041406)
					(end 51.134772 -297.032426)
				)
				(arc
					(start 51.134772 -296.537888)
					(mid 51.138492 -296.528908)
					(end 51.147472 -296.525188)
				)
				(arc
					(start 52.620672 -296.525188)
					(mid 52.629652 -296.528908)
					(end 52.633372 -296.537888)
				)
			)
		)
	)
	(zone
		(layer "In1.Cu")
		(hatch none 0.5)
		(connect_pads
			(clearance 0)
		)
		(min_thickness 0.25)
		(keepout
			(tracks not_allowed)
			(vias allowed)
			(pads allowed)
			(copperpour not_allowed)
			(footprints allowed)
		)
		(placement
			(enabled no)
			(sheetname "")
		)
		(fill
			(thermal_gap 0.5)
			(thermal_bridge_width 0.5)
			(island_removal_mode 0)
		)
		(polygon
			(pts
				(arc
					(start 281.385264 -291.932106)
					(mid 281.381544 -291.941086)
					(end 281.372564 -291.944806)
				)
				(arc
					(start 279.899364 -291.944806)
					(mid 279.890384 -291.941086)
					(end 279.886664 -291.932106)
				)
				(arc
					(start 279.886664 -291.437568)
					(mid 279.890384 -291.428588)
					(end 279.899364 -291.424868)
				)
				(arc
					(start 281.372564 -291.424868)
					(mid 281.381544 -291.428588)
					(end 281.385264 -291.437568)
				)
			)
		)
	)
	(zone
		(layer "In1.Cu")
		(hatch none 0.5)
		(connect_pads
			(clearance 0)
		)
		(min_thickness 0.25)
		(keepout
			(tracks not_allowed)
			(vias allowed)
			(pads allowed)
			(copperpour not_allowed)
			(footprints allowed)
		)
		(placement
			(enabled no)
			(sheetname "")
		)
		(fill
			(thermal_gap 0.5)
			(thermal_bridge_width 0.5)
			(island_removal_mode 0)
		)
		(polygon
			(pts
				(arc
					(start 353.188524 -394.385292)
					(mid 352.807524 -394.385292)
					(end 353.188524 -394.385292)
				)
			)
		)
	)
	(zone
		(layer "In1.Cu")
		(hatch none 0.5)
		(connect_pads
			(clearance 0)
		)
		(min_thickness 0.25)
		(keepout
			(tracks not_allowed)
			(vias allowed)
			(pads allowed)
			(copperpour not_allowed)
			(footprints allowed)
		)
		(placement
			(enabled no)
			(sheetname "")
		)
		(fill
			(thermal_gap 0.5)
			(thermal_bridge_width 0.5)
			(island_removal_mode 0)
		)
		(polygon
			(pts
				(arc
					(start 293.029386 -210.33232)
					(mid 293.025666 -210.3413)
					(end 293.016686 -210.34502)
				)
				(arc
					(start 291.543486 -210.34502)
					(mid 291.534506 -210.3413)
					(end 291.530786 -210.33232)
				)
				(arc
					(start 291.530786 -209.837782)
					(mid 291.534506 -209.828802)
					(end 291.543486 -209.825082)
				)
				(arc
					(start 293.016686 -209.825082)
					(mid 293.025666 -209.828802)
					(end 293.029386 -209.837782)
				)
			)
		)
	)
	(zone
		(layer "In1.Cu")
		(hatch none 0.5)
		(connect_pads
			(clearance 0)
		)
		(min_thickness 0.25)
		(keepout
			(tracks not_allowed)
			(vias allowed)
			(pads allowed)
			(copperpour not_allowed)
			(footprints allowed)
		)
		(placement
			(enabled no)
			(sheetname "")
		)
		(fill
			(thermal_gap 0.5)
			(thermal_bridge_width 0.5)
			(island_removal_mode 0)
		)
		(polygon
			(pts
				(arc
					(start 162.218624 -383.440686)
					(mid 162.345624 -383.567686)
					(end 162.472624 -383.440686)
				)
				(arc
					(start 162.472624 -383.364486)
					(mid 162.345624 -383.237486)
					(end 162.218624 -383.364486)
				)
			)
		)
	)
	(zone
		(layer "In1.Cu")
		(hatch none 0.5)
		(connect_pads
			(clearance 0)
		)
		(min_thickness 0.25)
		(keepout
			(tracks not_allowed)
			(vias allowed)
			(pads allowed)
			(copperpour not_allowed)
			(footprints allowed)
		)
		(placement
			(enabled no)
			(sheetname "")
		)
		(fill
			(thermal_gap 0.5)
			(thermal_bridge_width 0.5)
			(island_removal_mode 0)
		)
		(polygon
			(pts
				(arc
					(start 52.633372 -210.332574)
					(mid 52.629652 -210.341554)
					(end 52.620672 -210.345274)
				)
				(arc
					(start 51.147472 -210.345274)
					(mid 51.138492 -210.341554)
					(end 51.134772 -210.332574)
				)
				(arc
					(start 51.134772 -209.838036)
					(mid 51.138492 -209.829056)
					(end 51.147472 -209.825336)
				)
				(arc
					(start 52.620672 -209.825336)
					(mid 52.629652 -209.829056)
					(end 52.633372 -209.838036)
				)
			)
		)
	)
	(zone
		(layer "In1.Cu")
		(hatch none 0.5)
		(connect_pads
			(clearance 0)
		)
		(min_thickness 0.25)
		(keepout
			(tracks not_allowed)
			(vias allowed)
			(pads allowed)
			(copperpour not_allowed)
			(footprints allowed)
		)
		(placement
			(enabled no)
			(sheetname "")
		)
		(fill
			(thermal_gap 0.5)
			(thermal_bridge_width 0.5)
			(island_removal_mode 0)
		)
		(polygon
			(pts
				(arc
					(start 281.385264 -302.982122)
					(mid 281.381544 -302.991102)
					(end 281.372564 -302.994822)
				)
				(arc
					(start 279.899364 -302.994822)
					(mid 279.890384 -302.991102)
					(end 279.886664 -302.982122)
				)
				(arc
					(start 279.886664 -302.487584)
					(mid 279.890384 -302.478604)
					(end 279.899364 -302.474884)
				)
				(arc
					(start 281.372564 -302.474884)
					(mid 281.381544 -302.478604)
					(end 281.385264 -302.487584)
				)
			)
		)
	)
	(zone
		(layer "In1.Cu")
		(hatch none 0.5)
		(connect_pads
			(clearance 0)
		)
		(min_thickness 0.25)
		(keepout
			(tracks not_allowed)
			(vias allowed)
			(pads allowed)
			(copperpour not_allowed)
			(footprints allowed)
		)
		(placement
			(enabled no)
			(sheetname "")
		)
		(fill
			(thermal_gap 0.5)
			(thermal_bridge_width 0.5)
			(island_removal_mode 0)
		)
		(polygon
			(pts
				(arc
					(start 413.117284 -209.482182)
					(mid 413.113564 -209.491162)
					(end 413.104584 -209.494882)
				)
				(arc
					(start 411.631384 -209.494882)
					(mid 411.622404 -209.491162)
					(end 411.618684 -209.482182)
				)
				(arc
					(start 411.618684 -208.987644)
					(mid 411.622404 -208.978664)
					(end 411.631384 -208.974944)
				)
				(arc
					(start 413.104584 -208.974944)
					(mid 413.113564 -208.978664)
					(end 413.117284 -208.987644)
				)
			)
		)
	)
	(zone
		(layer "In1.Cu")
		(hatch none 0.5)
		(connect_pads
			(clearance 0)
		)
		(min_thickness 0.25)
		(keepout
			(tracks not_allowed)
			(vias allowed)
			(pads allowed)
			(copperpour not_allowed)
			(footprints allowed)
		)
		(placement
			(enabled no)
			(sheetname "")
		)
		(fill
			(thermal_gap 0.5)
			(thermal_bridge_width 0.5)
			(island_removal_mode 0)
		)
		(polygon
			(pts
				(arc
					(start 172.72127 -263.882378)
					(mid 172.71755 -263.891358)
					(end 172.70857 -263.895078)
				)
				(arc
					(start 171.23537 -263.895078)
					(mid 171.22639 -263.891358)
					(end 171.22267 -263.882378)
				)
				(arc
					(start 171.22267 -263.38784)
					(mid 171.22639 -263.37886)
					(end 171.23537 -263.37514)
				)
				(arc
					(start 172.70857 -263.37514)
					(mid 172.71755 -263.37886)
					(end 172.72127 -263.38784)
				)
			)
		)
	)
	(zone
		(layer "In1.Cu")
		(hatch none 0.5)
		(connect_pads
			(clearance 0)
		)
		(min_thickness 0.25)
		(keepout
			(tracks not_allowed)
			(vias allowed)
			(pads allowed)
			(copperpour not_allowed)
			(footprints allowed)
		)
		(placement
			(enabled no)
			(sheetname "")
		)
		(fill
			(thermal_gap 0.5)
			(thermal_bridge_width 0.5)
			(island_removal_mode 0)
		)
		(polygon
			(pts
				(arc
					(start 432.30546 -212.882226)
					(mid 432.30174 -212.891206)
					(end 432.29276 -212.894926)
				)
				(arc
					(start 430.81956 -212.894926)
					(mid 430.81058 -212.891206)
					(end 430.80686 -212.882226)
				)
				(arc
					(start 430.80686 -212.387688)
					(mid 430.81058 -212.378708)
					(end 430.81956 -212.374988)
				)
				(arc
					(start 432.29276 -212.374988)
					(mid 432.30174 -212.378708)
					(end 432.30546 -212.387688)
				)
			)
		)
	)
	(zone
		(layer "In1.Cu")
		(hatch none 0.5)
		(connect_pads
			(clearance 0)
		)
		(min_thickness 0.25)
		(keepout
			(tracks not_allowed)
			(vias allowed)
			(pads allowed)
			(copperpour not_allowed)
			(footprints allowed)
		)
		(placement
			(enabled no)
			(sheetname "")
		)
		(fill
			(thermal_gap 0.5)
			(thermal_bridge_width 0.5)
			(island_removal_mode 0)
		)
		(polygon
			(pts
				(arc
					(start 199.4535 -276.632416)
					(mid 199.44978 -276.641396)
					(end 199.4408 -276.645116)
				)
				(arc
					(start 197.9676 -276.645116)
					(mid 197.95862 -276.641396)
					(end 197.9549 -276.632416)
				)
				(arc
					(start 197.9549 -276.137878)
					(mid 197.95862 -276.128898)
					(end 197.9676 -276.125178)
				)
				(arc
					(start 199.4408 -276.125178)
					(mid 199.44978 -276.128898)
					(end 199.4535 -276.137878)
				)
			)
		)
	)
	(zone
		(layer "In1.Cu")
		(hatch none 0.5)
		(connect_pads
			(clearance 0)
		)
		(min_thickness 0.25)
		(keepout
			(tracks not_allowed)
			(vias allowed)
			(pads allowed)
			(copperpour not_allowed)
			(footprints allowed)
		)
		(placement
			(enabled no)
			(sheetname "")
		)
		(fill
			(thermal_gap 0.5)
			(thermal_bridge_width 0.5)
			(island_removal_mode 0)
		)
		(polygon
			(pts
				(arc
					(start 32.697928 -423.27195)
					(mid 32.712807 -423.236029)
					(end 32.748728 -423.22115)
				)
				(arc
					(start 33.256728 -423.22115)
					(mid 33.292649 -423.236029)
					(end 33.307528 -423.27195)
				)
				(arc
					(start 33.307528 -423.7482)
					(mid 33.292649 -423.784121)
					(end 33.256728 -423.799)
				)
				(arc
					(start 32.748728 -423.799)
					(mid 32.712807 -423.784121)
					(end 32.697928 -423.7482)
				)
			)
		)
	)
	(zone
		(layer "In1.Cu")
		(hatch none 0.5)
		(connect_pads
			(clearance 0)
		)
		(min_thickness 0.25)
		(keepout
			(tracks not_allowed)
			(vias allowed)
			(pads allowed)
			(copperpour not_allowed)
			(footprints allowed)
		)
		(placement
			(enabled no)
			(sheetname "")
		)
		(fill
			(thermal_gap 0.5)
			(thermal_bridge_width 0.5)
			(island_removal_mode 0)
		)
		(polygon
			(pts
				(arc
					(start 33.445196 -198.43242)
					(mid 33.441476 -198.4414)
					(end 33.432496 -198.44512)
				)
				(arc
					(start 31.959296 -198.44512)
					(mid 31.950316 -198.4414)
					(end 31.946596 -198.43242)
				)
				(arc
					(start 31.946596 -197.937882)
					(mid 31.950316 -197.928902)
					(end 31.959296 -197.925182)
				)
				(arc
					(start 33.432496 -197.925182)
					(mid 33.441476 -197.928902)
					(end 33.445196 -197.937882)
				)
			)
		)
	)
	(zone
		(layer "In1.Cu")
		(hatch none 0.5)
		(connect_pads
			(clearance 0)
		)
		(min_thickness 0.25)
		(keepout
			(tracks not_allowed)
			(vias allowed)
			(pads allowed)
			(copperpour not_allowed)
			(footprints allowed)
		)
		(placement
			(enabled no)
			(sheetname "")
		)
		(fill
			(thermal_gap 0.5)
			(thermal_bridge_width 0.5)
			(island_removal_mode 0)
		)
		(polygon
			(pts
				(arc
					(start 296.473372 -299.582332)
					(mid 296.469652 -299.591312)
					(end 296.460672 -299.595032)
				)
				(arc
					(start 294.987472 -299.595032)
					(mid 294.978492 -299.591312)
					(end 294.974772 -299.582332)
				)
				(arc
					(start 294.974772 -299.087794)
					(mid 294.978492 -299.078814)
					(end 294.987472 -299.075094)
				)
				(arc
					(start 296.460672 -299.075094)
					(mid 296.469652 -299.078814)
					(end 296.473372 -299.087794)
				)
			)
		)
	)
	(zone
		(layer "In1.Cu")
		(hatch none 0.5)
		(connect_pads
			(clearance 0)
		)
		(min_thickness 0.25)
		(keepout
			(tracks not_allowed)
			(vias allowed)
			(pads allowed)
			(copperpour not_allowed)
			(footprints allowed)
		)
		(placement
			(enabled no)
			(sheetname "")
		)
		(fill
			(thermal_gap 0.5)
			(thermal_bridge_width 0.5)
			(island_removal_mode 0)
		)
		(polygon
			(pts
				(arc
					(start 37.667692 -16.443198)
					(mid 37.69001 -16.49708)
					(end 37.743892 -16.519398)
				)
				(arc
					(start 37.939472 -16.519398)
					(mid 37.961348 -16.516266)
					(end 37.981382 -16.506952)
				)
				(arc
					(start 38.275006 -16.31442)
					(mid 38.316662 -16.302018)
					(end 38.358318 -16.31442)
				)
				(arc
					(start 38.653212 -16.506952)
					(mid 38.673136 -16.516188)
					(end 38.694868 -16.519398)
				)
				(arc
					(start 38.889432 -16.519398)
					(mid 38.943314 -16.49708)
					(end 38.965632 -16.443198)
				)
				(arc
					(start 38.965632 -15.757398)
					(mid 38.943314 -15.703516)
					(end 38.889432 -15.681198)
				)
				(arc
					(start 38.694868 -15.681198)
					(mid 38.673124 -15.684366)
					(end 38.653212 -15.693644)
				)
				(arc
					(start 38.357048 -15.88643)
					(mid 38.315364 -15.898652)
					(end 38.273736 -15.886176)
				)
				(arc
					(start 37.980112 -15.693644)
					(mid 37.960188 -15.684408)
					(end 37.938456 -15.681198)
				)
				(arc
					(start 37.743892 -15.681198)
					(mid 37.69001 -15.703516)
					(end 37.667692 -15.757398)
				)
			)
		)
	)
	(zone
		(layer "In1.Cu")
		(hatch none 0.5)
		(connect_pads
			(clearance 0)
		)
		(min_thickness 0.25)
		(keepout
			(tracks not_allowed)
			(vias allowed)
			(pads allowed)
			(copperpour not_allowed)
			(footprints allowed)
		)
		(placement
			(enabled no)
			(sheetname "")
		)
		(fill
			(thermal_gap 0.5)
			(thermal_bridge_width 0.5)
			(island_removal_mode 0)
		)
		(polygon
			(pts
				(arc
					(start 318.590676 -399.701258)
					(mid 318.717676 -399.828258)
					(end 318.844676 -399.701258)
				)
				(arc
					(start 318.844676 -399.625058)
					(mid 318.717676 -399.498058)
					(end 318.590676 -399.625058)
				)
			)
		)
	)
	(zone
		(layer "In1.Cu")
		(hatch none 0.5)
		(connect_pads
			(clearance 0)
		)
		(min_thickness 0.25)
		(keepout
			(tracks not_allowed)
			(vias allowed)
			(pads allowed)
			(copperpour not_allowed)
			(footprints allowed)
		)
		(placement
			(enabled no)
			(sheetname "")
		)
		(fill
			(thermal_gap 0.5)
			(thermal_bridge_width 0.5)
			(island_removal_mode 0)
		)
		(polygon
			(pts
				(arc
					(start 184.365392 -261.332472)
					(mid 184.361672 -261.341452)
					(end 184.352692 -261.345172)
				)
				(arc
					(start 182.879492 -261.345172)
					(mid 182.870512 -261.341452)
					(end 182.866792 -261.332472)
				)
				(arc
					(start 182.866792 -260.837934)
					(mid 182.870512 -260.828954)
					(end 182.879492 -260.825234)
				)
				(arc
					(start 184.352692 -260.825234)
					(mid 184.361672 -260.828954)
					(end 184.365392 -260.837934)
				)
			)
		)
	)
	(zone
		(layer "In1.Cu")
		(hatch none 0.5)
		(connect_pads
			(clearance 0)
		)
		(min_thickness 0.25)
		(keepout
			(tracks not_allowed)
			(vias allowed)
			(pads allowed)
			(copperpour not_allowed)
			(footprints allowed)
		)
		(placement
			(enabled no)
			(sheetname "")
		)
		(fill
			(thermal_gap 0.5)
			(thermal_bridge_width 0.5)
			(island_removal_mode 0)
		)
		(polygon
			(pts
				(arc
					(start 339.697822 -392.30427)
					(mid 339.393022 -392.30427)
					(end 339.697822 -392.30427)
				)
			)
		)
	)
	(zone
		(layer "In1.Cu")
		(hatch none 0.5)
		(connect_pads
			(clearance 0)
		)
		(min_thickness 0.25)
		(keepout
			(tracks not_allowed)
			(vias allowed)
			(pads allowed)
			(copperpour not_allowed)
			(footprints allowed)
		)
		(placement
			(enabled no)
			(sheetname "")
		)
		(fill
			(thermal_gap 0.5)
			(thermal_bridge_width 0.5)
			(island_removal_mode 0)
		)
		(polygon
			(pts
				(arc
					(start 420.661338 -310.632094)
					(mid 420.657618 -310.641074)
					(end 420.648638 -310.644794)
				)
				(arc
					(start 419.175438 -310.644794)
					(mid 419.166458 -310.641074)
					(end 419.162738 -310.632094)
				)
				(arc
					(start 419.162738 -310.137556)
					(mid 419.166458 -310.128576)
					(end 419.175438 -310.124856)
				)
				(arc
					(start 420.648638 -310.124856)
					(mid 420.657618 -310.128576)
					(end 420.661338 -310.137556)
				)
			)
		)
	)
	(zone
		(layer "In1.Cu")
		(hatch none 0.5)
		(connect_pads
			(clearance 0)
		)
		(min_thickness 0.25)
		(keepout
			(tracks not_allowed)
			(vias allowed)
			(pads allowed)
			(copperpour not_allowed)
			(footprints allowed)
		)
		(placement
			(enabled no)
			(sheetname "")
		)
		(fill
			(thermal_gap 0.5)
			(thermal_bridge_width 0.5)
			(island_removal_mode 0)
		)
		(polygon
			(pts
				(arc
					(start 180.265324 -209.482436)
					(mid 180.261604 -209.491416)
					(end 180.252624 -209.495136)
				)
				(arc
					(start 178.779424 -209.495136)
					(mid 178.770444 -209.491416)
					(end 178.766724 -209.482436)
				)
				(arc
					(start 178.766724 -208.987898)
					(mid 178.770444 -208.978918)
					(end 178.779424 -208.975198)
				)
				(arc
					(start 180.252624 -208.975198)
					(mid 180.261604 -208.978918)
					(end 180.265324 -208.987898)
				)
			)
		)
	)
	(zone
		(layer "In1.Cu")
		(hatch none 0.5)
		(connect_pads
			(clearance 0)
		)
		(min_thickness 0.25)
		(keepout
			(tracks not_allowed)
			(vias allowed)
			(pads allowed)
			(copperpour not_allowed)
			(footprints allowed)
		)
		(placement
			(enabled no)
			(sheetname "")
		)
		(fill
			(thermal_gap 0.5)
			(thermal_bridge_width 0.5)
			(island_removal_mode 0)
		)
		(polygon
			(pts
				(arc
					(start 404.289006 -393.69238)
					(mid 403.908006 -393.69238)
					(end 404.289006 -393.69238)
				)
			)
		)
	)
	(zone
		(layer "In1.Cu")
		(hatch none 0.5)
		(connect_pads
			(clearance 0)
		)
		(min_thickness 0.25)
		(keepout
			(tracks not_allowed)
			(vias allowed)
			(pads allowed)
			(copperpour not_allowed)
			(footprints allowed)
		)
		(placement
			(enabled no)
			(sheetname "")
		)
		(fill
			(thermal_gap 0.5)
			(thermal_bridge_width 0.5)
			(island_removal_mode 0)
		)
		(polygon
			(pts
				(arc
					(start 304.017426 -297.88231)
					(mid 304.013706 -297.89129)
					(end 304.004726 -297.89501)
				)
				(arc
					(start 302.531526 -297.89501)
					(mid 302.522546 -297.89129)
					(end 302.518826 -297.88231)
				)
				(arc
					(start 302.518826 -297.387772)
					(mid 302.522546 -297.378792)
					(end 302.531526 -297.375072)
				)
				(arc
					(start 304.004726 -297.375072)
					(mid 304.013706 -297.378792)
					(end 304.017426 -297.387772)
				)
			)
		)
	)
	(zone
		(layer "In1.Cu")
		(hatch none 0.5)
		(connect_pads
			(clearance 0)
		)
		(min_thickness 0.25)
		(keepout
			(tracks not_allowed)
			(vias allowed)
			(pads allowed)
			(copperpour not_allowed)
			(footprints allowed)
		)
		(placement
			(enabled no)
			(sheetname "")
		)
		(fill
			(thermal_gap 0.5)
			(thermal_bridge_width 0.5)
			(island_removal_mode 0)
		)
		(polygon
			(pts
				(arc
					(start 300.57344 -300.432216)
					(mid 300.56972 -300.441196)
					(end 300.56074 -300.444916)
				)
				(arc
					(start 299.08754 -300.444916)
					(mid 299.07856 -300.441196)
					(end 299.07484 -300.432216)
				)
				(arc
					(start 299.07484 -299.937678)
					(mid 299.07856 -299.928698)
					(end 299.08754 -299.924978)
				)
				(arc
					(start 300.56074 -299.924978)
					(mid 300.56972 -299.928698)
					(end 300.57344 -299.937678)
				)
			)
		)
	)
	(zone
		(layer "In1.Cu")
		(hatch none 0.5)
		(connect_pads
			(clearance 0)
		)
		(min_thickness 0.25)
		(keepout
			(tracks not_allowed)
			(vias allowed)
			(pads allowed)
			(copperpour not_allowed)
			(footprints allowed)
		)
		(placement
			(enabled no)
			(sheetname "")
		)
		(fill
			(thermal_gap 0.5)
			(thermal_bridge_width 0.5)
			(island_removal_mode 0)
		)
		(polygon
			(pts
				(arc
					(start 435.749446 -237.532164)
					(mid 435.745726 -237.541144)
					(end 435.736746 -237.544864)
				)
				(arc
					(start 434.263546 -237.544864)
					(mid 434.254566 -237.541144)
					(end 434.250846 -237.532164)
				)
				(arc
					(start 434.250846 -237.037626)
					(mid 434.254566 -237.028646)
					(end 434.263546 -237.024926)
				)
				(arc
					(start 435.736746 -237.024926)
					(mid 435.745726 -237.028646)
					(end 435.749446 -237.037626)
				)
			)
		)
	)
	(zone
		(layer "In1.Cu")
		(hatch none 0.5)
		(connect_pads
			(clearance 0)
		)
		(min_thickness 0.25)
		(keepout
			(tracks not_allowed)
			(vias allowed)
			(pads allowed)
			(copperpour not_allowed)
			(footprints allowed)
		)
		(placement
			(enabled no)
			(sheetname "")
		)
		(fill
			(thermal_gap 0.5)
			(thermal_bridge_width 0.5)
			(island_removal_mode 0)
		)
		(polygon
			(pts
				(arc
					(start 165.198044 -383.92227)
					(mid 164.893244 -383.92227)
					(end 165.198044 -383.92227)
				)
			)
		)
	)
	(zone
		(layer "In1.Cu")
		(hatch none 0.5)
		(connect_pads
			(clearance 0)
		)
		(min_thickness 0.25)
		(keepout
			(tracks not_allowed)
			(vias allowed)
			(pads allowed)
			(copperpour not_allowed)
			(footprints allowed)
		)
		(placement
			(enabled no)
			(sheetname "")
		)
		(fill
			(thermal_gap 0.5)
			(thermal_bridge_width 0.5)
			(island_removal_mode 0)
		)
		(polygon
			(pts
				(arc
					(start 22.45741 -317.432436)
					(mid 22.45369 -317.441416)
					(end 22.44471 -317.445136)
				)
				(arc
					(start 20.97151 -317.445136)
					(mid 20.96253 -317.441416)
					(end 20.95881 -317.432436)
				)
				(arc
					(start 20.95881 -316.937898)
					(mid 20.96253 -316.928918)
					(end 20.97151 -316.925198)
				)
				(arc
					(start 22.44471 -316.925198)
					(mid 22.45369 -316.928918)
					(end 22.45741 -316.937898)
				)
			)
		)
	)
	(zone
		(layer "In1.Cu")
		(hatch none 0.5)
		(connect_pads
			(clearance 0)
		)
		(min_thickness 0.25)
		(keepout
			(tracks not_allowed)
			(vias allowed)
			(pads allowed)
			(copperpour not_allowed)
			(footprints allowed)
		)
		(placement
			(enabled no)
			(sheetname "")
		)
		(fill
			(thermal_gap 0.5)
			(thermal_bridge_width 0.5)
			(island_removal_mode 0)
		)
		(polygon
			(pts
				(arc
					(start 48.533304 -314.88253)
					(mid 48.529584 -314.89151)
					(end 48.520604 -314.89523)
				)
				(arc
					(start 47.047404 -314.89523)
					(mid 47.038424 -314.89151)
					(end 47.034704 -314.88253)
				)
				(arc
					(start 47.034704 -314.387992)
					(mid 47.038424 -314.379012)
					(end 47.047404 -314.375292)
				)
				(arc
					(start 48.520604 -314.375292)
					(mid 48.529584 -314.379012)
					(end 48.533304 -314.387992)
				)
			)
		)
	)
	(zone
		(layer "In1.Cu")
		(hatch none 0.5)
		(connect_pads
			(clearance 0)
		)
		(min_thickness 0.25)
		(keepout
			(tracks not_allowed)
			(vias allowed)
			(pads allowed)
			(copperpour not_allowed)
			(footprints allowed)
		)
		(placement
			(enabled no)
			(sheetname "")
		)
		(fill
			(thermal_gap 0.5)
			(thermal_bridge_width 0.5)
			(island_removal_mode 0)
		)
		(polygon
			(pts
				(arc
					(start 40.98925 -204.38237)
					(mid 40.98553 -204.39135)
					(end 40.97655 -204.39507)
				)
				(arc
					(start 39.50335 -204.39507)
					(mid 39.49437 -204.39135)
					(end 39.49065 -204.38237)
				)
				(arc
					(start 39.49065 -203.887832)
					(mid 39.49437 -203.878852)
					(end 39.50335 -203.875132)
				)
				(arc
					(start 40.97655 -203.875132)
					(mid 40.98553 -203.878852)
					(end 40.98925 -203.887832)
				)
			)
		)
	)
	(zone
		(layer "In1.Cu")
		(hatch none 0.5)
		(connect_pads
			(clearance 0)
		)
		(min_thickness 0.25)
		(keepout
			(tracks not_allowed)
			(vias allowed)
			(pads allowed)
			(copperpour not_allowed)
			(footprints allowed)
		)
		(placement
			(enabled no)
			(sheetname "")
		)
		(fill
			(thermal_gap 0.5)
			(thermal_bridge_width 0.5)
			(island_removal_mode 0)
		)
		(polygon
			(pts
				(arc
					(start 308.117494 -244.332252)
					(mid 308.113774 -244.341232)
					(end 308.104794 -244.344952)
				)
				(arc
					(start 306.631594 -244.344952)
					(mid 306.622614 -244.341232)
					(end 306.618894 -244.332252)
				)
				(arc
					(start 306.618894 -243.837714)
					(mid 306.622614 -243.828734)
					(end 306.631594 -243.825014)
				)
				(arc
					(start 308.104794 -243.825014)
					(mid 308.113774 -243.828734)
					(end 308.117494 -243.837714)
				)
			)
		)
	)
	(zone
		(layer "In1.Cu")
		(hatch none 0.5)
		(connect_pads
			(clearance 0)
		)
		(min_thickness 0.25)
		(keepout
			(tracks not_allowed)
			(vias allowed)
			(pads allowed)
			(copperpour not_allowed)
			(footprints allowed)
		)
		(placement
			(enabled no)
			(sheetname "")
		)
		(fill
			(thermal_gap 0.5)
			(thermal_bridge_width 0.5)
			(island_removal_mode 0)
		)
		(polygon
			(pts
				(arc
					(start 206.5782 -212.635338)
					(mid 205.9178 -212.635338)
					(end 206.5782 -212.635338)
				)
			)
		)
	)
	(zone
		(layer "In1.Cu")
		(hatch none 0.5)
		(connect_pads
			(clearance 0)
		)
		(min_thickness 0.25)
		(keepout
			(tracks not_allowed)
			(vias allowed)
			(pads allowed)
			(copperpour not_allowed)
			(footprints allowed)
		)
		(placement
			(enabled no)
			(sheetname "")
		)
		(fill
			(thermal_gap 0.5)
			(thermal_bridge_width 0.5)
			(island_removal_mode 0)
		)
		(polygon
			(pts
				(arc
					(start 25.901396 -221.382336)
					(mid 25.897676 -221.391316)
					(end 25.888696 -221.395036)
				)
				(arc
					(start 24.415496 -221.395036)
					(mid 24.406516 -221.391316)
					(end 24.402796 -221.382336)
				)
				(arc
					(start 24.402796 -220.887798)
					(mid 24.406516 -220.878818)
					(end 24.415496 -220.875098)
				)
				(arc
					(start 25.888696 -220.875098)
					(mid 25.897676 -220.878818)
					(end 25.901396 -220.887798)
				)
			)
		)
	)
	(zone
		(layer "In1.Cu")
		(hatch none 0.5)
		(connect_pads
			(clearance 0)
		)
		(min_thickness 0.25)
		(keepout
			(tracks not_allowed)
			(vias allowed)
			(pads allowed)
			(copperpour not_allowed)
			(footprints allowed)
		)
		(placement
			(enabled no)
			(sheetname "")
		)
		(fill
			(thermal_gap 0.5)
			(thermal_bridge_width 0.5)
			(island_removal_mode 0)
		)
		(polygon
			(pts
				(arc
					(start 447.393568 -272.382234)
					(mid 447.389848 -272.391214)
					(end 447.380868 -272.394934)
				)
				(arc
					(start 445.907668 -272.394934)
					(mid 445.898688 -272.391214)
					(end 445.894968 -272.382234)
				)
				(arc
					(start 445.894968 -271.887696)
					(mid 445.898688 -271.878716)
					(end 445.907668 -271.874996)
				)
				(arc
					(start 447.380868 -271.874996)
					(mid 447.389848 -271.878716)
					(end 447.393568 -271.887696)
				)
			)
		)
	)
	(zone
		(layer "In1.Cu")
		(hatch none 0.5)
		(connect_pads
			(clearance 0)
		)
		(min_thickness 0.25)
		(keepout
			(tracks not_allowed)
			(vias allowed)
			(pads allowed)
			(copperpour not_allowed)
			(footprints allowed)
		)
		(placement
			(enabled no)
			(sheetname "")
		)
		(fill
			(thermal_gap 0.5)
			(thermal_bridge_width 0.5)
			(island_removal_mode 0)
		)
		(polygon
			(pts
				(arc
					(start 33.445196 -224.78238)
					(mid 33.441476 -224.79136)
					(end 33.432496 -224.79508)
				)
				(arc
					(start 31.959296 -224.79508)
					(mid 31.950316 -224.79136)
					(end 31.946596 -224.78238)
				)
				(arc
					(start 31.946596 -224.287842)
					(mid 31.950316 -224.278862)
					(end 31.959296 -224.275142)
				)
				(arc
					(start 33.432496 -224.275142)
					(mid 33.441476 -224.278862)
					(end 33.445196 -224.287842)
				)
			)
		)
	)
	(zone
		(layer "In1.Cu")
		(hatch none 0.5)
		(connect_pads
			(clearance 0)
		)
		(min_thickness 0.25)
		(keepout
			(tracks not_allowed)
			(vias allowed)
			(pads allowed)
			(copperpour not_allowed)
			(footprints allowed)
		)
		(placement
			(enabled no)
			(sheetname "")
		)
		(fill
			(thermal_gap 0.5)
			(thermal_bridge_width 0.5)
			(island_removal_mode 0)
		)
		(polygon
			(pts
				(arc
					(start 450.8373 -245.182136)
					(mid 450.83358 -245.191116)
					(end 450.8246 -245.194836)
				)
				(arc
					(start 449.3514 -245.194836)
					(mid 449.34242 -245.191116)
					(end 449.3387 -245.182136)
				)
				(arc
					(start 449.3387 -244.687598)
					(mid 449.34242 -244.678618)
					(end 449.3514 -244.674898)
				)
				(arc
					(start 450.8246 -244.674898)
					(mid 450.83358 -244.678618)
					(end 450.8373 -244.687598)
				)
			)
		)
	)
	(zone
		(layer "In1.Cu")
		(hatch none 0.5)
		(connect_pads
			(clearance 0)
		)
		(min_thickness 0.25)
		(keepout
			(tracks not_allowed)
			(vias allowed)
			(pads allowed)
			(copperpour not_allowed)
			(footprints allowed)
		)
		(placement
			(enabled no)
			(sheetname "")
		)
		(fill
			(thermal_gap 0.5)
			(thermal_bridge_width 0.5)
			(island_removal_mode 0)
		)
		(polygon
			(pts
				(arc
					(start 454.937368 -217.982292)
					(mid 454.933648 -217.991272)
					(end 454.924668 -217.994992)
				)
				(arc
					(start 453.451468 -217.994992)
					(mid 453.442488 -217.991272)
					(end 453.438768 -217.982292)
				)
				(arc
					(start 453.438768 -217.487754)
					(mid 453.442488 -217.478774)
					(end 453.451468 -217.475054)
				)
				(arc
					(start 454.924668 -217.475054)
					(mid 454.933648 -217.478774)
					(end 454.937368 -217.487754)
				)
			)
		)
	)
	(zone
		(layer "In1.Cu")
		(hatch none 0.5)
		(connect_pads
			(clearance 0)
		)
		(min_thickness 0.25)
		(keepout
			(tracks not_allowed)
			(vias allowed)
			(pads allowed)
			(copperpour not_allowed)
			(footprints allowed)
		)
		(placement
			(enabled no)
			(sheetname "")
		)
		(fill
			(thermal_gap 0.5)
			(thermal_bridge_width 0.5)
			(island_removal_mode 0)
		)
		(polygon
			(pts
				(arc
					(start 413.117284 -211.182204)
					(mid 413.113564 -211.191184)
					(end 413.104584 -211.194904)
				)
				(arc
					(start 411.631384 -211.194904)
					(mid 411.622404 -211.191184)
					(end 411.618684 -211.182204)
				)
				(arc
					(start 411.618684 -210.687666)
					(mid 411.622404 -210.678686)
					(end 411.631384 -210.674966)
				)
				(arc
					(start 413.104584 -210.674966)
					(mid 413.113564 -210.678686)
					(end 413.117284 -210.687666)
				)
			)
		)
	)
	(zone
		(layer "In1.Cu")
		(hatch none 0.5)
		(connect_pads
			(clearance 0)
		)
		(min_thickness 0.25)
		(keepout
			(tracks not_allowed)
			(vias allowed)
			(pads allowed)
			(copperpour not_allowed)
			(footprints allowed)
		)
		(placement
			(enabled no)
			(sheetname "")
		)
		(fill
			(thermal_gap 0.5)
			(thermal_bridge_width 0.5)
			(island_removal_mode 0)
		)
		(polygon
			(pts
				(arc
					(start 319.790826 -391.822686)
					(mid 319.917826 -391.949686)
					(end 320.044826 -391.822686)
				)
				(arc
					(start 320.044826 -391.746486)
					(mid 319.917826 -391.619486)
					(end 319.790826 -391.746486)
				)
			)
		)
	)
	(zone
		(layer "In1.Cu")
		(hatch none 0.5)
		(connect_pads
			(clearance 0)
		)
		(min_thickness 0.25)
		(keepout
			(tracks not_allowed)
			(vias allowed)
			(pads allowed)
			(copperpour not_allowed)
			(footprints allowed)
		)
		(placement
			(enabled no)
			(sheetname "")
		)
		(fill
			(thermal_gap 0.5)
			(thermal_bridge_width 0.5)
			(island_removal_mode 0)
		)
		(polygon
			(pts
				(arc
					(start 199.4535 -208.632552)
					(mid 199.44978 -208.641532)
					(end 199.4408 -208.645252)
				)
				(arc
					(start 197.9676 -208.645252)
					(mid 197.95862 -208.641532)
					(end 197.9549 -208.632552)
				)
				(arc
					(start 197.9549 -208.138014)
					(mid 197.95862 -208.129034)
					(end 197.9676 -208.125314)
				)
				(arc
					(start 199.4408 -208.125314)
					(mid 199.44978 -208.129034)
					(end 199.4535 -208.138014)
				)
			)
		)
	)
	(zone
		(layer "In1.Cu")
		(hatch none 0.5)
		(connect_pads
			(clearance 0)
		)
		(min_thickness 0.25)
		(keepout
			(tracks not_allowed)
			(vias allowed)
			(pads allowed)
			(copperpour not_allowed)
			(footprints allowed)
		)
		(placement
			(enabled no)
			(sheetname "")
		)
		(fill
			(thermal_gap 0.5)
			(thermal_bridge_width 0.5)
			(island_removal_mode 0)
		)
		(polygon
			(pts
				(arc
					(start 411.888686 -394.385292)
					(mid 411.507686 -394.385292)
					(end 411.888686 -394.385292)
				)
			)
		)
	)
	(zone
		(layer "In1.Cu")
		(hatch none 0.5)
		(connect_pads
			(clearance 0)
		)
		(min_thickness 0.25)
		(keepout
			(tracks not_allowed)
			(vias allowed)
			(pads allowed)
			(copperpour not_allowed)
			(footprints allowed)
		)
		(placement
			(enabled no)
			(sheetname "")
		)
		(fill
			(thermal_gap 0.5)
			(thermal_bridge_width 0.5)
			(island_removal_mode 0)
		)
		(polygon
			(pts
				(arc
					(start 331.088492 -390.65581)
					(mid 331.079256 -390.675734)
					(end 331.076046 -390.697466)
				)
				(arc
					(start 331.076046 -390.89203)
					(mid 331.098364 -390.945912)
					(end 331.152246 -390.96823)
				)
				(arc
					(start 331.838046 -390.96823)
					(mid 331.891928 -390.945912)
					(end 331.914246 -390.89203)
				)
				(arc
					(start 331.914246 -390.697466)
					(mid 331.911078 -390.675722)
					(end 331.9018 -390.65581)
				)
				(arc
					(start 331.709014 -390.359646)
					(mid 331.696792 -390.317962)
					(end 331.709268 -390.276334)
				)
				(arc
					(start 331.9018 -389.98271)
					(mid 331.911036 -389.962786)
					(end 331.914246 -389.941054)
				)
				(arc
					(start 331.914246 -389.74649)
					(mid 331.891928 -389.692608)
					(end 331.838046 -389.67029)
				)
				(arc
					(start 331.152246 -389.67029)
					(mid 331.098364 -389.692608)
					(end 331.076046 -389.74649)
				)
				(arc
					(start 331.076046 -389.942324)
					(mid 331.079214 -389.964068)
					(end 331.088492 -389.98398)
				)
				(arc
					(start 331.281024 -390.277604)
					(mid 331.293426 -390.31926)
					(end 331.281024 -390.360916)
				)
			)
		)
	)
	(zone
		(layer "In1.Cu")
		(hatch none 0.5)
		(connect_pads
			(clearance 0)
		)
		(min_thickness 0.25)
		(keepout
			(tracks not_allowed)
			(vias allowed)
			(pads allowed)
			(copperpour not_allowed)
			(footprints allowed)
		)
		(placement
			(enabled no)
			(sheetname "")
		)
		(fill
			(thermal_gap 0.5)
			(thermal_bridge_width 0.5)
			(island_removal_mode 0)
		)
		(polygon
			(pts
				(arc
					(start 265.87831 -280.634948)
					(mid 265.21791 -280.634948)
					(end 265.87831 -280.634948)
				)
			)
		)
	)
	(zone
		(layer "In1.Cu")
		(hatch none 0.5)
		(connect_pads
			(clearance 0)
		)
		(min_thickness 0.25)
		(keepout
			(tracks not_allowed)
			(vias allowed)
			(pads allowed)
			(copperpour not_allowed)
			(footprints allowed)
		)
		(placement
			(enabled no)
			(sheetname "")
		)
		(fill
			(thermal_gap 0.5)
			(thermal_bridge_width 0.5)
			(island_removal_mode 0)
		)
		(polygon
			(pts
				(arc
					(start 49.861216 -385.31038)
					(mid 49.480216 -385.31038)
					(end 49.861216 -385.31038)
				)
			)
		)
	)
	(zone
		(layer "In1.Cu")
		(hatch none 0.5)
		(connect_pads
			(clearance 0)
		)
		(min_thickness 0.25)
		(keepout
			(tracks not_allowed)
			(vias allowed)
			(pads allowed)
			(copperpour not_allowed)
			(footprints allowed)
		)
		(placement
			(enabled no)
			(sheetname "")
		)
		(fill
			(thermal_gap 0.5)
			(thermal_bridge_width 0.5)
			(island_removal_mode 0)
		)
		(polygon
			(pts
				(arc
					(start 428.205392 -268.98219)
					(mid 428.201672 -268.99117)
					(end 428.192692 -268.99489)
				)
				(arc
					(start 426.719492 -268.99489)
					(mid 426.710512 -268.99117)
					(end 426.706792 -268.98219)
				)
				(arc
					(start 426.706792 -268.487652)
					(mid 426.710512 -268.478672)
					(end 426.719492 -268.474952)
				)
				(arc
					(start 428.192692 -268.474952)
					(mid 428.201672 -268.478672)
					(end 428.205392 -268.487652)
				)
			)
		)
	)
	(zone
		(layer "In1.Cu")
		(hatch none 0.5)
		(connect_pads
			(clearance 0)
		)
		(min_thickness 0.25)
		(keepout
			(tracks not_allowed)
			(vias allowed)
			(pads allowed)
			(copperpour not_allowed)
			(footprints allowed)
		)
		(placement
			(enabled no)
			(sheetname "")
		)
		(fill
			(thermal_gap 0.5)
			(thermal_bridge_width 0.5)
			(island_removal_mode 0)
		)
		(polygon
			(pts
				(arc
					(start 270.397478 -246.032274)
					(mid 270.393758 -246.041254)
					(end 270.384778 -246.044974)
				)
				(arc
					(start 268.911578 -246.044974)
					(mid 268.902598 -246.041254)
					(end 268.898878 -246.032274)
				)
				(arc
					(start 268.898878 -245.537736)
					(mid 268.902598 -245.528756)
					(end 268.911578 -245.525036)
				)
				(arc
					(start 270.384778 -245.525036)
					(mid 270.393758 -245.528756)
					(end 270.397478 -245.537736)
				)
			)
		)
	)
	(zone
		(layer "In1.Cu")
		(hatch none 0.5)
		(connect_pads
			(clearance 0)
		)
		(min_thickness 0.25)
		(keepout
			(tracks not_allowed)
			(vias allowed)
			(pads allowed)
			(copperpour not_allowed)
			(footprints allowed)
		)
		(placement
			(enabled no)
			(sheetname "")
		)
		(fill
			(thermal_gap 0.5)
			(thermal_bridge_width 0.5)
			(island_removal_mode 0)
		)
		(polygon
			(pts
				(arc
					(start 187.809378 -276.632416)
					(mid 187.805658 -276.641396)
					(end 187.796678 -276.645116)
				)
				(arc
					(start 186.323478 -276.645116)
					(mid 186.314498 -276.641396)
					(end 186.310778 -276.632416)
				)
				(arc
					(start 186.310778 -276.137878)
					(mid 186.314498 -276.128898)
					(end 186.323478 -276.125178)
				)
				(arc
					(start 187.796678 -276.125178)
					(mid 187.805658 -276.128898)
					(end 187.809378 -276.137878)
				)
			)
		)
	)
	(zone
		(layer "In1.Cu")
		(hatch none 0.5)
		(connect_pads
			(clearance 0)
		)
		(min_thickness 0.25)
		(keepout
			(tracks not_allowed)
			(vias allowed)
			(pads allowed)
			(copperpour not_allowed)
			(footprints allowed)
		)
		(placement
			(enabled no)
			(sheetname "")
		)
		(fill
			(thermal_gap 0.5)
			(thermal_bridge_width 0.5)
			(island_removal_mode 0)
		)
		(polygon
			(pts
				(arc
					(start 300.57344 -261.332218)
					(mid 300.56972 -261.341198)
					(end 300.56074 -261.344918)
				)
				(arc
					(start 299.08754 -261.344918)
					(mid 299.07856 -261.341198)
					(end 299.07484 -261.332218)
				)
				(arc
					(start 299.07484 -260.83768)
					(mid 299.07856 -260.8287)
					(end 299.08754 -260.82498)
				)
				(arc
					(start 300.56074 -260.82498)
					(mid 300.56972 -260.8287)
					(end 300.57344 -260.83768)
				)
			)
		)
	)
	(zone
		(layer "In1.Cu")
		(hatch none 0.5)
		(connect_pads
			(clearance 0)
		)
		(min_thickness 0.25)
		(keepout
			(tracks not_allowed)
			(vias allowed)
			(pads allowed)
			(copperpour not_allowed)
			(footprints allowed)
		)
		(placement
			(enabled no)
			(sheetname "")
		)
		(fill
			(thermal_gap 0.5)
			(thermal_bridge_width 0.5)
			(island_removal_mode 0)
		)
		(polygon
			(pts
				(arc
					(start 37.545264 -314.032392)
					(mid 37.541544 -314.041372)
					(end 37.532564 -314.045092)
				)
				(arc
					(start 36.059364 -314.045092)
					(mid 36.050384 -314.041372)
					(end 36.046664 -314.032392)
				)
				(arc
					(start 36.046664 -313.537854)
					(mid 36.050384 -313.528874)
					(end 36.059364 -313.525154)
				)
				(arc
					(start 37.532564 -313.525154)
					(mid 37.541544 -313.528874)
					(end 37.545264 -313.537854)
				)
			)
		)
	)
	(zone
		(layer "In1.Cu")
		(hatch none 0.5)
		(connect_pads
			(clearance 0)
		)
		(min_thickness 0.25)
		(keepout
			(tracks not_allowed)
			(vias allowed)
			(pads allowed)
			(copperpour not_allowed)
			(footprints allowed)
		)
		(placement
			(enabled no)
			(sheetname "")
		)
		(fill
			(thermal_gap 0.5)
			(thermal_bridge_width 0.5)
			(island_removal_mode 0)
		)
		(polygon
			(pts
				(arc
					(start 300.57344 -268.132306)
					(mid 300.56972 -268.141286)
					(end 300.56074 -268.145006)
				)
				(arc
					(start 299.08754 -268.145006)
					(mid 299.07856 -268.141286)
					(end 299.07484 -268.132306)
				)
				(arc
					(start 299.07484 -267.637768)
					(mid 299.07856 -267.628788)
					(end 299.08754 -267.625068)
				)
				(arc
					(start 300.56074 -267.625068)
					(mid 300.56972 -267.628788)
					(end 300.57344 -267.637768)
				)
			)
		)
	)
	(zone
		(layer "In1.Cu")
		(hatch none 0.5)
		(connect_pads
			(clearance 0)
		)
		(min_thickness 0.25)
		(keepout
			(tracks not_allowed)
			(vias allowed)
			(pads allowed)
			(copperpour not_allowed)
			(footprints allowed)
		)
		(placement
			(enabled no)
			(sheetname "")
		)
		(fill
			(thermal_gap 0.5)
			(thermal_bridge_width 0.5)
			(island_removal_mode 0)
		)
		(polygon
			(pts
				(arc
					(start 33.445196 -301.282354)
					(mid 33.441476 -301.291334)
					(end 33.432496 -301.295054)
				)
				(arc
					(start 31.959296 -301.295054)
					(mid 31.950316 -301.291334)
					(end 31.946596 -301.282354)
				)
				(arc
					(start 31.946596 -300.787816)
					(mid 31.950316 -300.778836)
					(end 31.959296 -300.775116)
				)
				(arc
					(start 33.432496 -300.775116)
					(mid 33.441476 -300.778836)
					(end 33.445196 -300.787816)
				)
			)
		)
	)
	(zone
		(layer "In1.Cu")
		(hatch none 0.5)
		(connect_pads
			(clearance 0)
		)
		(min_thickness 0.25)
		(keepout
			(tracks not_allowed)
			(vias allowed)
			(pads allowed)
			(copperpour not_allowed)
			(footprints allowed)
		)
		(placement
			(enabled no)
			(sheetname "")
		)
		(fill
			(thermal_gap 0.5)
			(thermal_bridge_width 0.5)
			(island_removal_mode 0)
		)
		(polygon
			(pts
				(arc
					(start 165.177216 -318.282574)
					(mid 165.173496 -318.291554)
					(end 165.164516 -318.295274)
				)
				(arc
					(start 163.691316 -318.295274)
					(mid 163.682336 -318.291554)
					(end 163.678616 -318.282574)
				)
				(arc
					(start 163.678616 -317.788036)
					(mid 163.682336 -317.779056)
					(end 163.691316 -317.775336)
				)
				(arc
					(start 165.164516 -317.775336)
					(mid 165.173496 -317.779056)
					(end 165.177216 -317.788036)
				)
			)
		)
	)
	(zone
		(layer "In1.Cu")
		(hatch none 0.5)
		(connect_pads
			(clearance 0)
		)
		(min_thickness 0.25)
		(keepout
			(tracks not_allowed)
			(vias allowed)
			(pads allowed)
			(copperpour not_allowed)
			(footprints allowed)
		)
		(placement
			(enabled no)
			(sheetname "")
		)
		(fill
			(thermal_gap 0.5)
			(thermal_bridge_width 0.5)
			(island_removal_mode 0)
		)
		(polygon
			(pts
				(arc
					(start 450.8373 -308.932326)
					(mid 450.83358 -308.941306)
					(end 450.8246 -308.945026)
				)
				(arc
					(start 449.3514 -308.945026)
					(mid 449.34242 -308.941306)
					(end 449.3387 -308.932326)
				)
				(arc
					(start 449.3387 -308.437788)
					(mid 449.34242 -308.428808)
					(end 449.3514 -308.425088)
				)
				(arc
					(start 450.8246 -308.425088)
					(mid 450.83358 -308.428808)
					(end 450.8373 -308.437788)
				)
			)
		)
	)
	(zone
		(layer "In1.Cu")
		(hatch none 0.5)
		(connect_pads
			(clearance 0)
		)
		(min_thickness 0.25)
		(keepout
			(tracks not_allowed)
			(vias allowed)
			(pads allowed)
			(copperpour not_allowed)
			(footprints allowed)
		)
		(placement
			(enabled no)
			(sheetname "")
		)
		(fill
			(thermal_gap 0.5)
			(thermal_bridge_width 0.5)
			(island_removal_mode 0)
		)
		(polygon
			(pts
				(arc
					(start 265.87831 -302.73498)
					(mid 265.21791 -302.73498)
					(end 265.87831 -302.73498)
				)
			)
		)
	)
	(zone
		(layer "In1.Cu")
		(hatch none 0.5)
		(connect_pads
			(clearance 0)
		)
		(min_thickness 0.25)
		(keepout
			(tracks not_allowed)
			(vias allowed)
			(pads allowed)
			(copperpour not_allowed)
			(footprints allowed)
		)
		(placement
			(enabled no)
			(sheetname "")
		)
		(fill
			(thermal_gap 0.5)
			(thermal_bridge_width 0.5)
			(island_removal_mode 0)
		)
		(polygon
			(pts
				(arc
					(start 60.177426 -246.032528)
					(mid 60.173706 -246.041508)
					(end 60.164726 -246.045228)
				)
				(arc
					(start 58.691526 -246.045228)
					(mid 58.682546 -246.041508)
					(end 58.678826 -246.032528)
				)
				(arc
					(start 58.678826 -245.53799)
					(mid 58.682546 -245.52901)
					(end 58.691526 -245.52529)
				)
				(arc
					(start 60.164726 -245.52529)
					(mid 60.173706 -245.52901)
					(end 60.177426 -245.53799)
				)
			)
		)
	)
	(zone
		(layer "In1.Cu")
		(hatch none 0.5)
		(connect_pads
			(clearance 0)
		)
		(min_thickness 0.25)
		(keepout
			(tracks not_allowed)
			(vias allowed)
			(pads allowed)
			(copperpour not_allowed)
			(footprints allowed)
		)
		(placement
			(enabled no)
			(sheetname "")
		)
		(fill
			(thermal_gap 0.5)
			(thermal_bridge_width 0.5)
			(island_removal_mode 0)
		)
		(polygon
			(pts
				(arc
					(start 296.473372 -253.682246)
					(mid 296.469652 -253.691226)
					(end 296.460672 -253.694946)
				)
				(arc
					(start 294.987472 -253.694946)
					(mid 294.978492 -253.691226)
					(end 294.974772 -253.682246)
				)
				(arc
					(start 294.974772 -253.187708)
					(mid 294.978492 -253.178728)
					(end 294.987472 -253.175008)
				)
				(arc
					(start 296.460672 -253.175008)
					(mid 296.469652 -253.178728)
					(end 296.473372 -253.187708)
				)
			)
		)
	)
	(zone
		(layer "In1.Cu")
		(hatch none 0.5)
		(connect_pads
			(clearance 0)
		)
		(min_thickness 0.25)
		(keepout
			(tracks not_allowed)
			(vias allowed)
			(pads allowed)
			(copperpour not_allowed)
			(footprints allowed)
		)
		(placement
			(enabled no)
			(sheetname "")
		)
		(fill
			(thermal_gap 0.5)
			(thermal_bridge_width 0.5)
			(island_removal_mode 0)
		)
		(polygon
			(pts
				(arc
					(start 432.30546 -283.43225)
					(mid 432.30174 -283.44123)
					(end 432.29276 -283.44495)
				)
				(arc
					(start 430.81956 -283.44495)
					(mid 430.81058 -283.44123)
					(end 430.80686 -283.43225)
				)
				(arc
					(start 430.80686 -282.937712)
					(mid 430.81058 -282.928732)
					(end 430.81956 -282.925012)
				)
				(arc
					(start 432.29276 -282.925012)
					(mid 432.30174 -282.928732)
					(end 432.30546 -282.937712)
				)
			)
		)
	)
	(zone
		(layer "In1.Cu")
		(hatch none 0.5)
		(connect_pads
			(clearance 0)
		)
		(min_thickness 0.25)
		(keepout
			(tracks not_allowed)
			(vias allowed)
			(pads allowed)
			(copperpour not_allowed)
			(footprints allowed)
		)
		(placement
			(enabled no)
			(sheetname "")
		)
		(fill
			(thermal_gap 0.5)
			(thermal_bridge_width 0.5)
			(island_removal_mode 0)
		)
		(polygon
			(pts
				(arc
					(start 180.265324 -314.88253)
					(mid 180.261604 -314.89151)
					(end 180.252624 -314.89523)
				)
				(arc
					(start 178.779424 -314.89523)
					(mid 178.770444 -314.89151)
					(end 178.766724 -314.88253)
				)
				(arc
					(start 178.766724 -314.387992)
					(mid 178.770444 -314.379012)
					(end 178.779424 -314.375292)
				)
				(arc
					(start 180.252624 -314.375292)
					(mid 180.261604 -314.379012)
					(end 180.265324 -314.387992)
				)
			)
		)
	)
	(zone
		(layer "In1.Cu")
		(hatch none 0.5)
		(connect_pads
			(clearance 0)
		)
		(min_thickness 0.25)
		(keepout
			(tracks not_allowed)
			(vias allowed)
			(pads allowed)
			(copperpour not_allowed)
			(footprints allowed)
		)
		(placement
			(enabled no)
			(sheetname "")
		)
		(fill
			(thermal_gap 0.5)
			(thermal_bridge_width 0.5)
			(island_removal_mode 0)
		)
		(polygon
			(pts
				(arc
					(start 417.217352 -229.032308)
					(mid 417.213632 -229.041288)
					(end 417.204652 -229.045008)
				)
				(arc
					(start 415.731452 -229.045008)
					(mid 415.722472 -229.041288)
					(end 415.718752 -229.032308)
				)
				(arc
					(start 415.718752 -228.53777)
					(mid 415.722472 -228.52879)
					(end 415.731452 -228.52507)
				)
				(arc
					(start 417.204652 -228.52507)
					(mid 417.213632 -228.52879)
					(end 417.217352 -228.53777)
				)
			)
		)
	)
	(zone
		(layer "In1.Cu")
		(hatch none 0.5)
		(connect_pads
			(clearance 0)
		)
		(min_thickness 0.25)
		(keepout
			(tracks not_allowed)
			(vias allowed)
			(pads allowed)
			(copperpour not_allowed)
			(footprints allowed)
		)
		(placement
			(enabled no)
			(sheetname "")
		)
		(fill
			(thermal_gap 0.5)
			(thermal_bridge_width 0.5)
			(island_removal_mode 0)
		)
		(polygon
			(pts
				(arc
					(start 417.217352 -222.23222)
					(mid 417.213632 -222.2412)
					(end 417.204652 -222.24492)
				)
				(arc
					(start 415.731452 -222.24492)
					(mid 415.722472 -222.2412)
					(end 415.718752 -222.23222)
				)
				(arc
					(start 415.718752 -221.737682)
					(mid 415.722472 -221.728702)
					(end 415.731452 -221.724982)
				)
				(arc
					(start 417.204652 -221.724982)
					(mid 417.213632 -221.728702)
					(end 417.217352 -221.737682)
				)
			)
		)
	)
	(zone
		(layer "In1.Cu")
		(hatch none 0.5)
		(connect_pads
			(clearance 0)
		)
		(min_thickness 0.25)
		(keepout
			(tracks not_allowed)
			(vias allowed)
			(pads allowed)
			(copperpour not_allowed)
			(footprints allowed)
		)
		(placement
			(enabled no)
			(sheetname "")
		)
		(fill
			(thermal_gap 0.5)
			(thermal_bridge_width 0.5)
			(island_removal_mode 0)
		)
		(polygon
			(pts
				(arc
					(start 129.690876 -383.440686)
					(mid 129.817876 -383.567686)
					(end 129.944876 -383.440686)
				)
				(arc
					(start 129.944876 -383.364486)
					(mid 129.817876 -383.237486)
					(end 129.690876 -383.364486)
				)
			)
		)
	)
	(zone
		(layer "In1.Cu")
		(hatch none 0.5)
		(connect_pads
			(clearance 0)
		)
		(min_thickness 0.25)
		(keepout
			(tracks not_allowed)
			(vias allowed)
			(pads allowed)
			(copperpour not_allowed)
			(footprints allowed)
		)
		(placement
			(enabled no)
			(sheetname "")
		)
		(fill
			(thermal_gap 0.5)
			(thermal_bridge_width 0.5)
			(island_removal_mode 0)
		)
		(polygon
			(pts
				(arc
					(start 281.385264 -293.632128)
					(mid 281.381544 -293.641108)
					(end 281.372564 -293.644828)
				)
				(arc
					(start 279.899364 -293.644828)
					(mid 279.890384 -293.641108)
					(end 279.886664 -293.632128)
				)
				(arc
					(start 279.886664 -293.13759)
					(mid 279.890384 -293.12861)
					(end 279.899364 -293.12489)
				)
				(arc
					(start 281.372564 -293.12489)
					(mid 281.381544 -293.12861)
					(end 281.385264 -293.13759)
				)
			)
		)
	)
	(zone
		(layer "In1.Cu")
		(hatch none 0.5)
		(connect_pads
			(clearance 0)
		)
		(min_thickness 0.25)
		(keepout
			(tracks not_allowed)
			(vias allowed)
			(pads allowed)
			(copperpour not_allowed)
			(footprints allowed)
		)
		(placement
			(enabled no)
			(sheetname "")
		)
		(fill
			(thermal_gap 0.5)
			(thermal_bridge_width 0.5)
			(island_removal_mode 0)
		)
		(polygon
			(pts
				(arc
					(start 420.661338 -223.082104)
					(mid 420.657618 -223.091084)
					(end 420.648638 -223.094804)
				)
				(arc
					(start 419.175438 -223.094804)
					(mid 419.166458 -223.091084)
					(end 419.162738 -223.082104)
				)
				(arc
					(start 419.162738 -222.587566)
					(mid 419.166458 -222.578586)
					(end 419.175438 -222.574866)
				)
				(arc
					(start 420.648638 -222.574866)
					(mid 420.657618 -222.578586)
					(end 420.661338 -222.587566)
				)
			)
		)
	)
	(zone
		(layer "In1.Cu")
		(hatch none 0.5)
		(connect_pads
			(clearance 0)
		)
		(min_thickness 0.25)
		(keepout
			(tracks not_allowed)
			(vias allowed)
			(pads allowed)
			(copperpour not_allowed)
			(footprints allowed)
		)
		(placement
			(enabled no)
			(sheetname "")
		)
		(fill
			(thermal_gap 0.5)
			(thermal_bridge_width 0.5)
			(island_removal_mode 0)
		)
		(polygon
			(pts
				(arc
					(start 293.029386 -272.382234)
					(mid 293.025666 -272.391214)
					(end 293.016686 -272.394934)
				)
				(arc
					(start 291.543486 -272.394934)
					(mid 291.534506 -272.391214)
					(end 291.530786 -272.382234)
				)
				(arc
					(start 291.530786 -271.887696)
					(mid 291.534506 -271.878716)
					(end 291.543486 -271.874996)
				)
				(arc
					(start 293.016686 -271.874996)
					(mid 293.025666 -271.878716)
					(end 293.029386 -271.887696)
				)
			)
		)
	)
	(zone
		(layer "In1.Cu")
		(hatch none 0.5)
		(connect_pads
			(clearance 0)
		)
		(min_thickness 0.25)
		(keepout
			(tracks not_allowed)
			(vias allowed)
			(pads allowed)
			(copperpour not_allowed)
			(footprints allowed)
		)
		(placement
			(enabled no)
			(sheetname "")
		)
		(fill
			(thermal_gap 0.5)
			(thermal_bridge_width 0.5)
			(island_removal_mode 0)
		)
		(polygon
			(pts
				(arc
					(start 184.365392 -292.782498)
					(mid 184.361672 -292.791478)
					(end 184.352692 -292.795198)
				)
				(arc
					(start 182.879492 -292.795198)
					(mid 182.870512 -292.791478)
					(end 182.866792 -292.782498)
				)
				(arc
					(start 182.866792 -292.28796)
					(mid 182.870512 -292.27898)
					(end 182.879492 -292.27526)
				)
				(arc
					(start 184.352692 -292.27526)
					(mid 184.361672 -292.27898)
					(end 184.365392 -292.28796)
				)
			)
		)
	)
	(zone
		(layer "In1.Cu")
		(hatch none 0.5)
		(connect_pads
			(clearance 0)
		)
		(min_thickness 0.25)
		(keepout
			(tracks not_allowed)
			(vias allowed)
			(pads allowed)
			(copperpour not_allowed)
			(footprints allowed)
		)
		(placement
			(enabled no)
			(sheetname "")
		)
		(fill
			(thermal_gap 0.5)
			(thermal_bridge_width 0.5)
			(island_removal_mode 0)
		)
		(polygon
			(pts
				(arc
					(start 413.117284 -282.582112)
					(mid 413.113564 -282.591092)
					(end 413.104584 -282.594812)
				)
				(arc
					(start 411.631384 -282.594812)
					(mid 411.622404 -282.591092)
					(end 411.618684 -282.582112)
				)
				(arc
					(start 411.618684 -282.087574)
					(mid 411.622404 -282.078594)
					(end 411.631384 -282.074874)
				)
				(arc
					(start 413.104584 -282.074874)
					(mid 413.113564 -282.078594)
					(end 413.117284 -282.087574)
				)
			)
		)
	)
	(zone
		(layer "In1.Cu")
		(hatch none 0.5)
		(connect_pads
			(clearance 0)
		)
		(min_thickness 0.25)
		(keepout
			(tracks not_allowed)
			(vias allowed)
			(pads allowed)
			(copperpour not_allowed)
			(footprints allowed)
		)
		(placement
			(enabled no)
			(sheetname "")
		)
		(fill
			(thermal_gap 0.5)
			(thermal_bridge_width 0.5)
			(island_removal_mode 0)
		)
		(polygon
			(pts
				(arc
					(start 428.205392 -202.682094)
					(mid 428.201672 -202.691074)
					(end 428.192692 -202.694794)
				)
				(arc
					(start 426.719492 -202.694794)
					(mid 426.710512 -202.691074)
					(end 426.706792 -202.682094)
				)
				(arc
					(start 426.706792 -202.187556)
					(mid 426.710512 -202.178576)
					(end 426.719492 -202.174856)
				)
				(arc
					(start 428.192692 -202.174856)
					(mid 428.201672 -202.178576)
					(end 428.205392 -202.187556)
				)
			)
		)
	)
	(zone
		(layer "In1.Cu")
		(hatch none 0.5)
		(connect_pads
			(clearance 0)
		)
		(min_thickness 0.25)
		(keepout
			(tracks not_allowed)
			(vias allowed)
			(pads allowed)
			(copperpour not_allowed)
			(footprints allowed)
		)
		(placement
			(enabled no)
			(sheetname "")
		)
		(fill
			(thermal_gap 0.5)
			(thermal_bridge_width 0.5)
			(island_removal_mode 0)
		)
		(polygon
			(pts
				(arc
					(start 417.217352 -314.032138)
					(mid 417.213632 -314.041118)
					(end 417.204652 -314.044838)
				)
				(arc
					(start 415.731452 -314.044838)
					(mid 415.722472 -314.041118)
					(end 415.718752 -314.032138)
				)
				(arc
					(start 415.718752 -313.5376)
					(mid 415.722472 -313.52862)
					(end 415.731452 -313.5249)
				)
				(arc
					(start 417.204652 -313.5249)
					(mid 417.213632 -313.52862)
					(end 417.217352 -313.5376)
				)
			)
		)
	)
	(zone
		(layer "In1.Cu")
		(hatch none 0.5)
		(connect_pads
			(clearance 0)
		)
		(min_thickness 0.25)
		(keepout
			(tracks not_allowed)
			(vias allowed)
			(pads allowed)
			(copperpour not_allowed)
			(footprints allowed)
		)
		(placement
			(enabled no)
			(sheetname "")
		)
		(fill
			(thermal_gap 0.5)
			(thermal_bridge_width 0.5)
			(island_removal_mode 0)
		)
		(polygon
			(pts
				(arc
					(start 180.265324 -305.532536)
					(mid 180.261604 -305.541516)
					(end 180.252624 -305.545236)
				)
				(arc
					(start 178.779424 -305.545236)
					(mid 178.770444 -305.541516)
					(end 178.766724 -305.532536)
				)
				(arc
					(start 178.766724 -305.037998)
					(mid 178.770444 -305.029018)
					(end 178.779424 -305.025298)
				)
				(arc
					(start 180.252624 -305.025298)
					(mid 180.261604 -305.029018)
					(end 180.265324 -305.037998)
				)
			)
		)
	)
	(zone
		(layer "In1.Cu")
		(hatch none 0.5)
		(connect_pads
			(clearance 0)
		)
		(min_thickness 0.25)
		(keepout
			(tracks not_allowed)
			(vias allowed)
			(pads allowed)
			(copperpour not_allowed)
			(footprints allowed)
		)
		(placement
			(enabled no)
			(sheetname "")
		)
		(fill
			(thermal_gap 0.5)
			(thermal_bridge_width 0.5)
			(island_removal_mode 0)
		)
		(polygon
			(pts
				(arc
					(start 352.897948 -399.143474)
					(mid 352.593148 -399.143474)
					(end 352.897948 -399.143474)
				)
			)
		)
	)
	(zone
		(layer "In1.Cu")
		(hatch none 0.5)
		(connect_pads
			(clearance 0)
		)
		(min_thickness 0.25)
		(keepout
			(tracks not_allowed)
			(vias allowed)
			(pads allowed)
			(copperpour not_allowed)
			(footprints allowed)
		)
		(placement
			(enabled no)
			(sheetname "")
		)
		(fill
			(thermal_gap 0.5)
			(thermal_bridge_width 0.5)
			(island_removal_mode 0)
		)
		(polygon
			(pts
				(arc
					(start 288.929318 -250.282202)
					(mid 288.925598 -250.291182)
					(end 288.916618 -250.294902)
				)
				(arc
					(start 287.443418 -250.294902)
					(mid 287.434438 -250.291182)
					(end 287.430718 -250.282202)
				)
				(arc
					(start 287.430718 -249.787664)
					(mid 287.434438 -249.778684)
					(end 287.443418 -249.774964)
				)
				(arc
					(start 288.916618 -249.774964)
					(mid 288.925598 -249.778684)
					(end 288.929318 -249.787664)
				)
			)
		)
	)
	(zone
		(layer "In1.Cu")
		(hatch none 0.5)
		(connect_pads
			(clearance 0)
		)
		(min_thickness 0.25)
		(keepout
			(tracks not_allowed)
			(vias allowed)
			(pads allowed)
			(copperpour not_allowed)
			(footprints allowed)
		)
		(placement
			(enabled no)
			(sheetname "")
		)
		(fill
			(thermal_gap 0.5)
			(thermal_bridge_width 0.5)
			(island_removal_mode 0)
		)
		(polygon
			(pts
				(arc
					(start 48.533304 -220.532452)
					(mid 48.529584 -220.541432)
					(end 48.520604 -220.545152)
				)
				(arc
					(start 47.047404 -220.545152)
					(mid 47.038424 -220.541432)
					(end 47.034704 -220.532452)
				)
				(arc
					(start 47.034704 -220.037914)
					(mid 47.038424 -220.028934)
					(end 47.047404 -220.025214)
				)
				(arc
					(start 48.520604 -220.025214)
					(mid 48.529584 -220.028934)
					(end 48.533304 -220.037914)
				)
			)
		)
	)
	(zone
		(layer "In1.Cu")
		(hatch none 0.5)
		(connect_pads
			(clearance 0)
		)
		(min_thickness 0.25)
		(keepout
			(tracks not_allowed)
			(vias allowed)
			(pads allowed)
			(copperpour not_allowed)
			(footprints allowed)
		)
		(placement
			(enabled no)
			(sheetname "")
		)
		(fill
			(thermal_gap 0.5)
			(thermal_bridge_width 0.5)
			(island_removal_mode 0)
		)
		(polygon
			(pts
				(arc
					(start 199.4535 -266.432538)
					(mid 199.44978 -266.441518)
					(end 199.4408 -266.445238)
				)
				(arc
					(start 197.9676 -266.445238)
					(mid 197.95862 -266.441518)
					(end 197.9549 -266.432538)
				)
				(arc
					(start 197.9549 -265.938)
					(mid 197.95862 -265.92902)
					(end 197.9676 -265.9253)
				)
				(arc
					(start 199.4408 -265.9253)
					(mid 199.44978 -265.92902)
					(end 199.4535 -265.938)
				)
			)
		)
	)
	(zone
		(layer "In1.Cu")
		(hatch none 0.5)
		(connect_pads
			(clearance 0)
		)
		(min_thickness 0.25)
		(keepout
			(tracks not_allowed)
			(vias allowed)
			(pads allowed)
			(copperpour not_allowed)
			(footprints allowed)
		)
		(placement
			(enabled no)
			(sheetname "")
		)
		(fill
			(thermal_gap 0.5)
			(thermal_bridge_width 0.5)
			(island_removal_mode 0)
		)
		(polygon
			(pts
				(arc
					(start 120.67032 -390.761474)
					(mid 120.36552 -390.761474)
					(end 120.67032 -390.761474)
				)
			)
		)
	)
	(zone
		(layer "In1.Cu")
		(hatch none 0.5)
		(connect_pads
			(clearance 0)
		)
		(min_thickness 0.25)
		(keepout
			(tracks not_allowed)
			(vias allowed)
			(pads allowed)
			(copperpour not_allowed)
			(footprints allowed)
		)
		(placement
			(enabled no)
			(sheetname "")
		)
		(fill
			(thermal_gap 0.5)
			(thermal_bridge_width 0.5)
			(island_removal_mode 0)
		)
		(polygon
			(pts
				(arc
					(start 454.937368 -313.182254)
					(mid 454.933648 -313.191234)
					(end 454.924668 -313.194954)
				)
				(arc
					(start 453.451468 -313.194954)
					(mid 453.442488 -313.191234)
					(end 453.438768 -313.182254)
				)
				(arc
					(start 453.438768 -312.687716)
					(mid 453.442488 -312.678736)
					(end 453.451468 -312.675016)
				)
				(arc
					(start 454.924668 -312.675016)
					(mid 454.933648 -312.678736)
					(end 454.937368 -312.687716)
				)
			)
		)
	)
	(zone
		(layer "In1.Cu")
		(hatch none 0.5)
		(connect_pads
			(clearance 0)
		)
		(min_thickness 0.25)
		(keepout
			(tracks not_allowed)
			(vias allowed)
			(pads allowed)
			(copperpour not_allowed)
			(footprints allowed)
		)
		(placement
			(enabled no)
			(sheetname "")
		)
		(fill
			(thermal_gap 0.5)
			(thermal_bridge_width 0.5)
			(island_removal_mode 0)
		)
		(polygon
			(pts
				(arc
					(start 345.98864 -397.849344)
					(mid 345.60764 -397.849344)
					(end 345.98864 -397.849344)
				)
			)
		)
	)
	(zone
		(layer "In1.Cu")
		(hatch none 0.5)
		(connect_pads
			(clearance 0)
		)
		(min_thickness 0.25)
		(keepout
			(tracks not_allowed)
			(vias allowed)
			(pads allowed)
			(copperpour not_allowed)
			(footprints allowed)
		)
		(placement
			(enabled no)
			(sheetname "")
		)
		(fill
			(thermal_gap 0.5)
			(thermal_bridge_width 0.5)
			(island_removal_mode 0)
		)
		(polygon
			(pts
				(arc
					(start 30.001464 -306.38242)
					(mid 29.997744 -306.3914)
					(end 29.988764 -306.39512)
				)
				(arc
					(start 28.515564 -306.39512)
					(mid 28.506584 -306.3914)
					(end 28.502864 -306.38242)
				)
				(arc
					(start 28.502864 -305.887882)
					(mid 28.506584 -305.878902)
					(end 28.515564 -305.875182)
				)
				(arc
					(start 29.988764 -305.875182)
					(mid 29.997744 -305.878902)
					(end 30.001464 -305.887882)
				)
			)
		)
	)
	(zone
		(layer "In1.Cu")
		(hatch none 0.5)
		(connect_pads
			(clearance 0)
		)
		(min_thickness 0.25)
		(keepout
			(tracks not_allowed)
			(vias allowed)
			(pads allowed)
			(copperpour not_allowed)
			(footprints allowed)
		)
		(placement
			(enabled no)
			(sheetname "")
		)
		(fill
			(thermal_gap 0.5)
			(thermal_bridge_width 0.5)
			(island_removal_mode 0)
		)
		(polygon
			(pts
				(arc
					(start 33.445196 -265.5824)
					(mid 33.441476 -265.59138)
					(end 33.432496 -265.5951)
				)
				(arc
					(start 31.959296 -265.5951)
					(mid 31.950316 -265.59138)
					(end 31.946596 -265.5824)
				)
				(arc
					(start 31.946596 -265.087862)
					(mid 31.950316 -265.078882)
					(end 31.959296 -265.075162)
				)
				(arc
					(start 33.432496 -265.075162)
					(mid 33.441476 -265.078882)
					(end 33.445196 -265.087862)
				)
			)
		)
	)
	(zone
		(layer "In1.Cu")
		(hatch none 0.5)
		(connect_pads
			(clearance 0)
		)
		(min_thickness 0.25)
		(keepout
			(tracks not_allowed)
			(vias allowed)
			(pads allowed)
			(copperpour not_allowed)
			(footprints allowed)
		)
		(placement
			(enabled no)
			(sheetname "")
		)
		(fill
			(thermal_gap 0.5)
			(thermal_bridge_width 0.5)
			(island_removal_mode 0)
		)
		(polygon
			(pts
				(arc
					(start 60.177426 -261.332472)
					(mid 60.173706 -261.341452)
					(end 60.164726 -261.345172)
				)
				(arc
					(start 58.691526 -261.345172)
					(mid 58.682546 -261.341452)
					(end 58.678826 -261.332472)
				)
				(arc
					(start 58.678826 -260.837934)
					(mid 58.682546 -260.828954)
					(end 58.691526 -260.825234)
				)
				(arc
					(start 60.164726 -260.825234)
					(mid 60.173706 -260.828954)
					(end 60.177426 -260.837934)
				)
			)
		)
	)
	(zone
		(layer "In1.Cu")
		(hatch none 0.5)
		(connect_pads
			(clearance 0)
		)
		(min_thickness 0.25)
		(keepout
			(tracks not_allowed)
			(vias allowed)
			(pads allowed)
			(copperpour not_allowed)
			(footprints allowed)
		)
		(placement
			(enabled no)
			(sheetname "")
		)
		(fill
			(thermal_gap 0.5)
			(thermal_bridge_width 0.5)
			(island_removal_mode 0)
		)
		(polygon
			(pts
				(arc
					(start 180.265324 -237.532418)
					(mid 180.261604 -237.541398)
					(end 180.252624 -237.545118)
				)
				(arc
					(start 178.779424 -237.545118)
					(mid 178.770444 -237.541398)
					(end 178.766724 -237.532418)
				)
				(arc
					(start 178.766724 -237.03788)
					(mid 178.770444 -237.0289)
					(end 178.779424 -237.02518)
				)
				(arc
					(start 180.252624 -237.02518)
					(mid 180.261604 -237.0289)
					(end 180.265324 -237.03788)
				)
			)
		)
	)
	(zone
		(layer "In1.Cu")
		(hatch none 0.5)
		(connect_pads
			(clearance 0)
		)
		(min_thickness 0.25)
		(keepout
			(tracks not_allowed)
			(vias allowed)
			(pads allowed)
			(copperpour not_allowed)
			(footprints allowed)
		)
		(placement
			(enabled no)
			(sheetname "")
		)
		(fill
			(thermal_gap 0.5)
			(thermal_bridge_width 0.5)
			(island_removal_mode 0)
		)
		(polygon
			(pts
				(arc
					(start 180.265324 -248.582434)
					(mid 180.261604 -248.591414)
					(end 180.252624 -248.595134)
				)
				(arc
					(start 178.779424 -248.595134)
					(mid 178.770444 -248.591414)
					(end 178.766724 -248.582434)
				)
				(arc
					(start 178.766724 -248.087896)
					(mid 178.770444 -248.078916)
					(end 178.779424 -248.075196)
				)
				(arc
					(start 180.252624 -248.075196)
					(mid 180.261604 -248.078916)
					(end 180.265324 -248.087896)
				)
			)
		)
	)
	(zone
		(layer "In1.Cu")
		(hatch none 0.5)
		(connect_pads
			(clearance 0)
		)
		(min_thickness 0.25)
		(keepout
			(tracks not_allowed)
			(vias allowed)
			(pads allowed)
			(copperpour not_allowed)
			(footprints allowed)
		)
		(placement
			(enabled no)
			(sheetname "")
		)
		(fill
			(thermal_gap 0.5)
			(thermal_bridge_width 0.5)
			(island_removal_mode 0)
		)
		(polygon
			(pts
				(arc
					(start 206.9973 -246.032528)
					(mid 206.99358 -246.041508)
					(end 206.9846 -246.045228)
				)
				(arc
					(start 205.5114 -246.045228)
					(mid 205.50242 -246.041508)
					(end 205.4987 -246.032528)
				)
				(arc
					(start 205.4987 -245.53799)
					(mid 205.50242 -245.52901)
					(end 205.5114 -245.52529)
				)
				(arc
					(start 206.9846 -245.52529)
					(mid 206.99358 -245.52901)
					(end 206.9973 -245.53799)
				)
			)
		)
	)
	(zone
		(layer "In1.Cu")
		(hatch none 0.5)
		(connect_pads
			(clearance 0)
		)
		(min_thickness 0.25)
		(keepout
			(tracks not_allowed)
			(vias allowed)
			(pads allowed)
			(copperpour not_allowed)
			(footprints allowed)
		)
		(placement
			(enabled no)
			(sheetname "")
		)
		(fill
			(thermal_gap 0.5)
			(thermal_bridge_width 0.5)
			(island_removal_mode 0)
		)
		(polygon
			(pts
				(arc
					(start 421.48887 -394.385292)
					(mid 421.10787 -394.385292)
					(end 421.48887 -394.385292)
				)
			)
		)
	)
	(zone
		(layer "In1.Cu")
		(hatch none 0.5)
		(connect_pads
			(clearance 0)
		)
		(min_thickness 0.25)
		(keepout
			(tracks not_allowed)
			(vias allowed)
			(pads allowed)
			(copperpour not_allowed)
			(footprints allowed)
		)
		(placement
			(enabled no)
			(sheetname "")
		)
		(fill
			(thermal_gap 0.5)
			(thermal_bridge_width 0.5)
			(island_removal_mode 0)
		)
		(polygon
			(pts
				(arc
					(start 90.788998 -385.31038)
					(mid 90.407998 -385.31038)
					(end 90.788998 -385.31038)
				)
			)
		)
	)
	(zone
		(layer "In1.Cu")
		(hatch none 0.5)
		(connect_pads
			(clearance 0)
		)
		(min_thickness 0.25)
		(keepout
			(tracks not_allowed)
			(vias allowed)
			(pads allowed)
			(copperpour not_allowed)
			(footprints allowed)
		)
		(placement
			(enabled no)
			(sheetname "")
		)
		(fill
			(thermal_gap 0.5)
			(thermal_bridge_width 0.5)
			(island_removal_mode 0)
		)
		(polygon
			(pts
				(arc
					(start 195.353432 -305.532536)
					(mid 195.349712 -305.541516)
					(end 195.340732 -305.545236)
				)
				(arc
					(start 193.867532 -305.545236)
					(mid 193.858552 -305.541516)
					(end 193.854832 -305.532536)
				)
				(arc
					(start 193.854832 -305.037998)
					(mid 193.858552 -305.029018)
					(end 193.867532 -305.025298)
				)
				(arc
					(start 195.340732 -305.025298)
					(mid 195.349712 -305.029018)
					(end 195.353432 -305.037998)
				)
			)
		)
	)
	(zone
		(layer "In1.Cu")
		(hatch none 0.5)
		(connect_pads
			(clearance 0)
		)
		(min_thickness 0.25)
		(keepout
			(tracks not_allowed)
			(vias allowed)
			(pads allowed)
			(copperpour not_allowed)
			(footprints allowed)
		)
		(placement
			(enabled no)
			(sheetname "")
		)
		(fill
			(thermal_gap 0.5)
			(thermal_bridge_width 0.5)
			(island_removal_mode 0)
		)
		(polygon
			(pts
				(arc
					(start 116.961158 -388.774432)
					(mid 116.580158 -388.774432)
					(end 116.961158 -388.774432)
				)
			)
		)
	)
	(zone
		(layer "In1.Cu")
		(hatch none 0.5)
		(connect_pads
			(clearance 0)
		)
		(min_thickness 0.25)
		(keepout
			(tracks not_allowed)
			(vias allowed)
			(pads allowed)
			(copperpour not_allowed)
			(footprints allowed)
		)
		(placement
			(enabled no)
			(sheetname "")
		)
		(fill
			(thermal_gap 0.5)
			(thermal_bridge_width 0.5)
			(island_removal_mode 0)
		)
		(polygon
			(pts
				(arc
					(start 344.388694 -393.69238)
					(mid 344.007694 -393.69238)
					(end 344.388694 -393.69238)
				)
			)
		)
	)
	(zone
		(layer "In1.Cu")
		(hatch none 0.5)
		(connect_pads
			(clearance 0)
		)
		(min_thickness 0.25)
		(keepout
			(tracks not_allowed)
			(vias allowed)
			(pads allowed)
			(copperpour not_allowed)
			(footprints allowed)
		)
		(placement
			(enabled no)
			(sheetname "")
		)
		(fill
			(thermal_gap 0.5)
			(thermal_bridge_width 0.5)
			(island_removal_mode 0)
		)
		(polygon
			(pts
				(arc
					(start 88.788748 -386.003292)
					(mid 88.407748 -386.003292)
					(end 88.788748 -386.003292)
				)
			)
		)
	)
	(zone
		(layer "In1.Cu")
		(hatch none 0.5)
		(connect_pads
			(clearance 0)
		)
		(min_thickness 0.25)
		(keepout
			(tracks not_allowed)
			(vias allowed)
			(pads allowed)
			(copperpour not_allowed)
			(footprints allowed)
		)
		(placement
			(enabled no)
			(sheetname "")
		)
		(fill
			(thermal_gap 0.5)
			(thermal_bridge_width 0.5)
			(island_removal_mode 0)
		)
		(polygon
			(pts
				(arc
					(start 86.718902 -383.440686)
					(mid 86.845902 -383.567686)
					(end 86.972902 -383.440686)
				)
				(arc
					(start 86.972902 -383.364486)
					(mid 86.845902 -383.237486)
					(end 86.718902 -383.364486)
				)
			)
		)
	)
	(zone
		(layer "In1.Cu")
		(hatch none 0.5)
		(connect_pads
			(clearance 0)
		)
		(min_thickness 0.25)
		(keepout
			(tracks not_allowed)
			(vias allowed)
			(pads allowed)
			(copperpour not_allowed)
			(footprints allowed)
		)
		(placement
			(enabled no)
			(sheetname "")
		)
		(fill
			(thermal_gap 0.5)
			(thermal_bridge_width 0.5)
			(island_removal_mode 0)
		)
		(polygon
			(pts
				(arc
					(start 417.217352 -300.432216)
					(mid 417.213632 -300.441196)
					(end 417.204652 -300.444916)
				)
				(arc
					(start 415.731452 -300.444916)
					(mid 415.722472 -300.441196)
					(end 415.718752 -300.432216)
				)
				(arc
					(start 415.718752 -299.937678)
					(mid 415.722472 -299.928698)
					(end 415.731452 -299.924978)
				)
				(arc
					(start 417.204652 -299.924978)
					(mid 417.213632 -299.928698)
					(end 417.217352 -299.937678)
				)
			)
		)
	)
	(zone
		(layer "In1.Cu")
		(hatch none 0.5)
		(connect_pads
			(clearance 0)
		)
		(min_thickness 0.25)
		(keepout
			(tracks not_allowed)
			(vias allowed)
			(pads allowed)
			(copperpour not_allowed)
			(footprints allowed)
		)
		(placement
			(enabled no)
			(sheetname "")
		)
		(fill
			(thermal_gap 0.5)
			(thermal_bridge_width 0.5)
			(island_removal_mode 0)
		)
		(polygon
			(pts
				(arc
					(start 187.809378 -209.482436)
					(mid 187.805658 -209.491416)
					(end 187.796678 -209.495136)
				)
				(arc
					(start 186.323478 -209.495136)
					(mid 186.314498 -209.491416)
					(end 186.310778 -209.482436)
				)
				(arc
					(start 186.310778 -208.987898)
					(mid 186.314498 -208.978918)
					(end 186.323478 -208.975198)
				)
				(arc
					(start 187.796678 -208.975198)
					(mid 187.805658 -208.978918)
					(end 187.809378 -208.987898)
				)
			)
		)
	)
	(zone
		(layer "In1.Cu")
		(hatch none 0.5)
		(connect_pads
			(clearance 0)
		)
		(min_thickness 0.25)
		(keepout
			(tracks not_allowed)
			(vias allowed)
			(pads allowed)
			(copperpour not_allowed)
			(footprints allowed)
		)
		(placement
			(enabled no)
			(sheetname "")
		)
		(fill
			(thermal_gap 0.5)
			(thermal_bridge_width 0.5)
			(island_removal_mode 0)
		)
		(polygon
			(pts
				(arc
					(start 176.821338 -298.732448)
					(mid 176.817618 -298.741428)
					(end 176.808638 -298.745148)
				)
				(arc
					(start 175.335438 -298.745148)
					(mid 175.326458 -298.741428)
					(end 175.322738 -298.732448)
				)
				(arc
					(start 175.322738 -298.23791)
					(mid 175.326458 -298.22893)
					(end 175.335438 -298.22521)
				)
				(arc
					(start 176.808638 -298.22521)
					(mid 176.817618 -298.22893)
					(end 176.821338 -298.23791)
				)
			)
		)
	)
	(zone
		(layer "In1.Cu")
		(hatch none 0.5)
		(connect_pads
			(clearance 0)
		)
		(min_thickness 0.25)
		(keepout
			(tracks not_allowed)
			(vias allowed)
			(pads allowed)
			(copperpour not_allowed)
			(footprints allowed)
		)
		(placement
			(enabled no)
			(sheetname "")
		)
		(fill
			(thermal_gap 0.5)
			(thermal_bridge_width 0.5)
			(island_removal_mode 0)
		)
		(polygon
			(pts
				(arc
					(start 382.561338 -397.156432)
					(mid 382.180338 -397.156432)
					(end 382.561338 -397.156432)
				)
			)
		)
	)
	(zone
		(layer "In1.Cu")
		(hatch none 0.5)
		(connect_pads
			(clearance 0)
		)
		(min_thickness 0.25)
		(keepout
			(tracks not_allowed)
			(vias allowed)
			(pads allowed)
			(copperpour not_allowed)
			(footprints allowed)
		)
		(placement
			(enabled no)
			(sheetname "")
		)
		(fill
			(thermal_gap 0.5)
			(thermal_bridge_width 0.5)
			(island_removal_mode 0)
		)
		(polygon
			(pts
				(arc
					(start 37.545264 -278.332438)
					(mid 37.541544 -278.341418)
					(end 37.532564 -278.345138)
				)
				(arc
					(start 36.059364 -278.345138)
					(mid 36.050384 -278.341418)
					(end 36.046664 -278.332438)
				)
				(arc
					(start 36.046664 -277.8379)
					(mid 36.050384 -277.82892)
					(end 36.059364 -277.8252)
				)
				(arc
					(start 37.532564 -277.8252)
					(mid 37.541544 -277.82892)
					(end 37.545264 -277.8379)
				)
			)
		)
	)
	(zone
		(layer "In1.Cu")
		(hatch none 0.5)
		(connect_pads
			(clearance 0)
		)
		(min_thickness 0.25)
		(keepout
			(tracks not_allowed)
			(vias allowed)
			(pads allowed)
			(copperpour not_allowed)
			(footprints allowed)
		)
		(placement
			(enabled no)
			(sheetname "")
		)
		(fill
			(thermal_gap 0.5)
			(thermal_bridge_width 0.5)
			(island_removal_mode 0)
		)
		(polygon
			(pts
				(arc
					(start 129.070354 -383.92227)
					(mid 128.765554 -383.92227)
					(end 129.070354 -383.92227)
				)
			)
		)
	)
	(zone
		(layer "In1.Cu")
		(hatch none 0.5)
		(connect_pads
			(clearance 0)
		)
		(min_thickness 0.25)
		(keepout
			(tracks not_allowed)
			(vias allowed)
			(pads allowed)
			(copperpour not_allowed)
			(footprints allowed)
		)
		(placement
			(enabled no)
			(sheetname "")
		)
		(fill
			(thermal_gap 0.5)
			(thermal_bridge_width 0.5)
			(island_removal_mode 0)
		)
		(polygon
			(pts
				(arc
					(start 450.8373 -200.132188)
					(mid 450.83358 -200.141168)
					(end 450.8246 -200.144888)
				)
				(arc
					(start 449.3514 -200.144888)
					(mid 449.34242 -200.141168)
					(end 449.3387 -200.132188)
				)
				(arc
					(start 449.3387 -199.63765)
					(mid 449.34242 -199.62867)
					(end 449.3514 -199.62495)
				)
				(arc
					(start 450.8246 -199.62495)
					(mid 450.83358 -199.62867)
					(end 450.8373 -199.63765)
				)
			)
		)
	)
	(zone
		(layer "In1.Cu")
		(hatch none 0.5)
		(connect_pads
			(clearance 0)
		)
		(min_thickness 0.25)
		(keepout
			(tracks not_allowed)
			(vias allowed)
			(pads allowed)
			(copperpour not_allowed)
			(footprints allowed)
		)
		(placement
			(enabled no)
			(sheetname "")
		)
		(fill
			(thermal_gap 0.5)
			(thermal_bridge_width 0.5)
			(island_removal_mode 0)
		)
		(polygon
			(pts
				(arc
					(start 443.2935 -229.882192)
					(mid 443.28978 -229.891172)
					(end 443.2808 -229.894892)
				)
				(arc
					(start 441.8076 -229.894892)
					(mid 441.79862 -229.891172)
					(end 441.7949 -229.882192)
				)
				(arc
					(start 441.7949 -229.387654)
					(mid 441.79862 -229.378674)
					(end 441.8076 -229.374954)
				)
				(arc
					(start 443.2808 -229.374954)
					(mid 443.28978 -229.378674)
					(end 443.2935 -229.387654)
				)
			)
		)
	)
	(zone
		(layer "In1.Cu")
		(hatch none 0.5)
		(connect_pads
			(clearance 0)
		)
		(min_thickness 0.25)
		(keepout
			(tracks not_allowed)
			(vias allowed)
			(pads allowed)
			(copperpour not_allowed)
			(footprints allowed)
		)
		(placement
			(enabled no)
			(sheetname "")
		)
		(fill
			(thermal_gap 0.5)
			(thermal_bridge_width 0.5)
			(island_removal_mode 0)
		)
		(polygon
			(pts
				(arc
					(start 184.365392 -311.482486)
					(mid 184.361672 -311.491466)
					(end 184.352692 -311.495186)
				)
				(arc
					(start 182.879492 -311.495186)
					(mid 182.870512 -311.491466)
					(end 182.866792 -311.482486)
				)
				(arc
					(start 182.866792 -310.987948)
					(mid 182.870512 -310.978968)
					(end 182.879492 -310.975248)
				)
				(arc
					(start 184.352692 -310.975248)
					(mid 184.361672 -310.978968)
					(end 184.365392 -310.987948)
				)
			)
		)
	)
	(zone
		(layer "In1.Cu")
		(hatch none 0.5)
		(connect_pads
			(clearance 0)
		)
		(min_thickness 0.25)
		(keepout
			(tracks not_allowed)
			(vias allowed)
			(pads allowed)
			(copperpour not_allowed)
			(footprints allowed)
		)
		(placement
			(enabled no)
			(sheetname "")
		)
		(fill
			(thermal_gap 0.5)
			(thermal_bridge_width 0.5)
			(island_removal_mode 0)
		)
		(polygon
			(pts
				(arc
					(start 60.177426 -314.032392)
					(mid 60.173706 -314.041372)
					(end 60.164726 -314.045092)
				)
				(arc
					(start 58.691526 -314.045092)
					(mid 58.682546 -314.041372)
					(end 58.678826 -314.032392)
				)
				(arc
					(start 58.678826 -313.537854)
					(mid 58.682546 -313.528874)
					(end 58.691526 -313.525154)
				)
				(arc
					(start 60.164726 -313.525154)
					(mid 60.173706 -313.528874)
					(end 60.177426 -313.537854)
				)
			)
		)
	)
	(zone
		(layer "In1.Cu")
		(hatch none 0.5)
		(connect_pads
			(clearance 0)
		)
		(min_thickness 0.25)
		(keepout
			(tracks not_allowed)
			(vias allowed)
			(pads allowed)
			(copperpour not_allowed)
			(footprints allowed)
		)
		(placement
			(enabled no)
			(sheetname "")
		)
		(fill
			(thermal_gap 0.5)
			(thermal_bridge_width 0.5)
			(island_removal_mode 0)
		)
		(polygon
			(pts
				(arc
					(start 87.588852 -389.467344)
					(mid 87.207852 -389.467344)
					(end 87.588852 -389.467344)
				)
			)
		)
	)
	(zone
		(layer "In1.Cu")
		(hatch none 0.5)
		(connect_pads
			(clearance 0)
		)
		(min_thickness 0.25)
		(keepout
			(tracks not_allowed)
			(vias allowed)
			(pads allowed)
			(copperpour not_allowed)
			(footprints allowed)
		)
		(placement
			(enabled no)
			(sheetname "")
		)
		(fill
			(thermal_gap 0.5)
			(thermal_bridge_width 0.5)
			(island_removal_mode 0)
		)
		(polygon
			(pts
				(arc
					(start 18.357342 -218.83243)
					(mid 18.353622 -218.84141)
					(end 18.344642 -218.84513)
				)
				(arc
					(start 16.871442 -218.84513)
					(mid 16.862462 -218.84141)
					(end 16.858742 -218.83243)
				)
				(arc
					(start 16.858742 -218.337892)
					(mid 16.862462 -218.328912)
					(end 16.871442 -218.325192)
				)
				(arc
					(start 18.344642 -218.325192)
					(mid 18.353622 -218.328912)
					(end 18.357342 -218.337892)
				)
			)
		)
	)
	(zone
		(layer "In1.Cu")
		(hatch none 0.5)
		(connect_pads
			(clearance 0)
		)
		(min_thickness 0.25)
		(keepout
			(tracks not_allowed)
			(vias allowed)
			(pads allowed)
			(copperpour not_allowed)
			(footprints allowed)
		)
		(placement
			(enabled no)
			(sheetname "")
		)
		(fill
			(thermal_gap 0.5)
			(thermal_bridge_width 0.5)
			(island_removal_mode 0)
		)
		(polygon
			(pts
				(arc
					(start 195.353432 -234.132374)
					(mid 195.349712 -234.141354)
					(end 195.340732 -234.145074)
				)
				(arc
					(start 193.867532 -234.145074)
					(mid 193.858552 -234.141354)
					(end 193.854832 -234.132374)
				)
				(arc
					(start 193.854832 -233.637836)
					(mid 193.858552 -233.628856)
					(end 193.867532 -233.625136)
				)
				(arc
					(start 195.340732 -233.625136)
					(mid 195.349712 -233.628856)
					(end 195.353432 -233.637836)
				)
			)
		)
	)
	(zone
		(layer "In1.Cu")
		(hatch none 0.5)
		(connect_pads
			(clearance 0)
		)
		(min_thickness 0.25)
		(keepout
			(tracks not_allowed)
			(vias allowed)
			(pads allowed)
			(copperpour not_allowed)
			(footprints allowed)
		)
		(placement
			(enabled no)
			(sheetname "")
		)
		(fill
			(thermal_gap 0.5)
			(thermal_bridge_width 0.5)
			(island_removal_mode 0)
		)
		(polygon
			(pts
				(arc
					(start 51.791108 -383.440686)
					(mid 51.918108 -383.567686)
					(end 52.045108 -383.440686)
				)
				(arc
					(start 52.045108 -383.364486)
					(mid 51.918108 -383.237486)
					(end 51.791108 -383.364486)
				)
			)
		)
	)
	(zone
		(layer "In1.Cu")
		(hatch none 0.5)
		(connect_pads
			(clearance 0)
		)
		(min_thickness 0.25)
		(keepout
			(tracks not_allowed)
			(vias allowed)
			(pads allowed)
			(copperpour not_allowed)
			(footprints allowed)
		)
		(placement
			(enabled no)
			(sheetname "")
		)
		(fill
			(thermal_gap 0.5)
			(thermal_bridge_width 0.5)
			(island_removal_mode 0)
		)
		(polygon
			(pts
				(arc
					(start 346.78874 -397.156432)
					(mid 346.40774 -397.156432)
					(end 346.78874 -397.156432)
				)
			)
		)
	)
	(zone
		(layer "In1.Cu")
		(hatch none 0.5)
		(connect_pads
			(clearance 0)
		)
		(min_thickness 0.25)
		(keepout
			(tracks not_allowed)
			(vias allowed)
			(pads allowed)
			(copperpour not_allowed)
			(footprints allowed)
		)
		(placement
			(enabled no)
			(sheetname "")
		)
		(fill
			(thermal_gap 0.5)
			(thermal_bridge_width 0.5)
			(island_removal_mode 0)
		)
		(polygon
			(pts
				(arc
					(start 304.017426 -228.18217)
					(mid 304.013706 -228.19115)
					(end 304.004726 -228.19487)
				)
				(arc
					(start 302.531526 -228.19487)
					(mid 302.522546 -228.19115)
					(end 302.518826 -228.18217)
				)
				(arc
					(start 302.518826 -227.687632)
					(mid 302.522546 -227.678652)
					(end 302.531526 -227.674932)
				)
				(arc
					(start 304.004726 -227.674932)
					(mid 304.013706 -227.678652)
					(end 304.017426 -227.687632)
				)
			)
		)
	)
	(zone
		(layer "In1.Cu")
		(hatch none 0.5)
		(connect_pads
			(clearance 0)
		)
		(min_thickness 0.25)
		(keepout
			(tracks not_allowed)
			(vias allowed)
			(pads allowed)
			(copperpour not_allowed)
			(footprints allowed)
		)
		(placement
			(enabled no)
			(sheetname "")
		)
		(fill
			(thermal_gap 0.5)
			(thermal_bridge_width 0.5)
			(island_removal_mode 0)
		)
		(polygon
			(pts
				(arc
					(start 159.198056 -383.92227)
					(mid 158.893256 -383.92227)
					(end 159.198056 -383.92227)
				)
			)
		)
	)
	(zone
		(layer "In1.Cu")
		(hatch none 0.5)
		(connect_pads
			(clearance 0)
		)
		(min_thickness 0.25)
		(keepout
			(tracks not_allowed)
			(vias allowed)
			(pads allowed)
			(copperpour not_allowed)
			(footprints allowed)
		)
		(placement
			(enabled no)
			(sheetname "")
		)
		(fill
			(thermal_gap 0.5)
			(thermal_bridge_width 0.5)
			(island_removal_mode 0)
		)
		(polygon
			(pts
				(arc
					(start 450.8373 -224.782126)
					(mid 450.83358 -224.791106)
					(end 450.8246 -224.794826)
				)
				(arc
					(start 449.3514 -224.794826)
					(mid 449.34242 -224.791106)
					(end 449.3387 -224.782126)
				)
				(arc
					(start 449.3387 -224.287588)
					(mid 449.34242 -224.278608)
					(end 449.3514 -224.274888)
				)
				(arc
					(start 450.8246 -224.274888)
					(mid 450.83358 -224.278608)
					(end 450.8373 -224.287588)
				)
			)
		)
	)
	(zone
		(layer "In1.Cu")
		(hatch none 0.5)
		(connect_pads
			(clearance 0)
		)
		(min_thickness 0.25)
		(keepout
			(tracks not_allowed)
			(vias allowed)
			(pads allowed)
			(copperpour not_allowed)
			(footprints allowed)
		)
		(placement
			(enabled no)
			(sheetname "")
		)
		(fill
			(thermal_gap 0.5)
			(thermal_bridge_width 0.5)
			(island_removal_mode 0)
		)
		(polygon
			(pts
				(arc
					(start 413.117284 -276.632162)
					(mid 413.113564 -276.641142)
					(end 413.104584 -276.644862)
				)
				(arc
					(start 411.631384 -276.644862)
					(mid 411.622404 -276.641142)
					(end 411.618684 -276.632162)
				)
				(arc
					(start 411.618684 -276.137624)
					(mid 411.622404 -276.128644)
					(end 411.631384 -276.124924)
				)
				(arc
					(start 413.104584 -276.124924)
					(mid 413.113564 -276.128644)
					(end 413.117284 -276.137624)
				)
			)
		)
	)
	(zone
		(layer "In1.Cu")
		(hatch none 0.5)
		(connect_pads
			(clearance 0)
		)
		(min_thickness 0.25)
		(keepout
			(tracks not_allowed)
			(vias allowed)
			(pads allowed)
			(copperpour not_allowed)
			(footprints allowed)
		)
		(placement
			(enabled no)
			(sheetname "")
		)
		(fill
			(thermal_gap 0.5)
			(thermal_bridge_width 0.5)
			(island_removal_mode 0)
		)
		(polygon
			(pts
				(arc
					(start 432.30546 -199.282304)
					(mid 432.30174 -199.291284)
					(end 432.29276 -199.295004)
				)
				(arc
					(start 430.81956 -199.295004)
					(mid 430.81058 -199.291284)
					(end 430.80686 -199.282304)
				)
				(arc
					(start 430.80686 -198.787766)
					(mid 430.81058 -198.778786)
					(end 430.81956 -198.775066)
				)
				(arc
					(start 432.29276 -198.775066)
					(mid 432.30174 -198.778786)
					(end 432.30546 -198.787766)
				)
			)
		)
	)
	(zone
		(layer "In1.Cu")
		(hatch none 0.5)
		(connect_pads
			(clearance 0)
		)
		(min_thickness 0.25)
		(keepout
			(tracks not_allowed)
			(vias allowed)
			(pads allowed)
			(copperpour not_allowed)
			(footprints allowed)
		)
		(placement
			(enabled no)
			(sheetname "")
		)
		(fill
			(thermal_gap 0.5)
			(thermal_bridge_width 0.5)
			(island_removal_mode 0)
		)
		(polygon
			(pts
				(arc
					(start 187.809378 -245.18239)
					(mid 187.805658 -245.19137)
					(end 187.796678 -245.19509)
				)
				(arc
					(start 186.323478 -245.19509)
					(mid 186.314498 -245.19137)
					(end 186.310778 -245.18239)
				)
				(arc
					(start 186.310778 -244.687852)
					(mid 186.314498 -244.678872)
					(end 186.323478 -244.675152)
				)
				(arc
					(start 187.796678 -244.675152)
					(mid 187.805658 -244.678872)
					(end 187.809378 -244.687852)
				)
			)
		)
	)
	(zone
		(layer "In1.Cu")
		(hatch none 0.5)
		(connect_pads
			(clearance 0)
		)
		(min_thickness 0.25)
		(keepout
			(tracks not_allowed)
			(vias allowed)
			(pads allowed)
			(copperpour not_allowed)
			(footprints allowed)
		)
		(placement
			(enabled no)
			(sheetname "")
		)
		(fill
			(thermal_gap 0.5)
			(thermal_bridge_width 0.5)
			(island_removal_mode 0)
		)
		(polygon
			(pts
				(arc
					(start 414.618678 -399.701258)
					(mid 414.745678 -399.828258)
					(end 414.872678 -399.701258)
				)
				(arc
					(start 414.872678 -399.625058)
					(mid 414.745678 -399.498058)
					(end 414.618678 -399.625058)
				)
			)
		)
	)
	(zone
		(layer "In1.Cu")
		(hatch none 0.5)
		(connect_pads
			(clearance 0)
		)
		(min_thickness 0.25)
		(keepout
			(tracks not_allowed)
			(vias allowed)
			(pads allowed)
			(copperpour not_allowed)
			(footprints allowed)
		)
		(placement
			(enabled no)
			(sheetname "")
		)
		(fill
			(thermal_gap 0.5)
			(thermal_bridge_width 0.5)
			(island_removal_mode 0)
		)
		(polygon
			(pts
				(arc
					(start 447.393568 -222.23222)
					(mid 447.389848 -222.2412)
					(end 447.380868 -222.24492)
				)
				(arc
					(start 445.907668 -222.24492)
					(mid 445.898688 -222.2412)
					(end 445.894968 -222.23222)
				)
				(arc
					(start 445.894968 -221.737682)
					(mid 445.898688 -221.728702)
					(end 445.907668 -221.724982)
				)
				(arc
					(start 447.380868 -221.724982)
					(mid 447.389848 -221.728702)
					(end 447.393568 -221.737682)
				)
			)
		)
	)
	(zone
		(layer "In1.Cu")
		(hatch none 0.5)
		(connect_pads
			(clearance 0)
		)
		(min_thickness 0.25)
		(keepout
			(tracks not_allowed)
			(vias allowed)
			(pads allowed)
			(copperpour not_allowed)
			(footprints allowed)
		)
		(placement
			(enabled no)
			(sheetname "")
		)
		(fill
			(thermal_gap 0.5)
			(thermal_bridge_width 0.5)
			(island_removal_mode 0)
		)
		(polygon
			(pts
				(arc
					(start 22.45741 -278.332438)
					(mid 22.45369 -278.341418)
					(end 22.44471 -278.345138)
				)
				(arc
					(start 20.97151 -278.345138)
					(mid 20.96253 -278.341418)
					(end 20.95881 -278.332438)
				)
				(arc
					(start 20.95881 -277.8379)
					(mid 20.96253 -277.82892)
					(end 20.97151 -277.8252)
				)
				(arc
					(start 22.44471 -277.8252)
					(mid 22.45369 -277.82892)
					(end 22.45741 -277.8379)
				)
			)
		)
	)
	(zone
		(layer "In1.Cu")
		(hatch none 0.5)
		(connect_pads
			(clearance 0)
		)
		(min_thickness 0.25)
		(keepout
			(tracks not_allowed)
			(vias allowed)
			(pads allowed)
			(copperpour not_allowed)
			(footprints allowed)
		)
		(placement
			(enabled no)
			(sheetname "")
		)
		(fill
			(thermal_gap 0.5)
			(thermal_bridge_width 0.5)
			(island_removal_mode 0)
		)
		(polygon
			(pts
				(arc
					(start 25.901396 -254.532384)
					(mid 25.897676 -254.541364)
					(end 25.888696 -254.545084)
				)
				(arc
					(start 24.415496 -254.545084)
					(mid 24.406516 -254.541364)
					(end 24.402796 -254.532384)
				)
				(arc
					(start 24.402796 -254.037846)
					(mid 24.406516 -254.028866)
					(end 24.415496 -254.025146)
				)
				(arc
					(start 25.888696 -254.025146)
					(mid 25.897676 -254.028866)
					(end 25.901396 -254.037846)
				)
			)
		)
	)
	(zone
		(layer "In1.Cu")
		(hatch none 0.5)
		(connect_pads
			(clearance 0)
		)
		(min_thickness 0.25)
		(keepout
			(tracks not_allowed)
			(vias allowed)
			(pads allowed)
			(copperpour not_allowed)
			(footprints allowed)
		)
		(placement
			(enabled no)
			(sheetname "")
		)
		(fill
			(thermal_gap 0.5)
			(thermal_bridge_width 0.5)
			(island_removal_mode 0)
		)
		(polygon
			(pts
				(arc
					(start 56.077358 -296.182542)
					(mid 56.073638 -296.191522)
					(end 56.064658 -296.195242)
				)
				(arc
					(start 54.591458 -296.195242)
					(mid 54.582478 -296.191522)
					(end 54.578758 -296.182542)
				)
				(arc
					(start 54.578758 -295.688004)
					(mid 54.582478 -295.679024)
					(end 54.591458 -295.675304)
				)
				(arc
					(start 56.064658 -295.675304)
					(mid 56.073638 -295.679024)
					(end 56.077358 -295.688004)
				)
			)
		)
	)
	(zone
		(layer "In1.Cu")
		(hatch none 0.5)
		(connect_pads
			(clearance 0)
		)
		(min_thickness 0.25)
		(keepout
			(tracks not_allowed)
			(vias allowed)
			(pads allowed)
			(copperpour not_allowed)
			(footprints allowed)
		)
		(placement
			(enabled no)
			(sheetname "")
		)
		(fill
			(thermal_gap 0.5)
			(thermal_bridge_width 0.5)
			(island_removal_mode 0)
		)
		(polygon
			(pts
				(arc
					(start 277.941532 -234.982258)
					(mid 277.937812 -234.991238)
					(end 277.928832 -234.994958)
				)
				(arc
					(start 276.455632 -234.994958)
					(mid 276.446652 -234.991238)
					(end 276.442932 -234.982258)
				)
				(arc
					(start 276.442932 -234.48772)
					(mid 276.446652 -234.47874)
					(end 276.455632 -234.47502)
				)
				(arc
					(start 277.928832 -234.47502)
					(mid 277.937812 -234.47874)
					(end 277.941532 -234.48772)
				)
			)
		)
	)
	(zone
		(layer "In1.Cu")
		(hatch none 0.5)
		(connect_pads
			(clearance 0)
		)
		(min_thickness 0.25)
		(keepout
			(tracks not_allowed)
			(vias allowed)
			(pads allowed)
			(copperpour not_allowed)
			(footprints allowed)
		)
		(placement
			(enabled no)
			(sheetname "")
		)
		(fill
			(thermal_gap 0.5)
			(thermal_bridge_width 0.5)
			(island_removal_mode 0)
		)
		(polygon
			(pts
				(arc
					(start 413.117284 -262.182102)
					(mid 413.113564 -262.191082)
					(end 413.104584 -262.194802)
				)
				(arc
					(start 411.631384 -262.194802)
					(mid 411.622404 -262.191082)
					(end 411.618684 -262.182102)
				)
				(arc
					(start 411.618684 -261.687564)
					(mid 411.622404 -261.678584)
					(end 411.631384 -261.674864)
				)
				(arc
					(start 413.104584 -261.674864)
					(mid 413.113564 -261.678584)
					(end 413.117284 -261.687564)
				)
			)
		)
	)
	(zone
		(layer "In1.Cu")
		(hatch none 0.5)
		(connect_pads
			(clearance 0)
		)
		(min_thickness 0.25)
		(keepout
			(tracks not_allowed)
			(vias allowed)
			(pads allowed)
			(copperpour not_allowed)
			(footprints allowed)
		)
		(placement
			(enabled no)
			(sheetname "")
		)
		(fill
			(thermal_gap 0.5)
			(thermal_bridge_width 0.5)
			(island_removal_mode 0)
		)
		(polygon
			(pts
				(arc
					(start 300.57344 -280.032206)
					(mid 300.56972 -280.041186)
					(end 300.56074 -280.044906)
				)
				(arc
					(start 299.08754 -280.044906)
					(mid 299.07856 -280.041186)
					(end 299.07484 -280.032206)
				)
				(arc
					(start 299.07484 -279.537668)
					(mid 299.07856 -279.528688)
					(end 299.08754 -279.524968)
				)
				(arc
					(start 300.56074 -279.524968)
					(mid 300.56972 -279.528688)
					(end 300.57344 -279.537668)
				)
			)
		)
	)
	(zone
		(layer "In1.Cu")
		(hatch none 0.5)
		(connect_pads
			(clearance 0)
		)
		(min_thickness 0.25)
		(keepout
			(tracks not_allowed)
			(vias allowed)
			(pads allowed)
			(copperpour not_allowed)
			(footprints allowed)
		)
		(placement
			(enabled no)
			(sheetname "")
		)
		(fill
			(thermal_gap 0.5)
			(thermal_bridge_width 0.5)
			(island_removal_mode 0)
		)
		(polygon
			(pts
				(arc
					(start 450.8373 -243.482114)
					(mid 450.83358 -243.491094)
					(end 450.8246 -243.494814)
				)
				(arc
					(start 449.3514 -243.494814)
					(mid 449.34242 -243.491094)
					(end 449.3387 -243.482114)
				)
				(arc
					(start 449.3387 -242.987576)
					(mid 449.34242 -242.978596)
					(end 449.3514 -242.974876)
				)
				(arc
					(start 450.8246 -242.974876)
					(mid 450.83358 -242.978596)
					(end 450.8373 -242.987576)
				)
			)
		)
	)
	(zone
		(layer "In1.Cu")
		(hatch none 0.5)
		(connect_pads
			(clearance 0)
		)
		(min_thickness 0.25)
		(keepout
			(tracks not_allowed)
			(vias allowed)
			(pads allowed)
			(copperpour not_allowed)
			(footprints allowed)
		)
		(placement
			(enabled no)
			(sheetname "")
		)
		(fill
			(thermal_gap 0.5)
			(thermal_bridge_width 0.5)
			(island_removal_mode 0)
		)
		(polygon
			(pts
				(arc
					(start 273.841464 -301.2821)
					(mid 273.837744 -301.29108)
					(end 273.828764 -301.2948)
				)
				(arc
					(start 272.355564 -301.2948)
					(mid 272.346584 -301.29108)
					(end 272.342864 -301.2821)
				)
				(arc
					(start 272.342864 -300.787562)
					(mid 272.346584 -300.778582)
					(end 272.355564 -300.774862)
				)
				(arc
					(start 273.828764 -300.774862)
					(mid 273.837744 -300.778582)
					(end 273.841464 -300.787562)
				)
			)
		)
	)
	(zone
		(layer "In1.Cu")
		(hatch none 0.5)
		(connect_pads
			(clearance 0)
		)
		(min_thickness 0.25)
		(keepout
			(tracks not_allowed)
			(vias allowed)
			(pads allowed)
			(copperpour not_allowed)
			(footprints allowed)
		)
		(placement
			(enabled no)
			(sheetname "")
		)
		(fill
			(thermal_gap 0.5)
			(thermal_bridge_width 0.5)
			(island_removal_mode 0)
		)
		(polygon
			(pts
				(arc
					(start 450.8373 -232.432098)
					(mid 450.83358 -232.441078)
					(end 450.8246 -232.444798)
				)
				(arc
					(start 449.3514 -232.444798)
					(mid 449.34242 -232.441078)
					(end 449.3387 -232.432098)
				)
				(arc
					(start 449.3387 -231.93756)
					(mid 449.34242 -231.92858)
					(end 449.3514 -231.92486)
				)
				(arc
					(start 450.8246 -231.92486)
					(mid 450.83358 -231.92858)
					(end 450.8373 -231.93756)
				)
			)
		)
	)
	(zone
		(layer "In1.Cu")
		(hatch none 0.5)
		(connect_pads
			(clearance 0)
		)
		(min_thickness 0.25)
		(keepout
			(tracks not_allowed)
			(vias allowed)
			(pads allowed)
			(copperpour not_allowed)
			(footprints allowed)
		)
		(placement
			(enabled no)
			(sheetname "")
		)
		(fill
			(thermal_gap 0.5)
			(thermal_bridge_width 0.5)
			(island_removal_mode 0)
		)
		(polygon
			(pts
				(arc
					(start 206.5782 -206.685388)
					(mid 205.9178 -206.685388)
					(end 206.5782 -206.685388)
				)
			)
		)
	)
	(zone
		(layer "In1.Cu")
		(hatch none 0.5)
		(connect_pads
			(clearance 0)
		)
		(min_thickness 0.25)
		(keepout
			(tracks not_allowed)
			(vias allowed)
			(pads allowed)
			(copperpour not_allowed)
			(footprints allowed)
		)
		(placement
			(enabled no)
			(sheetname "")
		)
		(fill
			(thermal_gap 0.5)
			(thermal_bridge_width 0.5)
			(island_removal_mode 0)
		)
		(polygon
			(pts
				(arc
					(start 443.2935 -209.482182)
					(mid 443.28978 -209.491162)
					(end 443.2808 -209.494882)
				)
				(arc
					(start 441.8076 -209.494882)
					(mid 441.79862 -209.491162)
					(end 441.7949 -209.482182)
				)
				(arc
					(start 441.7949 -208.987644)
					(mid 441.79862 -208.978664)
					(end 441.8076 -208.974944)
				)
				(arc
					(start 443.2808 -208.974944)
					(mid 443.28978 -208.978664)
					(end 443.2935 -208.987644)
				)
			)
		)
	)
	(zone
		(layer "In1.Cu")
		(hatch none 0.5)
		(connect_pads
			(clearance 0)
		)
		(min_thickness 0.25)
		(keepout
			(tracks not_allowed)
			(vias allowed)
			(pads allowed)
			(copperpour not_allowed)
			(footprints allowed)
		)
		(placement
			(enabled no)
			(sheetname "")
		)
		(fill
			(thermal_gap 0.5)
			(thermal_bridge_width 0.5)
			(island_removal_mode 0)
		)
		(polygon
			(pts
				(arc
					(start 285.485332 -216.28227)
					(mid 285.481612 -216.29125)
					(end 285.472632 -216.29497)
				)
				(arc
					(start 283.999432 -216.29497)
					(mid 283.990452 -216.29125)
					(end 283.986732 -216.28227)
				)
				(arc
					(start 283.986732 -215.787732)
					(mid 283.990452 -215.778752)
					(end 283.999432 -215.775032)
				)
				(arc
					(start 285.472632 -215.775032)
					(mid 285.481612 -215.778752)
					(end 285.485332 -215.787732)
				)
			)
		)
	)
	(zone
		(layer "In1.Cu")
		(hatch none 0.5)
		(connect_pads
			(clearance 0)
		)
		(min_thickness 0.25)
		(keepout
			(tracks not_allowed)
			(vias allowed)
			(pads allowed)
			(copperpour not_allowed)
			(footprints allowed)
		)
		(placement
			(enabled no)
			(sheetname "")
		)
		(fill
			(thermal_gap 0.5)
			(thermal_bridge_width 0.5)
			(island_removal_mode 0)
		)
		(polygon
			(pts
				(arc
					(start 424.761406 -222.23222)
					(mid 424.757686 -222.2412)
					(end 424.748706 -222.24492)
				)
				(arc
					(start 423.275506 -222.24492)
					(mid 423.266526 -222.2412)
					(end 423.262806 -222.23222)
				)
				(arc
					(start 423.262806 -221.737682)
					(mid 423.266526 -221.728702)
					(end 423.275506 -221.724982)
				)
				(arc
					(start 424.748706 -221.724982)
					(mid 424.757686 -221.728702)
					(end 424.761406 -221.737682)
				)
			)
		)
	)
	(zone
		(layer "In1.Cu")
		(hatch none 0.5)
		(connect_pads
			(clearance 0)
		)
		(min_thickness 0.25)
		(keepout
			(tracks not_allowed)
			(vias allowed)
			(pads allowed)
			(copperpour not_allowed)
			(footprints allowed)
		)
		(placement
			(enabled no)
			(sheetname "")
		)
		(fill
			(thermal_gap 0.5)
			(thermal_bridge_width 0.5)
			(island_removal_mode 0)
		)
		(polygon
			(pts
				(arc
					(start 117.360954 -386.003292)
					(mid 116.979954 -386.003292)
					(end 117.360954 -386.003292)
				)
			)
		)
	)
	(zone
		(layer "In1.Cu")
		(hatch none 0.5)
		(connect_pads
			(clearance 0)
		)
		(min_thickness 0.25)
		(keepout
			(tracks not_allowed)
			(vias allowed)
			(pads allowed)
			(copperpour not_allowed)
			(footprints allowed)
		)
		(placement
			(enabled no)
			(sheetname "")
		)
		(fill
			(thermal_gap 0.5)
			(thermal_bridge_width 0.5)
			(island_removal_mode 0)
		)
		(polygon
			(pts
				(arc
					(start 281.385264 -245.182136)
					(mid 281.381544 -245.191116)
					(end 281.372564 -245.194836)
				)
				(arc
					(start 279.899364 -245.194836)
					(mid 279.890384 -245.191116)
					(end 279.886664 -245.182136)
				)
				(arc
					(start 279.886664 -244.687598)
					(mid 279.890384 -244.678618)
					(end 279.899364 -244.674898)
				)
				(arc
					(start 281.372564 -244.674898)
					(mid 281.381544 -244.678618)
					(end 281.385264 -244.687598)
				)
			)
		)
	)
	(zone
		(layer "In1.Cu")
		(hatch none 0.5)
		(connect_pads
			(clearance 0)
		)
		(min_thickness 0.25)
		(keepout
			(tracks not_allowed)
			(vias allowed)
			(pads allowed)
			(copperpour not_allowed)
			(footprints allowed)
		)
		(placement
			(enabled no)
			(sheetname "")
		)
		(fill
			(thermal_gap 0.5)
			(thermal_bridge_width 0.5)
			(island_removal_mode 0)
		)
		(polygon
			(pts
				(arc
					(start 447.393568 -275.782278)
					(mid 447.389848 -275.791258)
					(end 447.380868 -275.794978)
				)
				(arc
					(start 445.907668 -275.794978)
					(mid 445.898688 -275.791258)
					(end 445.894968 -275.782278)
				)
				(arc
					(start 445.894968 -275.28774)
					(mid 445.898688 -275.27876)
					(end 445.907668 -275.27504)
				)
				(arc
					(start 447.380868 -275.27504)
					(mid 447.389848 -275.27876)
					(end 447.393568 -275.28774)
				)
			)
		)
	)
	(zone
		(layer "In1.Cu")
		(hatch none 0.5)
		(connect_pads
			(clearance 0)
		)
		(min_thickness 0.25)
		(keepout
			(tracks not_allowed)
			(vias allowed)
			(pads allowed)
			(copperpour not_allowed)
			(footprints allowed)
		)
		(placement
			(enabled no)
			(sheetname "")
		)
		(fill
			(thermal_gap 0.5)
			(thermal_bridge_width 0.5)
			(island_removal_mode 0)
		)
		(polygon
			(pts
				(arc
					(start 161.488882 -388.774432)
					(mid 161.107882 -388.774432)
					(end 161.488882 -388.774432)
				)
			)
		)
	)
	(zone
		(layer "In1.Cu")
		(hatch none 0.5)
		(connect_pads
			(clearance 0)
		)
		(min_thickness 0.25)
		(keepout
			(tracks not_allowed)
			(vias allowed)
			(pads allowed)
			(copperpour not_allowed)
			(footprints allowed)
		)
		(placement
			(enabled no)
			(sheetname "")
		)
		(fill
			(thermal_gap 0.5)
			(thermal_bridge_width 0.5)
			(island_removal_mode 0)
		)
		(polygon
			(pts
				(arc
					(start 345.69781 -392.30427)
					(mid 345.39301 -392.30427)
					(end 345.69781 -392.30427)
				)
			)
		)
	)
	(zone
		(layer "In1.Cu")
		(hatch none 0.5)
		(connect_pads
			(clearance 0)
		)
		(min_thickness 0.25)
		(keepout
			(tracks not_allowed)
			(vias allowed)
			(pads allowed)
			(copperpour not_allowed)
			(footprints allowed)
		)
		(placement
			(enabled no)
			(sheetname "")
		)
		(fill
			(thermal_gap 0.5)
			(thermal_bridge_width 0.5)
			(island_removal_mode 0)
		)
		(polygon
			(pts
				(arc
					(start 176.821338 -289.382454)
					(mid 176.817618 -289.391434)
					(end 176.808638 -289.395154)
				)
				(arc
					(start 175.335438 -289.395154)
					(mid 175.326458 -289.391434)
					(end 175.322738 -289.382454)
				)
				(arc
					(start 175.322738 -288.887916)
					(mid 175.326458 -288.878936)
					(end 175.335438 -288.875216)
				)
				(arc
					(start 176.808638 -288.875216)
					(mid 176.817618 -288.878936)
					(end 176.821338 -288.887916)
				)
			)
		)
	)
	(zone
		(layer "In1.Cu")
		(hatch none 0.5)
		(connect_pads
			(clearance 0)
		)
		(min_thickness 0.25)
		(keepout
			(tracks not_allowed)
			(vias allowed)
			(pads allowed)
			(copperpour not_allowed)
			(footprints allowed)
		)
		(placement
			(enabled no)
			(sheetname "")
		)
		(fill
			(thermal_gap 0.5)
			(thermal_bridge_width 0.5)
			(island_removal_mode 0)
		)
		(polygon
			(pts
				(arc
					(start 435.749446 -211.182204)
					(mid 435.745726 -211.191184)
					(end 435.736746 -211.194904)
				)
				(arc
					(start 434.263546 -211.194904)
					(mid 434.254566 -211.191184)
					(end 434.250846 -211.182204)
				)
				(arc
					(start 434.250846 -210.687666)
					(mid 434.254566 -210.678686)
					(end 434.263546 -210.674966)
				)
				(arc
					(start 435.736746 -210.674966)
					(mid 435.745726 -210.678686)
					(end 435.749446 -210.687666)
				)
			)
		)
	)
	(zone
		(layer "In1.Cu")
		(hatch none 0.5)
		(connect_pads
			(clearance 0)
		)
		(min_thickness 0.25)
		(keepout
			(tracks not_allowed)
			(vias allowed)
			(pads allowed)
			(copperpour not_allowed)
			(footprints allowed)
		)
		(placement
			(enabled no)
			(sheetname "")
		)
		(fill
			(thermal_gap 0.5)
			(thermal_bridge_width 0.5)
			(island_removal_mode 0)
		)
		(polygon
			(pts
				(arc
					(start 450.8373 -268.98219)
					(mid 450.83358 -268.99117)
					(end 450.8246 -268.99489)
				)
				(arc
					(start 449.3514 -268.99489)
					(mid 449.34242 -268.99117)
					(end 449.3387 -268.98219)
				)
				(arc
					(start 449.3387 -268.487652)
					(mid 449.34242 -268.478672)
					(end 449.3514 -268.474952)
				)
				(arc
					(start 450.8246 -268.474952)
					(mid 450.83358 -268.478672)
					(end 450.8373 -268.487652)
				)
			)
		)
	)
	(zone
		(layer "In1.Cu")
		(hatch none 0.5)
		(connect_pads
			(clearance 0)
		)
		(min_thickness 0.25)
		(keepout
			(tracks not_allowed)
			(vias allowed)
			(pads allowed)
			(copperpour not_allowed)
			(footprints allowed)
		)
		(placement
			(enabled no)
			(sheetname "")
		)
		(fill
			(thermal_gap 0.5)
			(thermal_bridge_width 0.5)
			(island_removal_mode 0)
		)
		(polygon
			(pts
				(arc
					(start 311.970166 -392.30427)
					(mid 311.665366 -392.30427)
					(end 311.970166 -392.30427)
				)
			)
		)
	)
	(zone
		(layer "In1.Cu")
		(hatch none 0.5)
		(connect_pads
			(clearance 0)
		)
		(min_thickness 0.25)
		(keepout
			(tracks not_allowed)
			(vias allowed)
			(pads allowed)
			(copperpour not_allowed)
			(footprints allowed)
		)
		(placement
			(enabled no)
			(sheetname "")
		)
		(fill
			(thermal_gap 0.5)
			(thermal_bridge_width 0.5)
			(island_removal_mode 0)
		)
		(polygon
			(pts
				(arc
					(start 304.017426 -286.832294)
					(mid 304.013706 -286.841274)
					(end 304.004726 -286.844994)
				)
				(arc
					(start 302.531526 -286.844994)
					(mid 302.522546 -286.841274)
					(end 302.518826 -286.832294)
				)
				(arc
					(start 302.518826 -286.337756)
					(mid 302.522546 -286.328776)
					(end 302.531526 -286.325056)
				)
				(arc
					(start 304.004726 -286.325056)
					(mid 304.013706 -286.328776)
					(end 304.017426 -286.337756)
				)
			)
		)
	)
	(zone
		(layer "In1.Cu")
		(hatch none 0.5)
		(connect_pads
			(clearance 0)
		)
		(min_thickness 0.25)
		(keepout
			(tracks not_allowed)
			(vias allowed)
			(pads allowed)
			(copperpour not_allowed)
			(footprints allowed)
		)
		(placement
			(enabled no)
			(sheetname "")
		)
		(fill
			(thermal_gap 0.5)
			(thermal_bridge_width 0.5)
			(island_removal_mode 0)
		)
		(polygon
			(pts
				(arc
					(start 132.090922 -383.440686)
					(mid 132.217922 -383.567686)
					(end 132.344922 -383.440686)
				)
				(arc
					(start 132.344922 -383.364486)
					(mid 132.217922 -383.237486)
					(end 132.090922 -383.364486)
				)
			)
		)
	)
	(zone
		(layer "In1.Cu")
		(hatch none 0.5)
		(connect_pads
			(clearance 0)
		)
		(min_thickness 0.25)
		(keepout
			(tracks not_allowed)
			(vias allowed)
			(pads allowed)
			(copperpour not_allowed)
			(footprints allowed)
		)
		(placement
			(enabled no)
			(sheetname "")
		)
		(fill
			(thermal_gap 0.5)
			(thermal_bridge_width 0.5)
			(island_removal_mode 0)
		)
		(polygon
			(pts
				(arc
					(start 48.533304 -316.582552)
					(mid 48.529584 -316.591532)
					(end 48.520604 -316.595252)
				)
				(arc
					(start 47.047404 -316.595252)
					(mid 47.038424 -316.591532)
					(end 47.034704 -316.582552)
				)
				(arc
					(start 47.034704 -316.088014)
					(mid 47.038424 -316.079034)
					(end 47.047404 -316.075314)
				)
				(arc
					(start 48.520604 -316.075314)
					(mid 48.529584 -316.079034)
					(end 48.533304 -316.088014)
				)
			)
		)
	)
	(zone
		(layer "In1.Cu")
		(hatch none 0.5)
		(connect_pads
			(clearance 0)
		)
		(min_thickness 0.25)
		(keepout
			(tracks not_allowed)
			(vias allowed)
			(pads allowed)
			(copperpour not_allowed)
			(footprints allowed)
		)
		(placement
			(enabled no)
			(sheetname "")
		)
		(fill
			(thermal_gap 0.5)
			(thermal_bridge_width 0.5)
			(island_removal_mode 0)
		)
		(polygon
			(pts
				(arc
					(start 343.298018 -392.30427)
					(mid 342.993218 -392.30427)
					(end 343.298018 -392.30427)
				)
			)
		)
	)
	(zone
		(layer "In1.Cu")
		(hatch none 0.5)
		(connect_pads
			(clearance 0)
		)
		(min_thickness 0.25)
		(keepout
			(tracks not_allowed)
			(vias allowed)
			(pads allowed)
			(copperpour not_allowed)
			(footprints allowed)
		)
		(placement
			(enabled no)
			(sheetname "")
		)
		(fill
			(thermal_gap 0.5)
			(thermal_bridge_width 0.5)
			(island_removal_mode 0)
		)
		(polygon
			(pts
				(arc
					(start 376.56135 -393.69238)
					(mid 376.18035 -393.69238)
					(end 376.56135 -393.69238)
				)
			)
		)
	)
	(zone
		(layer "In1.Cu")
		(hatch none 0.5)
		(connect_pads
			(clearance 0)
		)
		(min_thickness 0.25)
		(keepout
			(tracks not_allowed)
			(vias allowed)
			(pads allowed)
			(copperpour not_allowed)
			(footprints allowed)
		)
		(placement
			(enabled no)
			(sheetname "")
		)
		(fill
			(thermal_gap 0.5)
			(thermal_bridge_width 0.5)
			(island_removal_mode 0)
		)
		(polygon
			(pts
				(arc
					(start 450.8373 -263.882124)
					(mid 450.83358 -263.891104)
					(end 450.8246 -263.894824)
				)
				(arc
					(start 449.3514 -263.894824)
					(mid 449.34242 -263.891104)
					(end 449.3387 -263.882124)
				)
				(arc
					(start 449.3387 -263.387586)
					(mid 449.34242 -263.378606)
					(end 449.3514 -263.374886)
				)
				(arc
					(start 450.8246 -263.374886)
					(mid 450.83358 -263.378606)
					(end 450.8373 -263.387586)
				)
			)
		)
	)
	(zone
		(layer "In1.Cu")
		(hatch none 0.5)
		(connect_pads
			(clearance 0)
		)
		(min_thickness 0.25)
		(keepout
			(tracks not_allowed)
			(vias allowed)
			(pads allowed)
			(copperpour not_allowed)
			(footprints allowed)
		)
		(placement
			(enabled no)
			(sheetname "")
		)
		(fill
			(thermal_gap 0.5)
			(thermal_bridge_width 0.5)
			(island_removal_mode 0)
		)
		(polygon
			(pts
				(arc
					(start 270.397478 -270.682212)
					(mid 270.393758 -270.691192)
					(end 270.384778 -270.694912)
				)
				(arc
					(start 268.911578 -270.694912)
					(mid 268.902598 -270.691192)
					(end 268.898878 -270.682212)
				)
				(arc
					(start 268.898878 -270.187674)
					(mid 268.902598 -270.178694)
					(end 268.911578 -270.174974)
				)
				(arc
					(start 270.384778 -270.174974)
					(mid 270.393758 -270.178694)
					(end 270.397478 -270.187674)
				)
			)
		)
	)
	(zone
		(layer "In1.Cu")
		(hatch none 0.5)
		(connect_pads
			(clearance 0)
		)
		(min_thickness 0.25)
		(keepout
			(tracks not_allowed)
			(vias allowed)
			(pads allowed)
			(copperpour not_allowed)
			(footprints allowed)
		)
		(placement
			(enabled no)
			(sheetname "")
		)
		(fill
			(thermal_gap 0.5)
			(thermal_bridge_width 0.5)
			(island_removal_mode 0)
		)
		(polygon
			(pts
				(arc
					(start 184.365392 -266.432538)
					(mid 184.361672 -266.441518)
					(end 184.352692 -266.445238)
				)
				(arc
					(start 182.879492 -266.445238)
					(mid 182.870512 -266.441518)
					(end 182.866792 -266.432538)
				)
				(arc
					(start 182.866792 -265.938)
					(mid 182.870512 -265.92902)
					(end 182.879492 -265.9253)
				)
				(arc
					(start 184.352692 -265.9253)
					(mid 184.361672 -265.92902)
					(end 184.365392 -265.938)
				)
			)
		)
	)
	(zone
		(layer "In1.Cu")
		(hatch none 0.5)
		(connect_pads
			(clearance 0)
		)
		(min_thickness 0.25)
		(keepout
			(tracks not_allowed)
			(vias allowed)
			(pads allowed)
			(copperpour not_allowed)
			(footprints allowed)
		)
		(placement
			(enabled no)
			(sheetname "")
		)
		(fill
			(thermal_gap 0.5)
			(thermal_bridge_width 0.5)
			(island_removal_mode 0)
		)
		(polygon
			(pts
				(arc
					(start 172.72127 -290.232592)
					(mid 172.71755 -290.241572)
					(end 172.70857 -290.245292)
				)
				(arc
					(start 171.23537 -290.245292)
					(mid 171.22639 -290.241572)
					(end 171.22267 -290.232592)
				)
				(arc
					(start 171.22267 -289.738054)
					(mid 171.22639 -289.729074)
					(end 171.23537 -289.725354)
				)
				(arc
					(start 172.70857 -289.725354)
					(mid 172.71755 -289.729074)
					(end 172.72127 -289.738054)
				)
			)
		)
	)
	(zone
		(layer "In1.Cu")
		(hatch none 0.5)
		(connect_pads
			(clearance 0)
		)
		(min_thickness 0.25)
		(keepout
			(tracks not_allowed)
			(vias allowed)
			(pads allowed)
			(copperpour not_allowed)
			(footprints allowed)
		)
		(placement
			(enabled no)
			(sheetname "")
		)
		(fill
			(thermal_gap 0.5)
			(thermal_bridge_width 0.5)
			(island_removal_mode 0)
		)
		(polygon
			(pts
				(arc
					(start 15.315692 -16.443198)
					(mid 15.33801 -16.49708)
					(end 15.391892 -16.519398)
				)
				(arc
					(start 15.587472 -16.519398)
					(mid 15.609348 -16.516266)
					(end 15.629382 -16.506952)
				)
				(arc
					(start 15.923006 -16.31442)
					(mid 15.964662 -16.302018)
					(end 16.006318 -16.31442)
				)
				(arc
					(start 16.301212 -16.506952)
					(mid 16.321136 -16.516188)
					(end 16.342868 -16.519398)
				)
				(arc
					(start 16.537432 -16.519398)
					(mid 16.591314 -16.49708)
					(end 16.613632 -16.443198)
				)
				(arc
					(start 16.613632 -15.757398)
					(mid 16.591314 -15.703516)
					(end 16.537432 -15.681198)
				)
				(arc
					(start 16.342868 -15.681198)
					(mid 16.321124 -15.684366)
					(end 16.301212 -15.693644)
				)
				(arc
					(start 16.005048 -15.88643)
					(mid 15.963364 -15.898652)
					(end 15.921736 -15.886176)
				)
				(arc
					(start 15.628112 -15.693644)
					(mid 15.608188 -15.684408)
					(end 15.586456 -15.681198)
				)
				(arc
					(start 15.391892 -15.681198)
					(mid 15.33801 -15.703516)
					(end 15.315692 -15.757398)
				)
			)
		)
	)
	(zone
		(layer "In1.Cu")
		(hatch none 0.5)
		(connect_pads
			(clearance 0)
		)
		(min_thickness 0.25)
		(keepout
			(tracks not_allowed)
			(vias allowed)
			(pads allowed)
			(copperpour not_allowed)
			(footprints allowed)
		)
		(placement
			(enabled no)
			(sheetname "")
		)
		(fill
			(thermal_gap 0.5)
			(thermal_bridge_width 0.5)
			(island_removal_mode 0)
		)
		(polygon
			(pts
				(arc
					(start 176.821338 -222.232474)
					(mid 176.817618 -222.241454)
					(end 176.808638 -222.245174)
				)
				(arc
					(start 175.335438 -222.245174)
					(mid 175.326458 -222.241454)
					(end 175.322738 -222.232474)
				)
				(arc
					(start 175.322738 -221.737936)
					(mid 175.326458 -221.728956)
					(end 175.335438 -221.725236)
				)
				(arc
					(start 176.808638 -221.725236)
					(mid 176.817618 -221.728956)
					(end 176.821338 -221.737936)
				)
			)
		)
	)
	(zone
		(layer "In1.Cu")
		(hatch none 0.5)
		(connect_pads
			(clearance 0)
		)
		(min_thickness 0.25)
		(keepout
			(tracks not_allowed)
			(vias allowed)
			(pads allowed)
			(copperpour not_allowed)
			(footprints allowed)
		)
		(placement
			(enabled no)
			(sheetname "")
		)
		(fill
			(thermal_gap 0.5)
			(thermal_bridge_width 0.5)
			(island_removal_mode 0)
		)
		(polygon
			(pts
				(arc
					(start 191.909446 -264.732516)
					(mid 191.905726 -264.741496)
					(end 191.896746 -264.745216)
				)
				(arc
					(start 190.423546 -264.745216)
					(mid 190.414566 -264.741496)
					(end 190.410846 -264.732516)
				)
				(arc
					(start 190.410846 -264.237978)
					(mid 190.414566 -264.228998)
					(end 190.423546 -264.225278)
				)
				(arc
					(start 191.896746 -264.225278)
					(mid 191.905726 -264.228998)
					(end 191.909446 -264.237978)
				)
			)
		)
	)
	(zone
		(layer "In1.Cu")
		(hatch none 0.5)
		(connect_pads
			(clearance 0)
		)
		(min_thickness 0.25)
		(keepout
			(tracks not_allowed)
			(vias allowed)
			(pads allowed)
			(copperpour not_allowed)
			(footprints allowed)
		)
		(placement
			(enabled no)
			(sheetname "")
		)
		(fill
			(thermal_gap 0.5)
			(thermal_bridge_width 0.5)
			(island_removal_mode 0)
		)
		(polygon
			(pts
				(arc
					(start 270.397478 -216.28227)
					(mid 270.393758 -216.29125)
					(end 270.384778 -216.29497)
				)
				(arc
					(start 268.911578 -216.29497)
					(mid 268.902598 -216.29125)
					(end 268.898878 -216.28227)
				)
				(arc
					(start 268.898878 -215.787732)
					(mid 268.902598 -215.778752)
					(end 268.911578 -215.775032)
				)
				(arc
					(start 270.384778 -215.775032)
					(mid 270.393758 -215.778752)
					(end 270.397478 -215.787732)
				)
			)
		)
	)
	(zone
		(layer "In1.Cu")
		(hatch none 0.5)
		(connect_pads
			(clearance 0)
		)
		(min_thickness 0.25)
		(keepout
			(tracks not_allowed)
			(vias allowed)
			(pads allowed)
			(copperpour not_allowed)
			(footprints allowed)
		)
		(placement
			(enabled no)
			(sheetname "")
		)
		(fill
			(thermal_gap 0.5)
			(thermal_bridge_width 0.5)
			(island_removal_mode 0)
		)
		(polygon
			(pts
				(arc
					(start 48.533304 -291.93236)
					(mid 48.529584 -291.94134)
					(end 48.520604 -291.94506)
				)
				(arc
					(start 47.047404 -291.94506)
					(mid 47.038424 -291.94134)
					(end 47.034704 -291.93236)
				)
				(arc
					(start 47.034704 -291.437822)
					(mid 47.038424 -291.428842)
					(end 47.047404 -291.425122)
				)
				(arc
					(start 48.520604 -291.425122)
					(mid 48.529584 -291.428842)
					(end 48.533304 -291.437822)
				)
			)
		)
	)
	(zone
		(layer "In1.Cu")
		(hatch none 0.5)
		(connect_pads
			(clearance 0)
		)
		(min_thickness 0.25)
		(keepout
			(tracks not_allowed)
			(vias allowed)
			(pads allowed)
			(copperpour not_allowed)
			(footprints allowed)
		)
		(placement
			(enabled no)
			(sheetname "")
		)
		(fill
			(thermal_gap 0.5)
			(thermal_bridge_width 0.5)
			(island_removal_mode 0)
		)
		(polygon
			(pts
				(arc
					(start 308.117494 -314.032138)
					(mid 308.113774 -314.041118)
					(end 308.104794 -314.044838)
				)
				(arc
					(start 306.631594 -314.044838)
					(mid 306.622614 -314.041118)
					(end 306.618894 -314.032138)
				)
				(arc
					(start 306.618894 -313.5376)
					(mid 306.622614 -313.52862)
					(end 306.631594 -313.5249)
				)
				(arc
					(start 308.104794 -313.5249)
					(mid 308.113774 -313.52862)
					(end 308.117494 -313.5376)
				)
			)
		)
	)
	(zone
		(layer "In1.Cu")
		(hatch none 0.5)
		(connect_pads
			(clearance 0)
		)
		(min_thickness 0.25)
		(keepout
			(tracks not_allowed)
			(vias allowed)
			(pads allowed)
			(copperpour not_allowed)
			(footprints allowed)
		)
		(placement
			(enabled no)
			(sheetname "")
		)
		(fill
			(thermal_gap 0.5)
			(thermal_bridge_width 0.5)
			(island_removal_mode 0)
		)
		(polygon
			(pts
				(arc
					(start 60.177426 -225.632518)
					(mid 60.173706 -225.641498)
					(end 60.164726 -225.645218)
				)
				(arc
					(start 58.691526 -225.645218)
					(mid 58.682546 -225.641498)
					(end 58.678826 -225.632518)
				)
				(arc
					(start 58.678826 -225.13798)
					(mid 58.682546 -225.129)
					(end 58.691526 -225.12528)
				)
				(arc
					(start 60.164726 -225.12528)
					(mid 60.173706 -225.129)
					(end 60.177426 -225.13798)
				)
			)
		)
	)
	(zone
		(layer "In1.Cu")
		(hatch none 0.5)
		(connect_pads
			(clearance 0)
		)
		(min_thickness 0.25)
		(keepout
			(tracks not_allowed)
			(vias allowed)
			(pads allowed)
			(copperpour not_allowed)
			(footprints allowed)
		)
		(placement
			(enabled no)
			(sheetname "")
		)
		(fill
			(thermal_gap 0.5)
			(thermal_bridge_width 0.5)
			(island_removal_mode 0)
		)
		(polygon
			(pts
				(arc
					(start 191.909446 -231.582468)
					(mid 191.905726 -231.591448)
					(end 191.896746 -231.595168)
				)
				(arc
					(start 190.423546 -231.595168)
					(mid 190.414566 -231.591448)
					(end 190.410846 -231.582468)
				)
				(arc
					(start 190.410846 -231.08793)
					(mid 190.414566 -231.07895)
					(end 190.423546 -231.07523)
				)
				(arc
					(start 191.896746 -231.07523)
					(mid 191.905726 -231.07895)
					(end 191.909446 -231.08793)
				)
			)
		)
	)
	(zone
		(layer "In1.Cu")
		(hatch none 0.5)
		(connect_pads
			(clearance 0)
		)
		(min_thickness 0.25)
		(keepout
			(tracks not_allowed)
			(vias allowed)
			(pads allowed)
			(copperpour not_allowed)
			(footprints allowed)
		)
		(placement
			(enabled no)
			(sheetname "")
		)
		(fill
			(thermal_gap 0.5)
			(thermal_bridge_width 0.5)
			(island_removal_mode 0)
		)
		(polygon
			(pts
				(arc
					(start 187.809378 -202.682348)
					(mid 187.805658 -202.691328)
					(end 187.796678 -202.695048)
				)
				(arc
					(start 186.323478 -202.695048)
					(mid 186.314498 -202.691328)
					(end 186.310778 -202.682348)
				)
				(arc
					(start 186.310778 -202.18781)
					(mid 186.314498 -202.17883)
					(end 186.323478 -202.17511)
				)
				(arc
					(start 187.796678 -202.17511)
					(mid 187.805658 -202.17883)
					(end 187.809378 -202.18781)
				)
			)
		)
	)
	(zone
		(layer "In1.Cu")
		(hatch none 0.5)
		(connect_pads
			(clearance 0)
		)
		(min_thickness 0.25)
		(keepout
			(tracks not_allowed)
			(vias allowed)
			(pads allowed)
			(copperpour not_allowed)
			(footprints allowed)
		)
		(placement
			(enabled no)
			(sheetname "")
		)
		(fill
			(thermal_gap 0.5)
			(thermal_bridge_width 0.5)
			(island_removal_mode 0)
		)
		(polygon
			(pts
				(arc
					(start 169.277284 -208.632552)
					(mid 169.273564 -208.641532)
					(end 169.264584 -208.645252)
				)
				(arc
					(start 167.791384 -208.645252)
					(mid 167.782404 -208.641532)
					(end 167.778684 -208.632552)
				)
				(arc
					(start 167.778684 -208.138014)
					(mid 167.782404 -208.129034)
					(end 167.791384 -208.125314)
				)
				(arc
					(start 169.264584 -208.125314)
					(mid 169.273564 -208.129034)
					(end 169.277284 -208.138014)
				)
			)
		)
	)
	(zone
		(layer "In1.Cu")
		(hatch none 0.5)
		(connect_pads
			(clearance 0)
		)
		(min_thickness 0.25)
		(keepout
			(tracks not_allowed)
			(vias allowed)
			(pads allowed)
			(copperpour not_allowed)
			(footprints allowed)
		)
		(placement
			(enabled no)
			(sheetname "")
		)
		(fill
			(thermal_gap 0.5)
			(thermal_bridge_width 0.5)
			(island_removal_mode 0)
		)
		(polygon
			(pts
				(arc
					(start 169.277284 -283.432504)
					(mid 169.273564 -283.441484)
					(end 169.264584 -283.445204)
				)
				(arc
					(start 167.791384 -283.445204)
					(mid 167.782404 -283.441484)
					(end 167.778684 -283.432504)
				)
				(arc
					(start 167.778684 -282.937966)
					(mid 167.782404 -282.928986)
					(end 167.791384 -282.925266)
				)
				(arc
					(start 169.264584 -282.925266)
					(mid 169.273564 -282.928986)
					(end 169.277284 -282.937966)
				)
			)
		)
	)
	(zone
		(layer "In1.Cu")
		(hatch none 0.5)
		(connect_pads
			(clearance 0)
		)
		(min_thickness 0.25)
		(keepout
			(tracks not_allowed)
			(vias allowed)
			(pads allowed)
			(copperpour not_allowed)
			(footprints allowed)
		)
		(placement
			(enabled no)
			(sheetname "")
		)
		(fill
			(thermal_gap 0.5)
			(thermal_bridge_width 0.5)
			(island_removal_mode 0)
		)
		(polygon
			(pts
				(arc
					(start 206.9973 -281.732482)
					(mid 206.99358 -281.741462)
					(end 206.9846 -281.745182)
				)
				(arc
					(start 205.5114 -281.745182)
					(mid 205.50242 -281.741462)
					(end 205.4987 -281.732482)
				)
				(arc
					(start 205.4987 -281.237944)
					(mid 205.50242 -281.228964)
					(end 205.5114 -281.225244)
				)
				(arc
					(start 206.9846 -281.225244)
					(mid 206.99358 -281.228964)
					(end 206.9973 -281.237944)
				)
			)
		)
	)
	(zone
		(layer "In1.Cu")
		(hatch none 0.5)
		(connect_pads
			(clearance 0)
		)
		(min_thickness 0.25)
		(keepout
			(tracks not_allowed)
			(vias allowed)
			(pads allowed)
			(copperpour not_allowed)
			(footprints allowed)
		)
		(placement
			(enabled no)
			(sheetname "")
		)
		(fill
			(thermal_gap 0.5)
			(thermal_bridge_width 0.5)
			(island_removal_mode 0)
		)
		(polygon
			(pts
				(arc
					(start 405.598122 -392.30427)
					(mid 405.293322 -392.30427)
					(end 405.598122 -392.30427)
				)
			)
		)
	)
	(zone
		(layer "In1.Cu")
		(hatch none 0.5)
		(connect_pads
			(clearance 0)
		)
		(min_thickness 0.25)
		(keepout
			(tracks not_allowed)
			(vias allowed)
			(pads allowed)
			(copperpour not_allowed)
			(footprints allowed)
		)
		(placement
			(enabled no)
			(sheetname "")
		)
		(fill
			(thermal_gap 0.5)
			(thermal_bridge_width 0.5)
			(island_removal_mode 0)
		)
		(polygon
			(pts
				(arc
					(start 176.821338 -220.532452)
					(mid 176.817618 -220.541432)
					(end 176.808638 -220.545152)
				)
				(arc
					(start 175.335438 -220.545152)
					(mid 175.326458 -220.541432)
					(end 175.322738 -220.532452)
				)
				(arc
					(start 175.322738 -220.037914)
					(mid 175.326458 -220.028934)
					(end 175.335438 -220.025214)
				)
				(arc
					(start 176.808638 -220.025214)
					(mid 176.817618 -220.028934)
					(end 176.821338 -220.037914)
				)
			)
		)
	)
	(zone
		(layer "In1.Cu")
		(hatch none 0.5)
		(connect_pads
			(clearance 0)
		)
		(min_thickness 0.25)
		(keepout
			(tracks not_allowed)
			(vias allowed)
			(pads allowed)
			(copperpour not_allowed)
			(footprints allowed)
		)
		(placement
			(enabled no)
			(sheetname "")
		)
		(fill
			(thermal_gap 0.5)
			(thermal_bridge_width 0.5)
			(island_removal_mode 0)
		)
		(polygon
			(pts
				(arc
					(start 420.661338 -291.932106)
					(mid 420.657618 -291.941086)
					(end 420.648638 -291.944806)
				)
				(arc
					(start 419.175438 -291.944806)
					(mid 419.166458 -291.941086)
					(end 419.162738 -291.932106)
				)
				(arc
					(start 419.162738 -291.437568)
					(mid 419.166458 -291.428588)
					(end 419.175438 -291.424868)
				)
				(arc
					(start 420.648638 -291.424868)
					(mid 420.657618 -291.428588)
					(end 420.661338 -291.437568)
				)
			)
		)
	)
	(zone
		(layer "In1.Cu")
		(hatch none 0.5)
		(connect_pads
			(clearance 0)
		)
		(min_thickness 0.25)
		(keepout
			(tracks not_allowed)
			(vias allowed)
			(pads allowed)
			(copperpour not_allowed)
			(footprints allowed)
		)
		(placement
			(enabled no)
			(sheetname "")
		)
		(fill
			(thermal_gap 0.5)
			(thermal_bridge_width 0.5)
			(island_removal_mode 0)
		)
		(polygon
			(pts
				(arc
					(start 412.218632 -391.822686)
					(mid 412.345632 -391.949686)
					(end 412.472632 -391.822686)
				)
				(arc
					(start 412.472632 -391.746486)
					(mid 412.345632 -391.619486)
					(end 412.218632 -391.746486)
				)
			)
		)
	)
	(zone
		(layer "In1.Cu")
		(hatch none 0.5)
		(connect_pads
			(clearance 0)
		)
		(min_thickness 0.25)
		(keepout
			(tracks not_allowed)
			(vias allowed)
			(pads allowed)
			(copperpour not_allowed)
			(footprints allowed)
		)
		(placement
			(enabled no)
			(sheetname "")
		)
		(fill
			(thermal_gap 0.5)
			(thermal_bridge_width 0.5)
			(island_removal_mode 0)
		)
		(polygon
			(pts
				(arc
					(start 413.117284 -285.982156)
					(mid 413.113564 -285.991136)
					(end 413.104584 -285.994856)
				)
				(arc
					(start 411.631384 -285.994856)
					(mid 411.622404 -285.991136)
					(end 411.618684 -285.982156)
				)
				(arc
					(start 411.618684 -285.487618)
					(mid 411.622404 -285.478638)
					(end 411.631384 -285.474918)
				)
				(arc
					(start 413.104584 -285.474918)
					(mid 413.113564 -285.478638)
					(end 413.117284 -285.487618)
				)
			)
		)
	)
	(zone
		(layer "In1.Cu")
		(hatch none 0.5)
		(connect_pads
			(clearance 0)
		)
		(min_thickness 0.25)
		(keepout
			(tracks not_allowed)
			(vias allowed)
			(pads allowed)
			(copperpour not_allowed)
			(footprints allowed)
		)
		(placement
			(enabled no)
			(sheetname "")
		)
		(fill
			(thermal_gap 0.5)
			(thermal_bridge_width 0.5)
			(island_removal_mode 0)
		)
		(polygon
			(pts
				(arc
					(start 120.96115 -386.003292)
					(mid 120.58015 -386.003292)
					(end 120.96115 -386.003292)
				)
			)
		)
	)
	(zone
		(layer "In1.Cu")
		(hatch none 0.5)
		(connect_pads
			(clearance 0)
		)
		(min_thickness 0.25)
		(keepout
			(tracks not_allowed)
			(vias allowed)
			(pads allowed)
			(copperpour not_allowed)
			(footprints allowed)
		)
		(placement
			(enabled no)
			(sheetname "")
		)
		(fill
			(thermal_gap 0.5)
			(thermal_bridge_width 0.5)
			(island_removal_mode 0)
		)
		(polygon
			(pts
				(arc
					(start 45.089318 -219.682568)
					(mid 45.085598 -219.691548)
					(end 45.076618 -219.695268)
				)
				(arc
					(start 43.603418 -219.695268)
					(mid 43.594438 -219.691548)
					(end 43.590718 -219.682568)
				)
				(arc
					(start 43.590718 -219.18803)
					(mid 43.594438 -219.17905)
					(end 43.603418 -219.17533)
				)
				(arc
					(start 45.076618 -219.17533)
					(mid 45.085598 -219.17905)
					(end 45.089318 -219.18803)
				)
			)
		)
	)
	(zone
		(layer "In1.Cu")
		(hatch none 0.5)
		(connect_pads
			(clearance 0)
		)
		(min_thickness 0.25)
		(keepout
			(tracks not_allowed)
			(vias allowed)
			(pads allowed)
			(copperpour not_allowed)
			(footprints allowed)
		)
		(placement
			(enabled no)
			(sheetname "")
		)
		(fill
			(thermal_gap 0.5)
			(thermal_bridge_width 0.5)
			(island_removal_mode 0)
		)
		(polygon
			(pts
				(arc
					(start 424.761406 -249.432318)
					(mid 424.757686 -249.441298)
					(end 424.748706 -249.445018)
				)
				(arc
					(start 423.275506 -249.445018)
					(mid 423.266526 -249.441298)
					(end 423.262806 -249.432318)
				)
				(arc
					(start 423.262806 -248.93778)
					(mid 423.266526 -248.9288)
					(end 423.275506 -248.92508)
				)
				(arc
					(start 424.748706 -248.92508)
					(mid 424.757686 -248.9288)
					(end 424.761406 -248.93778)
				)
			)
		)
	)
	(zone
		(layer "In1.Cu")
		(hatch none 0.5)
		(connect_pads
			(clearance 0)
		)
		(min_thickness 0.25)
		(keepout
			(tracks not_allowed)
			(vias allowed)
			(pads allowed)
			(copperpour not_allowed)
			(footprints allowed)
		)
		(placement
			(enabled no)
			(sheetname "")
		)
		(fill
			(thermal_gap 0.5)
			(thermal_bridge_width 0.5)
			(island_removal_mode 0)
		)
		(polygon
			(pts
				(arc
					(start 321.46113 -397.156432)
					(mid 321.08013 -397.156432)
					(end 321.46113 -397.156432)
				)
			)
		)
	)
	(zone
		(layer "In1.Cu")
		(hatch none 0.5)
		(connect_pads
			(clearance 0)
		)
		(min_thickness 0.25)
		(keepout
			(tracks not_allowed)
			(vias allowed)
			(pads allowed)
			(copperpour not_allowed)
			(footprints allowed)
		)
		(placement
			(enabled no)
			(sheetname "")
		)
		(fill
			(thermal_gap 0.5)
			(thermal_bridge_width 0.5)
			(island_removal_mode 0)
		)
		(polygon
			(pts
				(arc
					(start 123.360942 -389.467344)
					(mid 122.979942 -389.467344)
					(end 123.360942 -389.467344)
				)
			)
		)
	)
	(zone
		(layer "In1.Cu")
		(hatch none 0.5)
		(connect_pads
			(clearance 0)
		)
		(min_thickness 0.25)
		(keepout
			(tracks not_allowed)
			(vias allowed)
			(pads allowed)
			(copperpour not_allowed)
			(footprints allowed)
		)
		(placement
			(enabled no)
			(sheetname "")
		)
		(fill
			(thermal_gap 0.5)
			(thermal_bridge_width 0.5)
			(island_removal_mode 0)
		)
		(polygon
			(pts
				(arc
					(start 273.841464 -211.182204)
					(mid 273.837744 -211.191184)
					(end 273.828764 -211.194904)
				)
				(arc
					(start 272.355564 -211.194904)
					(mid 272.346584 -211.191184)
					(end 272.342864 -211.182204)
				)
				(arc
					(start 272.342864 -210.687666)
					(mid 272.346584 -210.678686)
					(end 272.355564 -210.674966)
				)
				(arc
					(start 273.828764 -210.674966)
					(mid 273.837744 -210.678686)
					(end 273.841464 -210.687666)
				)
			)
		)
	)
	(zone
		(layer "In1.Cu")
		(hatch none 0.5)
		(connect_pads
			(clearance 0)
		)
		(min_thickness 0.25)
		(keepout
			(tracks not_allowed)
			(vias allowed)
			(pads allowed)
			(copperpour not_allowed)
			(footprints allowed)
		)
		(placement
			(enabled no)
			(sheetname "")
		)
		(fill
			(thermal_gap 0.5)
			(thermal_bridge_width 0.5)
			(island_removal_mode 0)
		)
		(polygon
			(pts
				(arc
					(start 180.265324 -262.182356)
					(mid 180.261604 -262.191336)
					(end 180.252624 -262.195056)
				)
				(arc
					(start 178.779424 -262.195056)
					(mid 178.770444 -262.191336)
					(end 178.766724 -262.182356)
				)
				(arc
					(start 178.766724 -261.687818)
					(mid 178.770444 -261.678838)
					(end 178.779424 -261.675118)
				)
				(arc
					(start 180.252624 -261.675118)
					(mid 180.261604 -261.678838)
					(end 180.265324 -261.687818)
				)
			)
		)
	)
	(zone
		(layer "In1.Cu")
		(hatch none 0.5)
		(connect_pads
			(clearance 0)
		)
		(min_thickness 0.25)
		(keepout
			(tracks not_allowed)
			(vias allowed)
			(pads allowed)
			(copperpour not_allowed)
			(footprints allowed)
		)
		(placement
			(enabled no)
			(sheetname "")
		)
		(fill
			(thermal_gap 0.5)
			(thermal_bridge_width 0.5)
			(island_removal_mode 0)
		)
		(polygon
			(pts
				(arc
					(start 266.29741 -235.832142)
					(mid 266.29369 -235.841122)
					(end 266.28471 -235.844842)
				)
				(arc
					(start 264.81151 -235.844842)
					(mid 264.80253 -235.841122)
					(end 264.79881 -235.832142)
				)
				(arc
					(start 264.79881 -235.337604)
					(mid 264.80253 -235.328624)
					(end 264.81151 -235.324904)
				)
				(arc
					(start 266.28471 -235.324904)
					(mid 266.29369 -235.328624)
					(end 266.29741 -235.337604)
				)
			)
		)
	)
	(zone
		(layer "In1.Cu")
		(hatch none 0.5)
		(connect_pads
			(clearance 0)
		)
		(min_thickness 0.25)
		(keepout
			(tracks not_allowed)
			(vias allowed)
			(pads allowed)
			(copperpour not_allowed)
			(footprints allowed)
		)
		(placement
			(enabled no)
			(sheetname "")
		)
		(fill
			(thermal_gap 0.5)
			(thermal_bridge_width 0.5)
			(island_removal_mode 0)
		)
		(polygon
			(pts
				(arc
					(start 56.077358 -274.932394)
					(mid 56.073638 -274.941374)
					(end 56.064658 -274.945094)
				)
				(arc
					(start 54.591458 -274.945094)
					(mid 54.582478 -274.941374)
					(end 54.578758 -274.932394)
				)
				(arc
					(start 54.578758 -274.437856)
					(mid 54.582478 -274.428876)
					(end 54.591458 -274.425156)
				)
				(arc
					(start 56.064658 -274.425156)
					(mid 56.073638 -274.428876)
					(end 56.077358 -274.437856)
				)
			)
		)
	)
	(zone
		(layer "In1.Cu")
		(hatch none 0.5)
		(connect_pads
			(clearance 0)
		)
		(min_thickness 0.25)
		(keepout
			(tracks not_allowed)
			(vias allowed)
			(pads allowed)
			(copperpour not_allowed)
			(footprints allowed)
		)
		(placement
			(enabled no)
			(sheetname "")
		)
		(fill
			(thermal_gap 0.5)
			(thermal_bridge_width 0.5)
			(island_removal_mode 0)
		)
		(polygon
			(pts
				(arc
					(start 206.5782 -292.535356)
					(mid 205.9178 -292.535356)
					(end 206.5782 -292.535356)
				)
			)
		)
	)
	(zone
		(layer "In1.Cu")
		(hatch none 0.5)
		(connect_pads
			(clearance 0)
		)
		(min_thickness 0.25)
		(keepout
			(tracks not_allowed)
			(vias allowed)
			(pads allowed)
			(copperpour not_allowed)
			(footprints allowed)
		)
		(placement
			(enabled no)
			(sheetname "")
		)
		(fill
			(thermal_gap 0.5)
			(thermal_bridge_width 0.5)
			(island_removal_mode 0)
		)
		(polygon
			(pts
				(arc
					(start 439.849514 -313.182254)
					(mid 439.845794 -313.191234)
					(end 439.836814 -313.194954)
				)
				(arc
					(start 438.363614 -313.194954)
					(mid 438.354634 -313.191234)
					(end 438.350914 -313.182254)
				)
				(arc
					(start 438.350914 -312.687716)
					(mid 438.354634 -312.678736)
					(end 438.363614 -312.675016)
				)
				(arc
					(start 439.836814 -312.675016)
					(mid 439.845794 -312.678736)
					(end 439.849514 -312.687716)
				)
			)
		)
	)
	(zone
		(layer "In1.Cu")
		(hatch none 0.5)
		(connect_pads
			(clearance 0)
		)
		(min_thickness 0.25)
		(keepout
			(tracks not_allowed)
			(vias allowed)
			(pads allowed)
			(copperpour not_allowed)
			(footprints allowed)
		)
		(placement
			(enabled no)
			(sheetname "")
		)
		(fill
			(thermal_gap 0.5)
			(thermal_bridge_width 0.5)
			(island_removal_mode 0)
		)
		(polygon
			(pts
				(arc
					(start 37.545264 -242.632484)
					(mid 37.541544 -242.641464)
					(end 37.532564 -242.645184)
				)
				(arc
					(start 36.059364 -242.645184)
					(mid 36.050384 -242.641464)
					(end 36.046664 -242.632484)
				)
				(arc
					(start 36.046664 -242.137946)
					(mid 36.050384 -242.128966)
					(end 36.059364 -242.125246)
				)
				(arc
					(start 37.532564 -242.125246)
					(mid 37.541544 -242.128966)
					(end 37.545264 -242.137946)
				)
			)
		)
	)
	(zone
		(layer "In1.Cu")
		(hatch none 0.5)
		(connect_pads
			(clearance 0)
		)
		(min_thickness 0.25)
		(keepout
			(tracks not_allowed)
			(vias allowed)
			(pads allowed)
			(copperpour not_allowed)
			(footprints allowed)
		)
		(placement
			(enabled no)
			(sheetname "")
		)
		(fill
			(thermal_gap 0.5)
			(thermal_bridge_width 0.5)
			(island_removal_mode 0)
		)
		(polygon
			(pts
				(arc
					(start 304.017426 -273.232118)
					(mid 304.013706 -273.241098)
					(end 304.004726 -273.244818)
				)
				(arc
					(start 302.531526 -273.244818)
					(mid 302.522546 -273.241098)
					(end 302.518826 -273.232118)
				)
				(arc
					(start 302.518826 -272.73758)
					(mid 302.522546 -272.7286)
					(end 302.531526 -272.72488)
				)
				(arc
					(start 304.004726 -272.72488)
					(mid 304.013706 -272.7286)
					(end 304.017426 -272.73758)
				)
			)
		)
	)
	(zone
		(layer "In1.Cu")
		(hatch none 0.5)
		(connect_pads
			(clearance 0)
		)
		(min_thickness 0.25)
		(keepout
			(tracks not_allowed)
			(vias allowed)
			(pads allowed)
			(copperpour not_allowed)
			(footprints allowed)
		)
		(placement
			(enabled no)
			(sheetname "")
		)
		(fill
			(thermal_gap 0.5)
			(thermal_bridge_width 0.5)
			(island_removal_mode 0)
		)
		(polygon
			(pts
				(arc
					(start 300.57344 -199.282304)
					(mid 300.56972 -199.291284)
					(end 300.56074 -199.295004)
				)
				(arc
					(start 299.08754 -199.295004)
					(mid 299.07856 -199.291284)
					(end 299.07484 -199.282304)
				)
				(arc
					(start 299.07484 -198.787766)
					(mid 299.07856 -198.778786)
					(end 299.08754 -198.775066)
				)
				(arc
					(start 300.56074 -198.775066)
					(mid 300.56972 -198.778786)
					(end 300.57344 -198.787766)
				)
			)
		)
	)
	(zone
		(layer "In1.Cu")
		(hatch none 0.5)
		(connect_pads
			(clearance 0)
		)
		(min_thickness 0.25)
		(keepout
			(tracks not_allowed)
			(vias allowed)
			(pads allowed)
			(copperpour not_allowed)
			(footprints allowed)
		)
		(placement
			(enabled no)
			(sheetname "")
		)
		(fill
			(thermal_gap 0.5)
			(thermal_bridge_width 0.5)
			(island_removal_mode 0)
		)
		(polygon
			(pts
				(arc
					(start 308.117494 -225.632264)
					(mid 308.113774 -225.641244)
					(end 308.104794 -225.644964)
				)
				(arc
					(start 306.631594 -225.644964)
					(mid 306.622614 -225.641244)
					(end 306.618894 -225.632264)
				)
				(arc
					(start 306.618894 -225.137726)
					(mid 306.622614 -225.128746)
					(end 306.631594 -225.125026)
				)
				(arc
					(start 308.104794 -225.125026)
					(mid 308.113774 -225.128746)
					(end 308.117494 -225.137726)
				)
			)
		)
	)
	(zone
		(layer "In1.Cu")
		(hatch none 0.5)
		(connect_pads
			(clearance 0)
		)
		(min_thickness 0.25)
		(keepout
			(tracks not_allowed)
			(vias allowed)
			(pads allowed)
			(copperpour not_allowed)
			(footprints allowed)
		)
		(placement
			(enabled no)
			(sheetname "")
		)
		(fill
			(thermal_gap 0.5)
			(thermal_bridge_width 0.5)
			(island_removal_mode 0)
		)
		(polygon
			(pts
				(arc
					(start 432.30546 -249.432318)
					(mid 432.30174 -249.441298)
					(end 432.29276 -249.445018)
				)
				(arc
					(start 430.81956 -249.445018)
					(mid 430.81058 -249.441298)
					(end 430.80686 -249.432318)
				)
				(arc
					(start 430.80686 -248.93778)
					(mid 430.81058 -248.9288)
					(end 430.81956 -248.92508)
				)
				(arc
					(start 432.29276 -248.92508)
					(mid 432.30174 -248.9288)
					(end 432.30546 -248.93778)
				)
			)
		)
	)
	(zone
		(layer "In1.Cu")
		(hatch none 0.5)
		(connect_pads
			(clearance 0)
		)
		(min_thickness 0.25)
		(keepout
			(tracks not_allowed)
			(vias allowed)
			(pads allowed)
			(copperpour not_allowed)
			(footprints allowed)
		)
		(placement
			(enabled no)
			(sheetname "")
		)
		(fill
			(thermal_gap 0.5)
			(thermal_bridge_width 0.5)
			(island_removal_mode 0)
		)
		(polygon
			(pts
				(arc
					(start 454.937368 -291.082222)
					(mid 454.933648 -291.091202)
					(end 454.924668 -291.094922)
				)
				(arc
					(start 453.451468 -291.094922)
					(mid 453.442488 -291.091202)
					(end 453.438768 -291.082222)
				)
				(arc
					(start 453.438768 -290.587684)
					(mid 453.442488 -290.578704)
					(end 453.451468 -290.574984)
				)
				(arc
					(start 454.924668 -290.574984)
					(mid 454.933648 -290.578704)
					(end 454.937368 -290.587684)
				)
			)
		)
	)
	(zone
		(layer "In1.Cu")
		(hatch none 0.5)
		(connect_pads
			(clearance 0)
		)
		(min_thickness 0.25)
		(keepout
			(tracks not_allowed)
			(vias allowed)
			(pads allowed)
			(copperpour not_allowed)
			(footprints allowed)
		)
		(placement
			(enabled no)
			(sheetname "")
		)
		(fill
			(thermal_gap 0.5)
			(thermal_bridge_width 0.5)
			(island_removal_mode 0)
		)
		(polygon
			(pts
				(arc
					(start 48.533304 -239.23244)
					(mid 48.529584 -239.24142)
					(end 48.520604 -239.24514)
				)
				(arc
					(start 47.047404 -239.24514)
					(mid 47.038424 -239.24142)
					(end 47.034704 -239.23244)
				)
				(arc
					(start 47.034704 -238.737902)
					(mid 47.038424 -238.728922)
					(end 47.047404 -238.725202)
				)
				(arc
					(start 48.520604 -238.725202)
					(mid 48.529584 -238.728922)
					(end 48.533304 -238.737902)
				)
			)
		)
	)
	(zone
		(layer "In1.Cu")
		(hatch none 0.5)
		(connect_pads
			(clearance 0)
		)
		(min_thickness 0.25)
		(keepout
			(tracks not_allowed)
			(vias allowed)
			(pads allowed)
			(copperpour not_allowed)
			(footprints allowed)
		)
		(placement
			(enabled no)
			(sheetname "")
		)
		(fill
			(thermal_gap 0.5)
			(thermal_bridge_width 0.5)
			(island_removal_mode 0)
		)
		(polygon
			(pts
				(arc
					(start 30.001464 -203.532486)
					(mid 29.997744 -203.541466)
					(end 29.988764 -203.545186)
				)
				(arc
					(start 28.515564 -203.545186)
					(mid 28.506584 -203.541466)
					(end 28.502864 -203.532486)
				)
				(arc
					(start 28.502864 -203.037948)
					(mid 28.506584 -203.028968)
					(end 28.515564 -203.025248)
				)
				(arc
					(start 29.988764 -203.025248)
					(mid 29.997744 -203.028968)
					(end 30.001464 -203.037948)
				)
			)
		)
	)
	(zone
		(layer "In1.Cu")
		(hatch none 0.5)
		(connect_pads
			(clearance 0)
		)
		(min_thickness 0.25)
		(keepout
			(tracks not_allowed)
			(vias allowed)
			(pads allowed)
			(copperpour not_allowed)
			(footprints allowed)
		)
		(placement
			(enabled no)
			(sheetname "")
		)
		(fill
			(thermal_gap 0.5)
			(thermal_bridge_width 0.5)
			(island_removal_mode 0)
		)
		(polygon
			(pts
				(arc
					(start 165.177216 -301.282354)
					(mid 165.173496 -301.291334)
					(end 165.164516 -301.295054)
				)
				(arc
					(start 163.691316 -301.295054)
					(mid 163.682336 -301.291334)
					(end 163.678616 -301.282354)
				)
				(arc
					(start 163.678616 -300.787816)
					(mid 163.682336 -300.778836)
					(end 163.691316 -300.775116)
				)
				(arc
					(start 165.164516 -300.775116)
					(mid 165.173496 -300.778836)
					(end 165.177216 -300.787816)
				)
			)
		)
	)
	(zone
		(layer "In1.Cu")
		(hatch none 0.5)
		(connect_pads
			(clearance 0)
		)
		(min_thickness 0.25)
		(keepout
			(tracks not_allowed)
			(vias allowed)
			(pads allowed)
			(copperpour not_allowed)
			(footprints allowed)
		)
		(placement
			(enabled no)
			(sheetname "")
		)
		(fill
			(thermal_gap 0.5)
			(thermal_bridge_width 0.5)
			(island_removal_mode 0)
		)
		(polygon
			(pts
				(arc
					(start 288.929318 -304.682144)
					(mid 288.925598 -304.691124)
					(end 288.916618 -304.694844)
				)
				(arc
					(start 287.443418 -304.694844)
					(mid 287.434438 -304.691124)
					(end 287.430718 -304.682144)
				)
				(arc
					(start 287.430718 -304.187606)
					(mid 287.434438 -304.178626)
					(end 287.443418 -304.174906)
				)
				(arc
					(start 288.916618 -304.174906)
					(mid 288.925598 -304.178626)
					(end 288.929318 -304.187606)
				)
			)
		)
	)
	(zone
		(layer "In1.Cu")
		(hatch none 0.5)
		(connect_pads
			(clearance 0)
		)
		(min_thickness 0.25)
		(keepout
			(tracks not_allowed)
			(vias allowed)
			(pads allowed)
			(copperpour not_allowed)
			(footprints allowed)
		)
		(placement
			(enabled no)
			(sheetname "")
		)
		(fill
			(thermal_gap 0.5)
			(thermal_bridge_width 0.5)
			(island_removal_mode 0)
		)
		(polygon
			(pts
				(arc
					(start 440.436254 5.598668)
					(mid 440.413936 5.544786)
					(end 440.360054 5.522468)
				)
				(arc
					(start 439.747914 5.522468)
					(mid 439.694032 5.544786)
					(end 439.671714 5.598668)
				)
				(arc
					(start 439.671714 6.695948)
					(mid 439.694032 6.74983)
					(end 439.747914 6.772148)
				)
				(arc
					(start 440.360054 6.772148)
					(mid 440.413936 6.74983)
					(end 440.436254 6.695948)
				)
			)
		)
	)
	(zone
		(layer "In1.Cu")
		(hatch none 0.5)
		(connect_pads
			(clearance 0)
		)
		(min_thickness 0.25)
		(keepout
			(tracks not_allowed)
			(vias allowed)
			(pads allowed)
			(copperpour not_allowed)
			(footprints allowed)
		)
		(placement
			(enabled no)
			(sheetname "")
		)
		(fill
			(thermal_gap 0.5)
			(thermal_bridge_width 0.5)
			(island_removal_mode 0)
		)
		(polygon
			(pts
				(arc
					(start 18.357342 -307.232558)
					(mid 18.353622 -307.241538)
					(end 18.344642 -307.245258)
				)
				(arc
					(start 16.871442 -307.245258)
					(mid 16.862462 -307.241538)
					(end 16.858742 -307.232558)
				)
				(arc
					(start 16.858742 -306.73802)
					(mid 16.862462 -306.72904)
					(end 16.871442 -306.72532)
				)
				(arc
					(start 18.344642 -306.72532)
					(mid 18.353622 -306.72904)
					(end 18.357342 -306.73802)
				)
			)
		)
	)
	(zone
		(layer "In1.Cu")
		(hatch none 0.5)
		(connect_pads
			(clearance 0)
		)
		(min_thickness 0.25)
		(keepout
			(tracks not_allowed)
			(vias allowed)
			(pads allowed)
			(copperpour not_allowed)
			(footprints allowed)
		)
		(placement
			(enabled no)
			(sheetname "")
		)
		(fill
			(thermal_gap 0.5)
			(thermal_bridge_width 0.5)
			(island_removal_mode 0)
		)
		(polygon
			(pts
				(arc
					(start 199.4535 -233.28249)
					(mid 199.44978 -233.29147)
					(end 199.4408 -233.29519)
				)
				(arc
					(start 197.9676 -233.29519)
					(mid 197.95862 -233.29147)
					(end 197.9549 -233.28249)
				)
				(arc
					(start 197.9549 -232.787952)
					(mid 197.95862 -232.778972)
					(end 197.9676 -232.775252)
				)
				(arc
					(start 199.4408 -232.775252)
					(mid 199.44978 -232.778972)
					(end 199.4535 -232.787952)
				)
			)
		)
	)
	(zone
		(layer "In1.Cu")
		(hatch none 0.5)
		(connect_pads
			(clearance 0)
		)
		(min_thickness 0.25)
		(keepout
			(tracks not_allowed)
			(vias allowed)
			(pads allowed)
			(copperpour not_allowed)
			(footprints allowed)
		)
		(placement
			(enabled no)
			(sheetname "")
		)
		(fill
			(thermal_gap 0.5)
			(thermal_bridge_width 0.5)
			(island_removal_mode 0)
		)
		(polygon
			(pts
				(arc
					(start 187.809378 -290.232592)
					(mid 187.805658 -290.241572)
					(end 187.796678 -290.245292)
				)
				(arc
					(start 186.323478 -290.245292)
					(mid 186.314498 -290.241572)
					(end 186.310778 -290.232592)
				)
				(arc
					(start 186.310778 -289.738054)
					(mid 186.314498 -289.729074)
					(end 186.323478 -289.725354)
				)
				(arc
					(start 187.796678 -289.725354)
					(mid 187.805658 -289.729074)
					(end 187.809378 -289.738054)
				)
			)
		)
	)
	(zone
		(layer "In1.Cu")
		(hatch none 0.5)
		(connect_pads
			(clearance 0)
		)
		(min_thickness 0.25)
		(keepout
			(tracks not_allowed)
			(vias allowed)
			(pads allowed)
			(copperpour not_allowed)
			(footprints allowed)
		)
		(placement
			(enabled no)
			(sheetname "")
		)
		(fill
			(thermal_gap 0.5)
			(thermal_bridge_width 0.5)
			(island_removal_mode 0)
		)
		(polygon
			(pts
				(arc
					(start 114.561366 -388.774432)
					(mid 114.180366 -388.774432)
					(end 114.561366 -388.774432)
				)
			)
		)
	)
	(zone
		(layer "In1.Cu")
		(hatch none 0.5)
		(connect_pads
			(clearance 0)
		)
		(min_thickness 0.25)
		(keepout
			(tracks not_allowed)
			(vias allowed)
			(pads allowed)
			(copperpour not_allowed)
			(footprints allowed)
		)
		(placement
			(enabled no)
			(sheetname "")
		)
		(fill
			(thermal_gap 0.5)
			(thermal_bridge_width 0.5)
			(island_removal_mode 0)
		)
		(polygon
			(pts
				(arc
					(start 169.277284 -231.582468)
					(mid 169.273564 -231.591448)
					(end 169.264584 -231.595168)
				)
				(arc
					(start 167.791384 -231.595168)
					(mid 167.782404 -231.591448)
					(end 167.778684 -231.582468)
				)
				(arc
					(start 167.778684 -231.08793)
					(mid 167.782404 -231.07895)
					(end 167.791384 -231.07523)
				)
				(arc
					(start 169.264584 -231.07523)
					(mid 169.273564 -231.07895)
					(end 169.277284 -231.08793)
				)
			)
		)
	)
	(zone
		(layer "In1.Cu")
		(hatch none 0.5)
		(connect_pads
			(clearance 0)
		)
		(min_thickness 0.25)
		(keepout
			(tracks not_allowed)
			(vias allowed)
			(pads allowed)
			(copperpour not_allowed)
			(footprints allowed)
		)
		(placement
			(enabled no)
			(sheetname "")
		)
		(fill
			(thermal_gap 0.5)
			(thermal_bridge_width 0.5)
			(island_removal_mode 0)
		)
		(polygon
			(pts
				(arc
					(start 454.937368 -210.33232)
					(mid 454.933648 -210.3413)
					(end 454.924668 -210.34502)
				)
				(arc
					(start 453.451468 -210.34502)
					(mid 453.442488 -210.3413)
					(end 453.438768 -210.33232)
				)
				(arc
					(start 453.438768 -209.837782)
					(mid 453.442488 -209.828802)
					(end 453.451468 -209.825082)
				)
				(arc
					(start 454.924668 -209.825082)
					(mid 454.933648 -209.828802)
					(end 454.937368 -209.837782)
				)
			)
		)
	)
	(zone
		(layer "In1.Cu")
		(hatch none 0.5)
		(connect_pads
			(clearance 0)
		)
		(min_thickness 0.25)
		(keepout
			(tracks not_allowed)
			(vias allowed)
			(pads allowed)
			(copperpour not_allowed)
			(footprints allowed)
		)
		(placement
			(enabled no)
			(sheetname "")
		)
		(fill
			(thermal_gap 0.5)
			(thermal_bridge_width 0.5)
			(island_removal_mode 0)
		)
		(polygon
			(pts
				(arc
					(start 296.473372 -200.132188)
					(mid 296.469652 -200.141168)
					(end 296.460672 -200.144888)
				)
				(arc
					(start 294.987472 -200.144888)
					(mid 294.978492 -200.141168)
					(end 294.974772 -200.132188)
				)
				(arc
					(start 294.974772 -199.63765)
					(mid 294.978492 -199.62867)
					(end 294.987472 -199.62495)
				)
				(arc
					(start 296.460672 -199.62495)
					(mid 296.469652 -199.62867)
					(end 296.473372 -199.63765)
				)
			)
		)
	)
	(zone
		(layer "In1.Cu")
		(hatch none 0.5)
		(connect_pads
			(clearance 0)
		)
		(min_thickness 0.25)
		(keepout
			(tracks not_allowed)
			(vias allowed)
			(pads allowed)
			(copperpour not_allowed)
			(footprints allowed)
		)
		(placement
			(enabled no)
			(sheetname "")
		)
		(fill
			(thermal_gap 0.5)
			(thermal_bridge_width 0.5)
			(island_removal_mode 0)
		)
		(polygon
			(pts
				(arc
					(start 40.98925 -318.282574)
					(mid 40.98553 -318.291554)
					(end 40.97655 -318.295274)
				)
				(arc
					(start 39.50335 -318.295274)
					(mid 39.49437 -318.291554)
					(end 39.49065 -318.282574)
				)
				(arc
					(start 39.49065 -317.788036)
					(mid 39.49437 -317.779056)
					(end 39.50335 -317.775336)
				)
				(arc
					(start 40.97655 -317.775336)
					(mid 40.98553 -317.779056)
					(end 40.98925 -317.788036)
				)
			)
		)
	)
	(zone
		(layer "In1.Cu")
		(hatch none 0.5)
		(connect_pads
			(clearance 0)
		)
		(min_thickness 0.25)
		(keepout
			(tracks not_allowed)
			(vias allowed)
			(pads allowed)
			(copperpour not_allowed)
			(footprints allowed)
		)
		(placement
			(enabled no)
			(sheetname "")
		)
		(fill
			(thermal_gap 0.5)
			(thermal_bridge_width 0.5)
			(island_removal_mode 0)
		)
		(polygon
			(pts
				(arc
					(start 33.445196 -239.23244)
					(mid 33.441476 -239.24142)
					(end 33.432496 -239.24514)
				)
				(arc
					(start 31.959296 -239.24514)
					(mid 31.950316 -239.24142)
					(end 31.946596 -239.23244)
				)
				(arc
					(start 31.946596 -238.737902)
					(mid 31.950316 -238.728922)
					(end 31.959296 -238.725202)
				)
				(arc
					(start 33.432496 -238.725202)
					(mid 33.441476 -238.728922)
					(end 33.445196 -238.737902)
				)
			)
		)
	)
	(zone
		(layer "In1.Cu")
		(hatch none 0.5)
		(connect_pads
			(clearance 0)
		)
		(min_thickness 0.25)
		(keepout
			(tracks not_allowed)
			(vias allowed)
			(pads allowed)
			(copperpour not_allowed)
			(footprints allowed)
		)
		(placement
			(enabled no)
			(sheetname "")
		)
		(fill
			(thermal_gap 0.5)
			(thermal_bridge_width 0.5)
			(island_removal_mode 0)
		)
		(polygon
			(pts
				(arc
					(start 265.87831 -233.884978)
					(mid 265.21791 -233.884978)
					(end 265.87831 -233.884978)
				)
			)
		)
	)
	(zone
		(layer "In1.Cu")
		(hatch none 0.5)
		(connect_pads
			(clearance 0)
		)
		(min_thickness 0.25)
		(keepout
			(tracks not_allowed)
			(vias allowed)
			(pads allowed)
			(copperpour not_allowed)
			(footprints allowed)
		)
		(placement
			(enabled no)
			(sheetname "")
		)
		(fill
			(thermal_gap 0.5)
			(thermal_bridge_width 0.5)
			(island_removal_mode 0)
		)
		(polygon
			(pts
				(arc
					(start 270.397478 -240.932208)
					(mid 270.393758 -240.941188)
					(end 270.384778 -240.944908)
				)
				(arc
					(start 268.911578 -240.944908)
					(mid 268.902598 -240.941188)
					(end 268.898878 -240.932208)
				)
				(arc
					(start 268.898878 -240.43767)
					(mid 268.902598 -240.42869)
					(end 268.911578 -240.42497)
				)
				(arc
					(start 270.384778 -240.42497)
					(mid 270.393758 -240.42869)
					(end 270.397478 -240.43767)
				)
			)
		)
	)
	(zone
		(layer "In1.Cu")
		(hatch none 0.5)
		(connect_pads
			(clearance 0)
		)
		(min_thickness 0.25)
		(keepout
			(tracks not_allowed)
			(vias allowed)
			(pads allowed)
			(copperpour not_allowed)
			(footprints allowed)
		)
		(placement
			(enabled no)
			(sheetname "")
		)
		(fill
			(thermal_gap 0.5)
			(thermal_bridge_width 0.5)
			(island_removal_mode 0)
		)
		(polygon
			(pts
				(arc
					(start 63.461138 -386.003292)
					(mid 63.080138 -386.003292)
					(end 63.461138 -386.003292)
				)
			)
		)
	)
	(zone
		(layer "In1.Cu")
		(hatch none 0.5)
		(connect_pads
			(clearance 0)
		)
		(min_thickness 0.25)
		(keepout
			(tracks not_allowed)
			(vias allowed)
			(pads allowed)
			(copperpour not_allowed)
			(footprints allowed)
		)
		(placement
			(enabled no)
			(sheetname "")
		)
		(fill
			(thermal_gap 0.5)
			(thermal_bridge_width 0.5)
			(island_removal_mode 0)
		)
		(polygon
			(pts
				(arc
					(start 45.089318 -270.682466)
					(mid 45.085598 -270.691446)
					(end 45.076618 -270.695166)
				)
				(arc
					(start 43.603418 -270.695166)
					(mid 43.594438 -270.691446)
					(end 43.590718 -270.682466)
				)
				(arc
					(start 43.590718 -270.187928)
					(mid 43.594438 -270.178948)
					(end 43.603418 -270.175228)
				)
				(arc
					(start 45.076618 -270.175228)
					(mid 45.085598 -270.178948)
					(end 45.089318 -270.187928)
				)
			)
		)
	)
	(zone
		(layer "In1.Cu")
		(hatch none 0.5)
		(connect_pads
			(clearance 0)
		)
		(min_thickness 0.25)
		(keepout
			(tracks not_allowed)
			(vias allowed)
			(pads allowed)
			(copperpour not_allowed)
			(footprints allowed)
		)
		(placement
			(enabled no)
			(sheetname "")
		)
		(fill
			(thermal_gap 0.5)
			(thermal_bridge_width 0.5)
			(island_removal_mode 0)
		)
		(polygon
			(pts
				(arc
					(start 163.888928 -385.31038)
					(mid 163.507928 -385.31038)
					(end 163.888928 -385.31038)
				)
			)
		)
	)
	(zone
		(layer "In1.Cu")
		(hatch none 0.5)
		(connect_pads
			(clearance 0)
		)
		(min_thickness 0.25)
		(keepout
			(tracks not_allowed)
			(vias allowed)
			(pads allowed)
			(copperpour not_allowed)
			(footprints allowed)
		)
		(placement
			(enabled no)
			(sheetname "")
		)
		(fill
			(thermal_gap 0.5)
			(thermal_bridge_width 0.5)
			(island_removal_mode 0)
		)
		(polygon
			(pts
				(arc
					(start 319.46088 -394.385292)
					(mid 319.07988 -394.385292)
					(end 319.46088 -394.385292)
				)
			)
		)
	)
	(zone
		(layer "In1.Cu")
		(hatch none 0.5)
		(connect_pads
			(clearance 0)
		)
		(min_thickness 0.25)
		(keepout
			(tracks not_allowed)
			(vias allowed)
			(pads allowed)
			(copperpour not_allowed)
			(footprints allowed)
		)
		(placement
			(enabled no)
			(sheetname "")
		)
		(fill
			(thermal_gap 0.5)
			(thermal_bridge_width 0.5)
			(island_removal_mode 0)
		)
		(polygon
			(pts
				(arc
					(start 25.901396 -263.882378)
					(mid 25.897676 -263.891358)
					(end 25.888696 -263.895078)
				)
				(arc
					(start 24.415496 -263.895078)
					(mid 24.406516 -263.891358)
					(end 24.402796 -263.882378)
				)
				(arc
					(start 24.402796 -263.38784)
					(mid 24.406516 -263.37886)
					(end 24.415496 -263.37514)
				)
				(arc
					(start 25.888696 -263.37514)
					(mid 25.897676 -263.37886)
					(end 25.901396 -263.38784)
				)
			)
		)
	)
	(zone
		(layer "In1.Cu")
		(hatch none 0.5)
		(connect_pads
			(clearance 0)
		)
		(min_thickness 0.25)
		(keepout
			(tracks not_allowed)
			(vias allowed)
			(pads allowed)
			(copperpour not_allowed)
			(footprints allowed)
		)
		(placement
			(enabled no)
			(sheetname "")
		)
		(fill
			(thermal_gap 0.5)
			(thermal_bridge_width 0.5)
			(island_removal_mode 0)
		)
		(polygon
			(pts
				(arc
					(start 296.473372 -228.18217)
					(mid 296.469652 -228.19115)
					(end 296.460672 -228.19487)
				)
				(arc
					(start 294.987472 -228.19487)
					(mid 294.978492 -228.19115)
					(end 294.974772 -228.18217)
				)
				(arc
					(start 294.974772 -227.687632)
					(mid 294.978492 -227.678652)
					(end 294.987472 -227.674932)
				)
				(arc
					(start 296.460672 -227.674932)
					(mid 296.469652 -227.678652)
					(end 296.473372 -227.687632)
				)
			)
		)
	)
	(zone
		(layer "In1.Cu")
		(hatch none 0.5)
		(connect_pads
			(clearance 0)
		)
		(min_thickness 0.25)
		(keepout
			(tracks not_allowed)
			(vias allowed)
			(pads allowed)
			(copperpour not_allowed)
			(footprints allowed)
		)
		(placement
			(enabled no)
			(sheetname "")
		)
		(fill
			(thermal_gap 0.5)
			(thermal_bridge_width 0.5)
			(island_removal_mode 0)
		)
		(polygon
			(pts
				(arc
					(start 300.57344 -281.732228)
					(mid 300.56972 -281.741208)
					(end 300.56074 -281.744928)
				)
				(arc
					(start 299.08754 -281.744928)
					(mid 299.07856 -281.741208)
					(end 299.07484 -281.732228)
				)
				(arc
					(start 299.07484 -281.23769)
					(mid 299.07856 -281.22871)
					(end 299.08754 -281.22499)
				)
				(arc
					(start 300.56074 -281.22499)
					(mid 300.56972 -281.22871)
					(end 300.57344 -281.23769)
				)
			)
		)
	)
	(zone
		(layer "In1.Cu")
		(hatch none 0.5)
		(connect_pads
			(clearance 0)
		)
		(min_thickness 0.25)
		(keepout
			(tracks not_allowed)
			(vias allowed)
			(pads allowed)
			(copperpour not_allowed)
			(footprints allowed)
		)
		(placement
			(enabled no)
			(sheetname "")
		)
		(fill
			(thermal_gap 0.5)
			(thermal_bridge_width 0.5)
			(island_removal_mode 0)
		)
		(polygon
			(pts
				(arc
					(start 439.849514 -274.082256)
					(mid 439.845794 -274.091236)
					(end 439.836814 -274.094956)
				)
				(arc
					(start 438.363614 -274.094956)
					(mid 438.354634 -274.091236)
					(end 438.350914 -274.082256)
				)
				(arc
					(start 438.350914 -273.587718)
					(mid 438.354634 -273.578738)
					(end 438.363614 -273.575018)
				)
				(arc
					(start 439.836814 -273.575018)
					(mid 439.845794 -273.578738)
					(end 439.849514 -273.587718)
				)
			)
		)
	)
	(zone
		(layer "In1.Cu")
		(hatch none 0.5)
		(connect_pads
			(clearance 0)
		)
		(min_thickness 0.25)
		(keepout
			(tracks not_allowed)
			(vias allowed)
			(pads allowed)
			(copperpour not_allowed)
			(footprints allowed)
		)
		(placement
			(enabled no)
			(sheetname "")
		)
		(fill
			(thermal_gap 0.5)
			(thermal_bridge_width 0.5)
			(island_removal_mode 0)
		)
		(polygon
			(pts
				(arc
					(start 33.445196 -229.882446)
					(mid 33.441476 -229.891426)
					(end 33.432496 -229.895146)
				)
				(arc
					(start 31.959296 -229.895146)
					(mid 31.950316 -229.891426)
					(end 31.946596 -229.882446)
				)
				(arc
					(start 31.946596 -229.387908)
					(mid 31.950316 -229.378928)
					(end 31.959296 -229.375208)
				)
				(arc
					(start 33.432496 -229.375208)
					(mid 33.441476 -229.378928)
					(end 33.445196 -229.387908)
				)
			)
		)
	)
	(zone
		(layer "In1.Cu")
		(hatch none 0.5)
		(connect_pads
			(clearance 0)
		)
		(min_thickness 0.25)
		(keepout
			(tracks not_allowed)
			(vias allowed)
			(pads allowed)
			(copperpour not_allowed)
			(footprints allowed)
		)
		(placement
			(enabled no)
			(sheetname "")
		)
		(fill
			(thermal_gap 0.5)
			(thermal_bridge_width 0.5)
			(island_removal_mode 0)
		)
		(polygon
			(pts
				(arc
					(start 281.385264 -240.082324)
					(mid 281.381544 -240.091304)
					(end 281.372564 -240.095024)
				)
				(arc
					(start 279.899364 -240.095024)
					(mid 279.890384 -240.091304)
					(end 279.886664 -240.082324)
				)
				(arc
					(start 279.886664 -239.587786)
					(mid 279.890384 -239.578806)
					(end 279.899364 -239.575086)
				)
				(arc
					(start 281.372564 -239.575086)
					(mid 281.381544 -239.578806)
					(end 281.385264 -239.587786)
				)
			)
		)
	)
	(zone
		(layer "In1.Cu")
		(hatch none 0.5)
		(connect_pads
			(clearance 0)
		)
		(min_thickness 0.25)
		(keepout
			(tracks not_allowed)
			(vias allowed)
			(pads allowed)
			(copperpour not_allowed)
			(footprints allowed)
		)
		(placement
			(enabled no)
			(sheetname "")
		)
		(fill
			(thermal_gap 0.5)
			(thermal_bridge_width 0.5)
			(island_removal_mode 0)
		)
		(polygon
			(pts
				(arc
					(start 385.360926 -397.849344)
					(mid 384.979926 -397.849344)
					(end 385.360926 -397.849344)
				)
			)
		)
	)
	(zone
		(layer "In1.Cu")
		(hatch none 0.5)
		(connect_pads
			(clearance 0)
		)
		(min_thickness 0.25)
		(keepout
			(tracks not_allowed)
			(vias allowed)
			(pads allowed)
			(copperpour not_allowed)
			(footprints allowed)
		)
		(placement
			(enabled no)
			(sheetname "")
		)
		(fill
			(thermal_gap 0.5)
			(thermal_bridge_width 0.5)
			(island_removal_mode 0)
		)
		(polygon
			(pts
				(arc
					(start 52.633372 -220.532452)
					(mid 52.629652 -220.541432)
					(end 52.620672 -220.545152)
				)
				(arc
					(start 51.147472 -220.545152)
					(mid 51.138492 -220.541432)
					(end 51.134772 -220.532452)
				)
				(arc
					(start 51.134772 -220.037914)
					(mid 51.138492 -220.028934)
					(end 51.147472 -220.025214)
				)
				(arc
					(start 52.620672 -220.025214)
					(mid 52.629652 -220.028934)
					(end 52.633372 -220.037914)
				)
			)
		)
	)
	(zone
		(layer "In1.Cu")
		(hatch none 0.5)
		(connect_pads
			(clearance 0)
		)
		(min_thickness 0.25)
		(keepout
			(tracks not_allowed)
			(vias allowed)
			(pads allowed)
			(copperpour not_allowed)
			(footprints allowed)
		)
		(placement
			(enabled no)
			(sheetname "")
		)
		(fill
			(thermal_gap 0.5)
			(thermal_bridge_width 0.5)
			(island_removal_mode 0)
		)
		(polygon
			(pts
				(arc
					(start 195.353432 -312.33237)
					(mid 195.349712 -312.34135)
					(end 195.340732 -312.34507)
				)
				(arc
					(start 193.867532 -312.34507)
					(mid 193.858552 -312.34135)
					(end 193.854832 -312.33237)
				)
				(arc
					(start 193.854832 -311.837832)
					(mid 193.858552 -311.828852)
					(end 193.867532 -311.825132)
				)
				(arc
					(start 195.340732 -311.825132)
					(mid 195.349712 -311.828852)
					(end 195.353432 -311.837832)
				)
			)
		)
	)
	(zone
		(layer "In1.Cu")
		(hatch none 0.5)
		(connect_pads
			(clearance 0)
		)
		(min_thickness 0.25)
		(keepout
			(tracks not_allowed)
			(vias allowed)
			(pads allowed)
			(copperpour not_allowed)
			(footprints allowed)
		)
		(placement
			(enabled no)
			(sheetname "")
		)
		(fill
			(thermal_gap 0.5)
			(thermal_bridge_width 0.5)
			(island_removal_mode 0)
		)
		(polygon
			(pts
				(arc
					(start 447.393568 -315.73216)
					(mid 447.389848 -315.74114)
					(end 447.380868 -315.74486)
				)
				(arc
					(start 445.907668 -315.74486)
					(mid 445.898688 -315.74114)
					(end 445.894968 -315.73216)
				)
				(arc
					(start 445.894968 -315.237622)
					(mid 445.898688 -315.228642)
					(end 445.907668 -315.224922)
				)
				(arc
					(start 447.380868 -315.224922)
					(mid 447.389848 -315.228642)
					(end 447.393568 -315.237622)
				)
			)
		)
	)
	(zone
		(layer "In1.Cu")
		(hatch none 0.5)
		(connect_pads
			(clearance 0)
		)
		(min_thickness 0.25)
		(keepout
			(tracks not_allowed)
			(vias allowed)
			(pads allowed)
			(copperpour not_allowed)
			(footprints allowed)
		)
		(placement
			(enabled no)
			(sheetname "")
		)
		(fill
			(thermal_gap 0.5)
			(thermal_bridge_width 0.5)
			(island_removal_mode 0)
		)
		(polygon
			(pts
				(arc
					(start 91.51874 -383.440686)
					(mid 91.64574 -383.567686)
					(end 91.77274 -383.440686)
				)
				(arc
					(start 91.77274 -383.364486)
					(mid 91.64574 -383.237486)
					(end 91.51874 -383.364486)
				)
			)
		)
	)
	(zone
		(layer "In1.Cu")
		(hatch none 0.5)
		(connect_pads
			(clearance 0)
		)
		(min_thickness 0.25)
		(keepout
			(tracks not_allowed)
			(vias allowed)
			(pads allowed)
			(copperpour not_allowed)
			(footprints allowed)
		)
		(placement
			(enabled no)
			(sheetname "")
		)
		(fill
			(thermal_gap 0.5)
			(thermal_bridge_width 0.5)
			(island_removal_mode 0)
		)
		(polygon
			(pts
				(arc
					(start 270.397478 -315.73216)
					(mid 270.393758 -315.74114)
					(end 270.384778 -315.74486)
				)
				(arc
					(start 268.911578 -315.74486)
					(mid 268.902598 -315.74114)
					(end 268.898878 -315.73216)
				)
				(arc
					(start 268.898878 -315.237622)
					(mid 268.902598 -315.228642)
					(end 268.911578 -315.224922)
				)
				(arc
					(start 270.384778 -315.224922)
					(mid 270.393758 -315.228642)
					(end 270.397478 -315.237622)
				)
			)
		)
	)
	(zone
		(layer "In1.Cu")
		(hatch none 0.5)
		(connect_pads
			(clearance 0)
		)
		(min_thickness 0.25)
		(keepout
			(tracks not_allowed)
			(vias allowed)
			(pads allowed)
			(copperpour not_allowed)
			(footprints allowed)
		)
		(placement
			(enabled no)
			(sheetname "")
		)
		(fill
			(thermal_gap 0.5)
			(thermal_bridge_width 0.5)
			(island_removal_mode 0)
		)
		(polygon
			(pts
				(arc
					(start 339.588856 -397.156432)
					(mid 339.207856 -397.156432)
					(end 339.588856 -397.156432)
				)
			)
		)
	)
	(zone
		(layer "In1.Cu")
		(hatch none 0.5)
		(connect_pads
			(clearance 0)
		)
		(min_thickness 0.25)
		(keepout
			(tracks not_allowed)
			(vias allowed)
			(pads allowed)
			(copperpour not_allowed)
			(footprints allowed)
		)
		(placement
			(enabled no)
			(sheetname "")
		)
		(fill
			(thermal_gap 0.5)
			(thermal_bridge_width 0.5)
			(island_removal_mode 0)
		)
		(polygon
			(pts
				(arc
					(start 304.017426 -268.98219)
					(mid 304.013706 -268.99117)
					(end 304.004726 -268.99489)
				)
				(arc
					(start 302.531526 -268.99489)
					(mid 302.522546 -268.99117)
					(end 302.518826 -268.98219)
				)
				(arc
					(start 302.518826 -268.487652)
					(mid 302.522546 -268.478672)
					(end 302.531526 -268.474952)
				)
				(arc
					(start 304.004726 -268.474952)
					(mid 304.013706 -268.478672)
					(end 304.017426 -268.487652)
				)
			)
		)
	)
	(zone
		(layer "In1.Cu")
		(hatch none 0.5)
		(connect_pads
			(clearance 0)
		)
		(min_thickness 0.25)
		(keepout
			(tracks not_allowed)
			(vias allowed)
			(pads allowed)
			(copperpour not_allowed)
			(footprints allowed)
		)
		(placement
			(enabled no)
			(sheetname "")
		)
		(fill
			(thermal_gap 0.5)
			(thermal_bridge_width 0.5)
			(island_removal_mode 0)
		)
		(polygon
			(pts
				(arc
					(start 33.445196 -220.532452)
					(mid 33.441476 -220.541432)
					(end 33.432496 -220.545152)
				)
				(arc
					(start 31.959296 -220.545152)
					(mid 31.950316 -220.541432)
					(end 31.946596 -220.532452)
				)
				(arc
					(start 31.946596 -220.037914)
					(mid 31.950316 -220.028934)
					(end 31.959296 -220.025214)
				)
				(arc
					(start 33.432496 -220.025214)
					(mid 33.441476 -220.028934)
					(end 33.445196 -220.037914)
				)
			)
		)
	)
	(zone
		(layer "In1.Cu")
		(hatch none 0.5)
		(connect_pads
			(clearance 0)
		)
		(min_thickness 0.25)
		(keepout
			(tracks not_allowed)
			(vias allowed)
			(pads allowed)
			(copperpour not_allowed)
			(footprints allowed)
		)
		(placement
			(enabled no)
			(sheetname "")
		)
		(fill
			(thermal_gap 0.5)
			(thermal_bridge_width 0.5)
			(island_removal_mode 0)
		)
		(polygon
			(pts
				(arc
					(start 277.941532 -294.482266)
					(mid 277.937812 -294.491246)
					(end 277.928832 -294.494966)
				)
				(arc
					(start 276.455632 -294.494966)
					(mid 276.446652 -294.491246)
					(end 276.442932 -294.482266)
				)
				(arc
					(start 276.442932 -293.987728)
					(mid 276.446652 -293.978748)
					(end 276.455632 -293.975028)
				)
				(arc
					(start 277.928832 -293.975028)
					(mid 277.937812 -293.978748)
					(end 277.941532 -293.987728)
				)
			)
		)
	)
	(zone
		(layer "In1.Cu")
		(hatch none 0.5)
		(connect_pads
			(clearance 0)
		)
		(min_thickness 0.25)
		(keepout
			(tracks not_allowed)
			(vias allowed)
			(pads allowed)
			(copperpour not_allowed)
			(footprints allowed)
		)
		(placement
			(enabled no)
			(sheetname "")
		)
		(fill
			(thermal_gap 0.5)
			(thermal_bridge_width 0.5)
			(island_removal_mode 0)
		)
		(polygon
			(pts
				(arc
					(start 206.5782 -294.235378)
					(mid 205.9178 -294.235378)
					(end 206.5782 -294.235378)
				)
			)
		)
	)
	(zone
		(layer "In1.Cu")
		(hatch none 0.5)
		(connect_pads
			(clearance 0)
		)
		(min_thickness 0.25)
		(keepout
			(tracks not_allowed)
			(vias allowed)
			(pads allowed)
			(copperpour not_allowed)
			(footprints allowed)
		)
		(placement
			(enabled no)
			(sheetname "")
		)
		(fill
			(thermal_gap 0.5)
			(thermal_bridge_width 0.5)
			(island_removal_mode 0)
		)
		(polygon
			(pts
				(arc
					(start 447.393568 -252.832108)
					(mid 447.389848 -252.841088)
					(end 447.380868 -252.844808)
				)
				(arc
					(start 445.907668 -252.844808)
					(mid 445.898688 -252.841088)
					(end 445.894968 -252.832108)
				)
				(arc
					(start 445.894968 -252.33757)
					(mid 445.898688 -252.32859)
					(end 445.907668 -252.32487)
				)
				(arc
					(start 447.380868 -252.32487)
					(mid 447.389848 -252.32859)
					(end 447.393568 -252.33757)
				)
			)
		)
	)
	(zone
		(layer "In1.Cu")
		(hatch none 0.5)
		(connect_pads
			(clearance 0)
		)
		(min_thickness 0.25)
		(keepout
			(tracks not_allowed)
			(vias allowed)
			(pads allowed)
			(copperpour not_allowed)
			(footprints allowed)
		)
		(placement
			(enabled no)
			(sheetname "")
		)
		(fill
			(thermal_gap 0.5)
			(thermal_bridge_width 0.5)
			(island_removal_mode 0)
		)
		(polygon
			(pts
				(arc
					(start 410.288994 -397.156432)
					(mid 409.907994 -397.156432)
					(end 410.288994 -397.156432)
				)
			)
		)
	)
	(zone
		(layer "In1.Cu")
		(hatch none 0.5)
		(connect_pads
			(clearance 0)
		)
		(min_thickness 0.25)
		(keepout
			(tracks not_allowed)
			(vias allowed)
			(pads allowed)
			(copperpour not_allowed)
			(footprints allowed)
		)
		(placement
			(enabled no)
			(sheetname "")
		)
		(fill
			(thermal_gap 0.5)
			(thermal_bridge_width 0.5)
			(island_removal_mode 0)
		)
		(polygon
			(pts
				(arc
					(start 304.017426 -211.182204)
					(mid 304.013706 -211.191184)
					(end 304.004726 -211.194904)
				)
				(arc
					(start 302.531526 -211.194904)
					(mid 302.522546 -211.191184)
					(end 302.518826 -211.182204)
				)
				(arc
					(start 302.518826 -210.687666)
					(mid 302.522546 -210.678686)
					(end 302.531526 -210.674966)
				)
				(arc
					(start 304.004726 -210.674966)
					(mid 304.013706 -210.678686)
					(end 304.017426 -210.687666)
				)
			)
		)
	)
	(zone
		(layer "In1.Cu")
		(hatch none 0.5)
		(connect_pads
			(clearance 0)
		)
		(min_thickness 0.25)
		(keepout
			(tracks not_allowed)
			(vias allowed)
			(pads allowed)
			(copperpour not_allowed)
			(footprints allowed)
		)
		(placement
			(enabled no)
			(sheetname "")
		)
		(fill
			(thermal_gap 0.5)
			(thermal_bridge_width 0.5)
			(island_removal_mode 0)
		)
		(polygon
			(pts
				(arc
					(start 428.205392 -234.13212)
					(mid 428.201672 -234.1411)
					(end 428.192692 -234.14482)
				)
				(arc
					(start 426.719492 -234.14482)
					(mid 426.710512 -234.1411)
					(end 426.706792 -234.13212)
				)
				(arc
					(start 426.706792 -233.637582)
					(mid 426.710512 -233.628602)
					(end 426.719492 -233.624882)
				)
				(arc
					(start 428.192692 -233.624882)
					(mid 428.201672 -233.628602)
					(end 428.205392 -233.637582)
				)
			)
		)
	)
	(zone
		(layer "In1.Cu")
		(hatch none 0.5)
		(connect_pads
			(clearance 0)
		)
		(min_thickness 0.25)
		(keepout
			(tracks not_allowed)
			(vias allowed)
			(pads allowed)
			(copperpour not_allowed)
			(footprints allowed)
		)
		(placement
			(enabled no)
			(sheetname "")
		)
		(fill
			(thermal_gap 0.5)
			(thermal_bridge_width 0.5)
			(island_removal_mode 0)
		)
		(polygon
			(pts
				(arc
					(start 48.533304 -262.182356)
					(mid 48.529584 -262.191336)
					(end 48.520604 -262.195056)
				)
				(arc
					(start 47.047404 -262.195056)
					(mid 47.038424 -262.191336)
					(end 47.034704 -262.182356)
				)
				(arc
					(start 47.034704 -261.687818)
					(mid 47.038424 -261.678838)
					(end 47.047404 -261.675118)
				)
				(arc
					(start 48.520604 -261.675118)
					(mid 48.529584 -261.678838)
					(end 48.533304 -261.687818)
				)
			)
		)
	)
	(zone
		(layer "In1.Cu")
		(hatch none 0.5)
		(connect_pads
			(clearance 0)
		)
		(min_thickness 0.25)
		(keepout
			(tracks not_allowed)
			(vias allowed)
			(pads allowed)
			(copperpour not_allowed)
			(footprints allowed)
		)
		(placement
			(enabled no)
			(sheetname "")
		)
		(fill
			(thermal_gap 0.5)
			(thermal_bridge_width 0.5)
			(island_removal_mode 0)
		)
		(polygon
			(pts
				(arc
					(start 123.070366 -383.92227)
					(mid 122.765566 -383.92227)
					(end 123.070366 -383.92227)
				)
			)
		)
	)
	(zone
		(layer "In1.Cu")
		(hatch none 0.5)
		(connect_pads
			(clearance 0)
		)
		(min_thickness 0.25)
		(keepout
			(tracks not_allowed)
			(vias allowed)
			(pads allowed)
			(copperpour not_allowed)
			(footprints allowed)
		)
		(placement
			(enabled no)
			(sheetname "")
		)
		(fill
			(thermal_gap 0.5)
			(thermal_bridge_width 0.5)
			(island_removal_mode 0)
		)
		(polygon
			(pts
				(arc
					(start 22.45741 -240.932462)
					(mid 22.45369 -240.941442)
					(end 22.44471 -240.945162)
				)
				(arc
					(start 20.97151 -240.945162)
					(mid 20.96253 -240.941442)
					(end 20.95881 -240.932462)
				)
				(arc
					(start 20.95881 -240.437924)
					(mid 20.96253 -240.428944)
					(end 20.97151 -240.425224)
				)
				(arc
					(start 22.44471 -240.425224)
					(mid 22.45369 -240.428944)
					(end 22.45741 -240.437924)
				)
			)
		)
	)
	(zone
		(layer "In1.Cu")
		(hatch none 0.5)
		(connect_pads
			(clearance 0)
		)
		(min_thickness 0.25)
		(keepout
			(tracks not_allowed)
			(vias allowed)
			(pads allowed)
			(copperpour not_allowed)
			(footprints allowed)
		)
		(placement
			(enabled no)
			(sheetname "")
		)
		(fill
			(thermal_gap 0.5)
			(thermal_bridge_width 0.5)
			(island_removal_mode 0)
		)
		(polygon
			(pts
				(arc
					(start 184.365392 -199.282558)
					(mid 184.361672 -199.291538)
					(end 184.352692 -199.295258)
				)
				(arc
					(start 182.879492 -199.295258)
					(mid 182.870512 -199.291538)
					(end 182.866792 -199.282558)
				)
				(arc
					(start 182.866792 -198.78802)
					(mid 182.870512 -198.77904)
					(end 182.879492 -198.77532)
				)
				(arc
					(start 184.352692 -198.77532)
					(mid 184.361672 -198.77904)
					(end 184.365392 -198.78802)
				)
			)
		)
	)
	(zone
		(layer "In1.Cu")
		(hatch none 0.5)
		(connect_pads
			(clearance 0)
		)
		(min_thickness 0.25)
		(keepout
			(tracks not_allowed)
			(vias allowed)
			(pads allowed)
			(copperpour not_allowed)
			(footprints allowed)
		)
		(placement
			(enabled no)
			(sheetname "")
		)
		(fill
			(thermal_gap 0.5)
			(thermal_bridge_width 0.5)
			(island_removal_mode 0)
		)
		(polygon
			(pts
				(arc
					(start 33.445196 -228.182424)
					(mid 33.441476 -228.191404)
					(end 33.432496 -228.195124)
				)
				(arc
					(start 31.959296 -228.195124)
					(mid 31.950316 -228.191404)
					(end 31.946596 -228.182424)
				)
				(arc
					(start 31.946596 -227.687886)
					(mid 31.950316 -227.678906)
					(end 31.959296 -227.675186)
				)
				(arc
					(start 33.432496 -227.675186)
					(mid 33.441476 -227.678906)
					(end 33.445196 -227.687886)
				)
			)
		)
	)
	(zone
		(layer "In1.Cu")
		(hatch none 0.5)
		(connect_pads
			(clearance 0)
		)
		(min_thickness 0.25)
		(keepout
			(tracks not_allowed)
			(vias allowed)
			(pads allowed)
			(copperpour not_allowed)
			(footprints allowed)
		)
		(placement
			(enabled no)
			(sheetname "")
		)
		(fill
			(thermal_gap 0.5)
			(thermal_bridge_width 0.5)
			(island_removal_mode 0)
		)
		(polygon
			(pts
				(arc
					(start 25.901396 -248.582434)
					(mid 25.897676 -248.591414)
					(end 25.888696 -248.595134)
				)
				(arc
					(start 24.415496 -248.595134)
					(mid 24.406516 -248.591414)
					(end 24.402796 -248.582434)
				)
				(arc
					(start 24.402796 -248.087896)
					(mid 24.406516 -248.078916)
					(end 24.415496 -248.075196)
				)
				(arc
					(start 25.888696 -248.075196)
					(mid 25.897676 -248.078916)
					(end 25.901396 -248.087896)
				)
			)
		)
	)
	(zone
		(layer "In1.Cu")
		(hatch none 0.5)
		(connect_pads
			(clearance 0)
		)
		(min_thickness 0.25)
		(keepout
			(tracks not_allowed)
			(vias allowed)
			(pads allowed)
			(copperpour not_allowed)
			(footprints allowed)
		)
		(placement
			(enabled no)
			(sheetname "")
		)
		(fill
			(thermal_gap 0.5)
			(thermal_bridge_width 0.5)
			(island_removal_mode 0)
		)
		(polygon
			(pts
				(arc
					(start 308.117494 -233.282236)
					(mid 308.113774 -233.291216)
					(end 308.104794 -233.294936)
				)
				(arc
					(start 306.631594 -233.294936)
					(mid 306.622614 -233.291216)
					(end 306.618894 -233.282236)
				)
				(arc
					(start 306.618894 -232.787698)
					(mid 306.622614 -232.778718)
					(end 306.631594 -232.774998)
				)
				(arc
					(start 308.104794 -232.774998)
					(mid 308.113774 -232.778718)
					(end 308.117494 -232.787698)
				)
			)
		)
	)
	(zone
		(layer "In1.Cu")
		(hatch none 0.5)
		(connect_pads
			(clearance 0)
		)
		(min_thickness 0.25)
		(keepout
			(tracks not_allowed)
			(vias allowed)
			(pads allowed)
			(copperpour not_allowed)
			(footprints allowed)
		)
		(placement
			(enabled no)
			(sheetname "")
		)
		(fill
			(thermal_gap 0.5)
			(thermal_bridge_width 0.5)
			(island_removal_mode 0)
		)
		(polygon
			(pts
				(arc
					(start 30.001464 -244.332506)
					(mid 29.997744 -244.341486)
					(end 29.988764 -244.345206)
				)
				(arc
					(start 28.515564 -244.345206)
					(mid 28.506584 -244.341486)
					(end 28.502864 -244.332506)
				)
				(arc
					(start 28.502864 -243.837968)
					(mid 28.506584 -243.828988)
					(end 28.515564 -243.825268)
				)
				(arc
					(start 29.988764 -243.825268)
					(mid 29.997744 -243.828988)
					(end 30.001464 -243.837968)
				)
			)
		)
	)
	(zone
		(layer "In1.Cu")
		(hatch none 0.5)
		(connect_pads
			(clearance 0)
		)
		(min_thickness 0.25)
		(keepout
			(tracks not_allowed)
			(vias allowed)
			(pads allowed)
			(copperpour not_allowed)
			(footprints allowed)
		)
		(placement
			(enabled no)
			(sheetname "")
		)
		(fill
			(thermal_gap 0.5)
			(thermal_bridge_width 0.5)
			(island_removal_mode 0)
		)
		(polygon
			(pts
				(arc
					(start 206.9973 -206.93253)
					(mid 206.99358 -206.94151)
					(end 206.9846 -206.94523)
				)
				(arc
					(start 205.5114 -206.94523)
					(mid 205.50242 -206.94151)
					(end 205.4987 -206.93253)
				)
				(arc
					(start 205.4987 -206.437992)
					(mid 205.50242 -206.429012)
					(end 205.5114 -206.425292)
				)
				(arc
					(start 206.9846 -206.425292)
					(mid 206.99358 -206.429012)
					(end 206.9973 -206.437992)
				)
			)
		)
	)
	(zone
		(layer "In1.Cu")
		(hatch none 0.5)
		(connect_pads
			(clearance 0)
		)
		(min_thickness 0.25)
		(keepout
			(tracks not_allowed)
			(vias allowed)
			(pads allowed)
			(copperpour not_allowed)
			(footprints allowed)
		)
		(placement
			(enabled no)
			(sheetname "")
		)
		(fill
			(thermal_gap 0.5)
			(thermal_bridge_width 0.5)
			(island_removal_mode 0)
		)
		(polygon
			(pts
				(arc
					(start 25.901396 -243.482368)
					(mid 25.897676 -243.491348)
					(end 25.888696 -243.495068)
				)
				(arc
					(start 24.415496 -243.495068)
					(mid 24.406516 -243.491348)
					(end 24.402796 -243.482368)
				)
				(arc
					(start 24.402796 -242.98783)
					(mid 24.406516 -242.97885)
					(end 24.415496 -242.97513)
				)
				(arc
					(start 25.888696 -242.97513)
					(mid 25.897676 -242.97885)
					(end 25.901396 -242.98783)
				)
			)
		)
	)
	(zone
		(layer "In1.Cu")
		(hatch none 0.5)
		(connect_pads
			(clearance 0)
		)
		(min_thickness 0.25)
		(keepout
			(tracks not_allowed)
			(vias allowed)
			(pads allowed)
			(copperpour not_allowed)
			(footprints allowed)
		)
		(placement
			(enabled no)
			(sheetname "")
		)
		(fill
			(thermal_gap 0.5)
			(thermal_bridge_width 0.5)
			(island_removal_mode 0)
		)
		(polygon
			(pts
				(arc
					(start 417.217352 -246.032274)
					(mid 417.213632 -246.041254)
					(end 417.204652 -246.044974)
				)
				(arc
					(start 415.731452 -246.044974)
					(mid 415.722472 -246.041254)
					(end 415.718752 -246.032274)
				)
				(arc
					(start 415.718752 -245.537736)
					(mid 415.722472 -245.528756)
					(end 415.731452 -245.525036)
				)
				(arc
					(start 417.204652 -245.525036)
					(mid 417.213632 -245.528756)
					(end 417.217352 -245.537736)
				)
			)
		)
	)
	(zone
		(layer "In1.Cu")
		(hatch none 0.5)
		(connect_pads
			(clearance 0)
		)
		(min_thickness 0.25)
		(keepout
			(tracks not_allowed)
			(vias allowed)
			(pads allowed)
			(copperpour not_allowed)
			(footprints allowed)
		)
		(placement
			(enabled no)
			(sheetname "")
		)
		(fill
			(thermal_gap 0.5)
			(thermal_bridge_width 0.5)
			(island_removal_mode 0)
		)
		(polygon
			(pts
				(arc
					(start 93.298264 -390.761474)
					(mid 92.993464 -390.761474)
					(end 93.298264 -390.761474)
				)
			)
		)
	)
	(zone
		(layer "In1.Cu")
		(hatch none 0.5)
		(connect_pads
			(clearance 0)
		)
		(min_thickness 0.25)
		(keepout
			(tracks not_allowed)
			(vias allowed)
			(pads allowed)
			(copperpour not_allowed)
			(footprints allowed)
		)
		(placement
			(enabled no)
			(sheetname "")
		)
		(fill
			(thermal_gap 0.5)
			(thermal_bridge_width 0.5)
			(island_removal_mode 0)
		)
		(polygon
			(pts
				(arc
					(start 18.357342 -229.882446)
					(mid 18.353622 -229.891426)
					(end 18.344642 -229.895146)
				)
				(arc
					(start 16.871442 -229.895146)
					(mid 16.862462 -229.891426)
					(end 16.858742 -229.882446)
				)
				(arc
					(start 16.858742 -229.387908)
					(mid 16.862462 -229.378928)
					(end 16.871442 -229.375208)
				)
				(arc
					(start 18.344642 -229.375208)
					(mid 18.353622 -229.378928)
					(end 18.357342 -229.387908)
				)
			)
		)
	)
	(zone
		(layer "In1.Cu")
		(hatch none 0.5)
		(connect_pads
			(clearance 0)
		)
		(min_thickness 0.25)
		(keepout
			(tracks not_allowed)
			(vias allowed)
			(pads allowed)
			(copperpour not_allowed)
			(footprints allowed)
		)
		(placement
			(enabled no)
			(sheetname "")
		)
		(fill
			(thermal_gap 0.5)
			(thermal_bridge_width 0.5)
			(island_removal_mode 0)
		)
		(polygon
			(pts
				(arc
					(start 266.29741 -291.932106)
					(mid 266.29369 -291.941086)
					(end 266.28471 -291.944806)
				)
				(arc
					(start 264.81151 -291.944806)
					(mid 264.80253 -291.941086)
					(end 264.79881 -291.932106)
				)
				(arc
					(start 264.79881 -291.437568)
					(mid 264.80253 -291.428588)
					(end 264.81151 -291.424868)
				)
				(arc
					(start 266.28471 -291.424868)
					(mid 266.29369 -291.428588)
					(end 266.29741 -291.437568)
				)
			)
		)
	)
	(zone
		(layer "In1.Cu")
		(hatch none 0.5)
		(connect_pads
			(clearance 0)
		)
		(min_thickness 0.25)
		(keepout
			(tracks not_allowed)
			(vias allowed)
			(pads allowed)
			(copperpour not_allowed)
			(footprints allowed)
		)
		(placement
			(enabled no)
			(sheetname "")
		)
		(fill
			(thermal_gap 0.5)
			(thermal_bridge_width 0.5)
			(island_removal_mode 0)
		)
		(polygon
			(pts
				(arc
					(start 413.888936 -397.156432)
					(mid 413.507936 -397.156432)
					(end 413.888936 -397.156432)
				)
			)
		)
	)
	(zone
		(layer "In1.Cu")
		(hatch none 0.5)
		(connect_pads
			(clearance 0)
		)
		(min_thickness 0.25)
		(keepout
			(tracks not_allowed)
			(vias allowed)
			(pads allowed)
			(copperpour not_allowed)
			(footprints allowed)
		)
		(placement
			(enabled no)
			(sheetname "")
		)
		(fill
			(thermal_gap 0.5)
			(thermal_bridge_width 0.5)
			(island_removal_mode 0)
		)
		(polygon
			(pts
				(arc
					(start 55.861204 -388.774432)
					(mid 55.480204 -388.774432)
					(end 55.861204 -388.774432)
				)
			)
		)
	)
	(zone
		(layer "In1.Cu")
		(hatch none 0.5)
		(connect_pads
			(clearance 0)
		)
		(min_thickness 0.25)
		(keepout
			(tracks not_allowed)
			(vias allowed)
			(pads allowed)
			(copperpour not_allowed)
			(footprints allowed)
		)
		(placement
			(enabled no)
			(sheetname "")
		)
		(fill
			(thermal_gap 0.5)
			(thermal_bridge_width 0.5)
			(island_removal_mode 0)
		)
		(polygon
			(pts
				(arc
					(start 40.98925 -291.93236)
					(mid 40.98553 -291.94134)
					(end 40.97655 -291.94506)
				)
				(arc
					(start 39.50335 -291.94506)
					(mid 39.49437 -291.94134)
					(end 39.49065 -291.93236)
				)
				(arc
					(start 39.49065 -291.437822)
					(mid 39.49437 -291.428842)
					(end 39.50335 -291.425122)
				)
				(arc
					(start 40.97655 -291.425122)
					(mid 40.98553 -291.428842)
					(end 40.98925 -291.437822)
				)
			)
		)
	)
	(zone
		(layer "In1.Cu")
		(hatch none 0.5)
		(connect_pads
			(clearance 0)
		)
		(min_thickness 0.25)
		(keepout
			(tracks not_allowed)
			(vias allowed)
			(pads allowed)
			(copperpour not_allowed)
			(footprints allowed)
		)
		(placement
			(enabled no)
			(sheetname "")
		)
		(fill
			(thermal_gap 0.5)
			(thermal_bridge_width 0.5)
			(island_removal_mode 0)
		)
		(polygon
			(pts
				(arc
					(start 432.30546 -263.03224)
					(mid 432.30174 -263.04122)
					(end 432.29276 -263.04494)
				)
				(arc
					(start 430.81956 -263.04494)
					(mid 430.81058 -263.04122)
					(end 430.80686 -263.03224)
				)
				(arc
					(start 430.80686 -262.537702)
					(mid 430.81058 -262.528722)
					(end 430.81956 -262.525002)
				)
				(arc
					(start 432.29276 -262.525002)
					(mid 432.30174 -262.528722)
					(end 432.30546 -262.537702)
				)
			)
		)
	)
	(zone
		(layer "In1.Cu")
		(hatch none 0.5)
		(connect_pads
			(clearance 0)
		)
		(min_thickness 0.25)
		(keepout
			(tracks not_allowed)
			(vias allowed)
			(pads allowed)
			(copperpour not_allowed)
			(footprints allowed)
		)
		(placement
			(enabled no)
			(sheetname "")
		)
		(fill
			(thermal_gap 0.5)
			(thermal_bridge_width 0.5)
			(island_removal_mode 0)
		)
		(polygon
			(pts
				(arc
					(start 265.87831 -207.535018)
					(mid 265.21791 -207.535018)
					(end 265.87831 -207.535018)
				)
			)
		)
	)
	(zone
		(layer "In1.Cu")
		(hatch none 0.5)
		(connect_pads
			(clearance 0)
		)
		(min_thickness 0.25)
		(keepout
			(tracks not_allowed)
			(vias allowed)
			(pads allowed)
			(copperpour not_allowed)
			(footprints allowed)
		)
		(placement
			(enabled no)
			(sheetname "")
		)
		(fill
			(thermal_gap 0.5)
			(thermal_bridge_width 0.5)
			(island_removal_mode 0)
		)
		(polygon
			(pts
				(arc
					(start 406.798018 -399.143474)
					(mid 406.493218 -399.143474)
					(end 406.798018 -399.143474)
				)
			)
		)
	)
	(zone
		(layer "In1.Cu")
		(hatch none 0.5)
		(connect_pads
			(clearance 0)
		)
		(min_thickness 0.25)
		(keepout
			(tracks not_allowed)
			(vias allowed)
			(pads allowed)
			(copperpour not_allowed)
			(footprints allowed)
		)
		(placement
			(enabled no)
			(sheetname "")
		)
		(fill
			(thermal_gap 0.5)
			(thermal_bridge_width 0.5)
			(island_removal_mode 0)
		)
		(polygon
			(pts
				(arc
					(start 157.99816 -390.761474)
					(mid 157.69336 -390.761474)
					(end 157.99816 -390.761474)
				)
			)
		)
	)
	(zone
		(layer "In1.Cu")
		(hatch none 0.5)
		(connect_pads
			(clearance 0)
		)
		(min_thickness 0.25)
		(keepout
			(tracks not_allowed)
			(vias allowed)
			(pads allowed)
			(copperpour not_allowed)
			(footprints allowed)
		)
		(placement
			(enabled no)
			(sheetname "")
		)
		(fill
			(thermal_gap 0.5)
			(thermal_bridge_width 0.5)
			(island_removal_mode 0)
		)
		(polygon
			(pts
				(arc
					(start 40.98925 -284.282388)
					(mid 40.98553 -284.291368)
					(end 40.97655 -284.295088)
				)
				(arc
					(start 39.50335 -284.295088)
					(mid 39.49437 -284.291368)
					(end 39.49065 -284.282388)
				)
				(arc
					(start 39.49065 -283.78785)
					(mid 39.49437 -283.77887)
					(end 39.50335 -283.77515)
				)
				(arc
					(start 40.97655 -283.77515)
					(mid 40.98553 -283.77887)
					(end 40.98925 -283.78785)
				)
			)
		)
	)
	(zone
		(layer "In1.Cu")
		(hatch none 0.5)
		(connect_pads
			(clearance 0)
		)
		(min_thickness 0.25)
		(keepout
			(tracks not_allowed)
			(vias allowed)
			(pads allowed)
			(copperpour not_allowed)
			(footprints allowed)
		)
		(placement
			(enabled no)
			(sheetname "")
		)
		(fill
			(thermal_gap 0.5)
			(thermal_bridge_width 0.5)
			(island_removal_mode 0)
		)
		(polygon
			(pts
				(arc
					(start 406.798018 -392.30427)
					(mid 406.493218 -392.30427)
					(end 406.798018 -392.30427)
				)
			)
		)
	)
	(zone
		(layer "In1.Cu")
		(hatch none 0.5)
		(connect_pads
			(clearance 0)
		)
		(min_thickness 0.25)
		(keepout
			(tracks not_allowed)
			(vias allowed)
			(pads allowed)
			(copperpour not_allowed)
			(footprints allowed)
		)
		(placement
			(enabled no)
			(sheetname "")
		)
		(fill
			(thermal_gap 0.5)
			(thermal_bridge_width 0.5)
			(island_removal_mode 0)
		)
		(polygon
			(pts
				(arc
					(start 265.87831 -211.784946)
					(mid 265.21791 -211.784946)
					(end 265.87831 -211.784946)
				)
			)
		)
	)
	(zone
		(layer "In1.Cu")
		(hatch none 0.5)
		(connect_pads
			(clearance 0)
		)
		(min_thickness 0.25)
		(keepout
			(tracks not_allowed)
			(vias allowed)
			(pads allowed)
			(copperpour not_allowed)
			(footprints allowed)
		)
		(placement
			(enabled no)
			(sheetname "")
		)
		(fill
			(thermal_gap 0.5)
			(thermal_bridge_width 0.5)
			(island_removal_mode 0)
		)
		(polygon
			(pts
				(arc
					(start 273.841464 -263.882124)
					(mid 273.837744 -263.891104)
					(end 273.828764 -263.894824)
				)
				(arc
					(start 272.355564 -263.894824)
					(mid 272.346584 -263.891104)
					(end 272.342864 -263.882124)
				)
				(arc
					(start 272.342864 -263.387586)
					(mid 272.346584 -263.378606)
					(end 272.355564 -263.374886)
				)
				(arc
					(start 273.828764 -263.374886)
					(mid 273.837744 -263.378606)
					(end 273.841464 -263.387586)
				)
			)
		)
	)
	(zone
		(layer "In1.Cu")
		(hatch none 0.5)
		(connect_pads
			(clearance 0)
		)
		(min_thickness 0.25)
		(keepout
			(tracks not_allowed)
			(vias allowed)
			(pads allowed)
			(copperpour not_allowed)
			(footprints allowed)
		)
		(placement
			(enabled no)
			(sheetname "")
		)
		(fill
			(thermal_gap 0.5)
			(thermal_bridge_width 0.5)
			(island_removal_mode 0)
		)
		(polygon
			(pts
				(arc
					(start 415.488882 -397.849344)
					(mid 415.107882 -397.849344)
					(end 415.488882 -397.849344)
				)
			)
		)
	)
	(zone
		(layer "In1.Cu")
		(hatch none 0.5)
		(connect_pads
			(clearance 0)
		)
		(min_thickness 0.25)
		(keepout
			(tracks not_allowed)
			(vias allowed)
			(pads allowed)
			(copperpour not_allowed)
			(footprints allowed)
		)
		(placement
			(enabled no)
			(sheetname "")
		)
		(fill
			(thermal_gap 0.5)
			(thermal_bridge_width 0.5)
			(island_removal_mode 0)
		)
		(polygon
			(pts
				(arc
					(start 123.90882 -35.684968)
					(mid 123.962702 -35.66265)
					(end 123.98502 -35.608768)
				)
				(arc
					(start 123.98502 -35.253168)
					(mid 123.962702 -35.199286)
					(end 123.90882 -35.176968)
				)
				(arc
					(start 122.00382 -35.176968)
					(mid 121.949938 -35.199286)
					(end 121.92762 -35.253168)
				)
				(arc
					(start 121.92762 -35.608768)
					(mid 121.949938 -35.66265)
					(end 122.00382 -35.684968)
				)
			)
		)
	)
	(zone
		(layer "In1.Cu")
		(hatch none 0.5)
		(connect_pads
			(clearance 0)
		)
		(min_thickness 0.25)
		(keepout
			(tracks not_allowed)
			(vias allowed)
			(pads allowed)
			(copperpour not_allowed)
			(footprints allowed)
		)
		(placement
			(enabled no)
			(sheetname "")
		)
		(fill
			(thermal_gap 0.5)
			(thermal_bridge_width 0.5)
			(island_removal_mode 0)
		)
		(polygon
			(pts
				(arc
					(start 199.4535 -317.432436)
					(mid 199.44978 -317.441416)
					(end 199.4408 -317.445136)
				)
				(arc
					(start 197.9676 -317.445136)
					(mid 197.95862 -317.441416)
					(end 197.9549 -317.432436)
				)
				(arc
					(start 197.9549 -316.937898)
					(mid 197.95862 -316.928918)
					(end 197.9676 -316.925198)
				)
				(arc
					(start 199.4408 -316.925198)
					(mid 199.44978 -316.928918)
					(end 199.4535 -316.937898)
				)
			)
		)
	)
	(zone
		(layer "In1.Cu")
		(hatch none 0.5)
		(connect_pads
			(clearance 0)
		)
		(min_thickness 0.25)
		(keepout
			(tracks not_allowed)
			(vias allowed)
			(pads allowed)
			(copperpour not_allowed)
			(footprints allowed)
		)
		(placement
			(enabled no)
			(sheetname "")
		)
		(fill
			(thermal_gap 0.5)
			(thermal_bridge_width 0.5)
			(island_removal_mode 0)
		)
		(polygon
			(pts
				(arc
					(start 273.841464 -279.182322)
					(mid 273.837744 -279.191302)
					(end 273.828764 -279.195022)
				)
				(arc
					(start 272.355564 -279.195022)
					(mid 272.346584 -279.191302)
					(end 272.342864 -279.182322)
				)
				(arc
					(start 272.342864 -278.687784)
					(mid 272.346584 -278.678804)
					(end 272.355564 -278.675084)
				)
				(arc
					(start 273.828764 -278.675084)
					(mid 273.837744 -278.678804)
					(end 273.841464 -278.687784)
				)
			)
		)
	)
	(zone
		(layer "In1.Cu")
		(hatch none 0.5)
		(connect_pads
			(clearance 0)
		)
		(min_thickness 0.25)
		(keepout
			(tracks not_allowed)
			(vias allowed)
			(pads allowed)
			(copperpour not_allowed)
			(footprints allowed)
		)
		(placement
			(enabled no)
			(sheetname "")
		)
		(fill
			(thermal_gap 0.5)
			(thermal_bridge_width 0.5)
			(island_removal_mode 0)
		)
		(polygon
			(pts
				(arc
					(start 265.87831 -241.53495)
					(mid 265.21791 -241.53495)
					(end 265.87831 -241.53495)
				)
			)
		)
	)
	(zone
		(layer "In1.Cu")
		(hatch none 0.5)
		(connect_pads
			(clearance 0)
		)
		(min_thickness 0.25)
		(keepout
			(tracks not_allowed)
			(vias allowed)
			(pads allowed)
			(copperpour not_allowed)
			(footprints allowed)
		)
		(placement
			(enabled no)
			(sheetname "")
		)
		(fill
			(thermal_gap 0.5)
			(thermal_bridge_width 0.5)
			(island_removal_mode 0)
		)
		(polygon
			(pts
				(arc
					(start 52.633372 -294.48252)
					(mid 52.629652 -294.4915)
					(end 52.620672 -294.49522)
				)
				(arc
					(start 51.147472 -294.49522)
					(mid 51.138492 -294.4915)
					(end 51.134772 -294.48252)
				)
				(arc
					(start 51.134772 -293.987982)
					(mid 51.138492 -293.979002)
					(end 51.147472 -293.975282)
				)
				(arc
					(start 52.620672 -293.975282)
					(mid 52.629652 -293.979002)
					(end 52.633372 -293.987982)
				)
			)
		)
	)
	(zone
		(layer "In1.Cu")
		(hatch none 0.5)
		(connect_pads
			(clearance 0)
		)
		(min_thickness 0.25)
		(keepout
			(tracks not_allowed)
			(vias allowed)
			(pads allowed)
			(copperpour not_allowed)
			(footprints allowed)
		)
		(placement
			(enabled no)
			(sheetname "")
		)
		(fill
			(thermal_gap 0.5)
			(thermal_bridge_width 0.5)
			(island_removal_mode 0)
		)
		(polygon
			(pts
				(arc
					(start 387.470396 -399.143474)
					(mid 387.165596 -399.143474)
					(end 387.470396 -399.143474)
				)
			)
		)
	)
	(zone
		(layer "In1.Cu")
		(hatch none 0.5)
		(connect_pads
			(clearance 0)
		)
		(min_thickness 0.25)
		(keepout
			(tracks not_allowed)
			(vias allowed)
			(pads allowed)
			(copperpour not_allowed)
			(footprints allowed)
		)
		(placement
			(enabled no)
			(sheetname "")
		)
		(fill
			(thermal_gap 0.5)
			(thermal_bridge_width 0.5)
			(island_removal_mode 0)
		)
		(polygon
			(pts
				(arc
					(start 172.72127 -245.18239)
					(mid 172.71755 -245.19137)
					(end 172.70857 -245.19509)
				)
				(arc
					(start 171.23537 -245.19509)
					(mid 171.22639 -245.19137)
					(end 171.22267 -245.18239)
				)
				(arc
					(start 171.22267 -244.687852)
					(mid 171.22639 -244.678872)
					(end 171.23537 -244.675152)
				)
				(arc
					(start 172.70857 -244.675152)
					(mid 172.71755 -244.678872)
					(end 172.72127 -244.687852)
				)
			)
		)
	)
	(zone
		(layer "In1.Cu")
		(hatch none 0.5)
		(connect_pads
			(clearance 0)
		)
		(min_thickness 0.25)
		(keepout
			(tracks not_allowed)
			(vias allowed)
			(pads allowed)
			(copperpour not_allowed)
			(footprints allowed)
		)
		(placement
			(enabled no)
			(sheetname "")
		)
		(fill
			(thermal_gap 0.5)
			(thermal_bridge_width 0.5)
			(island_removal_mode 0)
		)
		(polygon
			(pts
				(arc
					(start 98.098102 -383.92227)
					(mid 97.793302 -383.92227)
					(end 98.098102 -383.92227)
				)
			)
		)
	)
	(zone
		(layer "In1.Cu")
		(hatch none 0.5)
		(connect_pads
			(clearance 0)
		)
		(min_thickness 0.25)
		(keepout
			(tracks not_allowed)
			(vias allowed)
			(pads allowed)
			(copperpour not_allowed)
			(footprints allowed)
		)
		(placement
			(enabled no)
			(sheetname "")
		)
		(fill
			(thermal_gap 0.5)
			(thermal_bridge_width 0.5)
			(island_removal_mode 0)
		)
		(polygon
			(pts
				(arc
					(start 60.177426 -239.23244)
					(mid 60.173706 -239.24142)
					(end 60.164726 -239.24514)
				)
				(arc
					(start 58.691526 -239.24514)
					(mid 58.682546 -239.24142)
					(end 58.678826 -239.23244)
				)
				(arc
					(start 58.678826 -238.737902)
					(mid 58.682546 -238.728922)
					(end 58.691526 -238.725202)
				)
				(arc
					(start 60.164726 -238.725202)
					(mid 60.173706 -238.728922)
					(end 60.177426 -238.737902)
				)
			)
		)
	)
	(zone
		(layer "In1.Cu")
		(hatch none 0.5)
		(connect_pads
			(clearance 0)
		)
		(min_thickness 0.25)
		(keepout
			(tracks not_allowed)
			(vias allowed)
			(pads allowed)
			(copperpour not_allowed)
			(footprints allowed)
		)
		(placement
			(enabled no)
			(sheetname "")
		)
		(fill
			(thermal_gap 0.5)
			(thermal_bridge_width 0.5)
			(island_removal_mode 0)
		)
		(polygon
			(pts
				(arc
					(start 49.061116 -389.467344)
					(mid 48.680116 -389.467344)
					(end 49.061116 -389.467344)
				)
			)
		)
	)
	(zone
		(layer "In1.Cu")
		(hatch none 0.5)
		(connect_pads
			(clearance 0)
		)
		(min_thickness 0.25)
		(keepout
			(tracks not_allowed)
			(vias allowed)
			(pads allowed)
			(copperpour not_allowed)
			(footprints allowed)
		)
		(placement
			(enabled no)
			(sheetname "")
		)
		(fill
			(thermal_gap 0.5)
			(thermal_bridge_width 0.5)
			(island_removal_mode 0)
		)
		(polygon
			(pts
				(arc
					(start 206.9973 -225.632518)
					(mid 206.99358 -225.641498)
					(end 206.9846 -225.645218)
				)
				(arc
					(start 205.5114 -225.645218)
					(mid 205.50242 -225.641498)
					(end 205.4987 -225.632518)
				)
				(arc
					(start 205.4987 -225.13798)
					(mid 205.50242 -225.129)
					(end 205.5114 -225.12528)
				)
				(arc
					(start 206.9846 -225.12528)
					(mid 206.99358 -225.129)
					(end 206.9973 -225.13798)
				)
			)
		)
	)
	(zone
		(layer "In1.Cu")
		(hatch none 0.5)
		(connect_pads
			(clearance 0)
		)
		(min_thickness 0.25)
		(keepout
			(tracks not_allowed)
			(vias allowed)
			(pads allowed)
			(copperpour not_allowed)
			(footprints allowed)
		)
		(placement
			(enabled no)
			(sheetname "")
		)
		(fill
			(thermal_gap 0.5)
			(thermal_bridge_width 0.5)
			(island_removal_mode 0)
		)
		(polygon
			(pts
				(arc
					(start 424.761406 -212.882226)
					(mid 424.757686 -212.891206)
					(end 424.748706 -212.894926)
				)
				(arc
					(start 423.275506 -212.894926)
					(mid 423.266526 -212.891206)
					(end 423.262806 -212.882226)
				)
				(arc
					(start 423.262806 -212.387688)
					(mid 423.266526 -212.378708)
					(end 423.275506 -212.374988)
				)
				(arc
					(start 424.748706 -212.374988)
					(mid 424.757686 -212.378708)
					(end 424.761406 -212.387688)
				)
			)
		)
	)
	(zone
		(layer "In1.Cu")
		(hatch none 0.5)
		(connect_pads
			(clearance 0)
		)
		(min_thickness 0.25)
		(keepout
			(tracks not_allowed)
			(vias allowed)
			(pads allowed)
			(copperpour not_allowed)
			(footprints allowed)
		)
		(placement
			(enabled no)
			(sheetname "")
		)
		(fill
			(thermal_gap 0.5)
			(thermal_bridge_width 0.5)
			(island_removal_mode 0)
		)
		(polygon
			(pts
				(arc
					(start 151.888952 -385.31038)
					(mid 151.507952 -385.31038)
					(end 151.888952 -385.31038)
				)
			)
		)
	)
	(zone
		(layer "In1.Cu")
		(hatch none 0.5)
		(connect_pads
			(clearance 0)
		)
		(min_thickness 0.25)
		(keepout
			(tracks not_allowed)
			(vias allowed)
			(pads allowed)
			(copperpour not_allowed)
			(footprints allowed)
		)
		(placement
			(enabled no)
			(sheetname "")
		)
		(fill
			(thermal_gap 0.5)
			(thermal_bridge_width 0.5)
			(island_removal_mode 0)
		)
		(polygon
			(pts
				(arc
					(start 304.017426 -304.682144)
					(mid 304.013706 -304.691124)
					(end 304.004726 -304.694844)
				)
				(arc
					(start 302.531526 -304.694844)
					(mid 302.522546 -304.691124)
					(end 302.518826 -304.682144)
				)
				(arc
					(start 302.518826 -304.187606)
					(mid 302.522546 -304.178626)
					(end 302.531526 -304.174906)
				)
				(arc
					(start 304.004726 -304.174906)
					(mid 304.013706 -304.178626)
					(end 304.017426 -304.187606)
				)
			)
		)
	)
	(zone
		(layer "In1.Cu")
		(hatch none 0.5)
		(connect_pads
			(clearance 0)
		)
		(min_thickness 0.25)
		(keepout
			(tracks not_allowed)
			(vias allowed)
			(pads allowed)
			(copperpour not_allowed)
			(footprints allowed)
		)
		(placement
			(enabled no)
			(sheetname "")
		)
		(fill
			(thermal_gap 0.5)
			(thermal_bridge_width 0.5)
			(island_removal_mode 0)
		)
		(polygon
			(pts
				(arc
					(start 420.618666 -399.701258)
					(mid 420.745666 -399.828258)
					(end 420.872666 -399.701258)
				)
				(arc
					(start 420.872666 -399.625058)
					(mid 420.745666 -399.498058)
					(end 420.618666 -399.625058)
				)
			)
		)
	)
	(zone
		(layer "In1.Cu")
		(hatch none 0.5)
		(connect_pads
			(clearance 0)
		)
		(min_thickness 0.25)
		(keepout
			(tracks not_allowed)
			(vias allowed)
			(pads allowed)
			(copperpour not_allowed)
			(footprints allowed)
		)
		(placement
			(enabled no)
			(sheetname "")
		)
		(fill
			(thermal_gap 0.5)
			(thermal_bridge_width 0.5)
			(island_removal_mode 0)
		)
		(polygon
			(pts
				(arc
					(start 40.98925 -228.182424)
					(mid 40.98553 -228.191404)
					(end 40.97655 -228.195124)
				)
				(arc
					(start 39.50335 -228.195124)
					(mid 39.49437 -228.191404)
					(end 39.49065 -228.182424)
				)
				(arc
					(start 39.49065 -227.687886)
					(mid 39.49437 -227.678906)
					(end 39.50335 -227.675186)
				)
				(arc
					(start 40.97655 -227.675186)
					(mid 40.98553 -227.678906)
					(end 40.98925 -227.687886)
				)
			)
		)
	)
	(zone
		(layer "In1.Cu")
		(hatch none 0.5)
		(connect_pads
			(clearance 0)
		)
		(min_thickness 0.25)
		(keepout
			(tracks not_allowed)
			(vias allowed)
			(pads allowed)
			(copperpour not_allowed)
			(footprints allowed)
		)
		(placement
			(enabled no)
			(sheetname "")
		)
		(fill
			(thermal_gap 0.5)
			(thermal_bridge_width 0.5)
			(island_removal_mode 0)
		)
		(polygon
			(pts
				(arc
					(start 308.261004 -397.156432)
					(mid 307.880004 -397.156432)
					(end 308.261004 -397.156432)
				)
			)
		)
	)
	(zone
		(layer "In1.Cu")
		(hatch none 0.5)
		(connect_pads
			(clearance 0)
		)
		(min_thickness 0.25)
		(keepout
			(tracks not_allowed)
			(vias allowed)
			(pads allowed)
			(copperpour not_allowed)
			(footprints allowed)
		)
		(placement
			(enabled no)
			(sheetname "")
		)
		(fill
			(thermal_gap 0.5)
			(thermal_bridge_width 0.5)
			(island_removal_mode 0)
		)
		(polygon
			(pts
				(arc
					(start 300.57344 -214.582248)
					(mid 300.56972 -214.591228)
					(end 300.56074 -214.594948)
				)
				(arc
					(start 299.08754 -214.594948)
					(mid 299.07856 -214.591228)
					(end 299.07484 -214.582248)
				)
				(arc
					(start 299.07484 -214.08771)
					(mid 299.07856 -214.07873)
					(end 299.08754 -214.07501)
				)
				(arc
					(start 300.56074 -214.07501)
					(mid 300.56972 -214.07873)
					(end 300.57344 -214.08771)
				)
			)
		)
	)
	(zone
		(layer "In1.Cu")
		(hatch none 0.5)
		(connect_pads
			(clearance 0)
		)
		(min_thickness 0.25)
		(keepout
			(tracks not_allowed)
			(vias allowed)
			(pads allowed)
			(copperpour not_allowed)
			(footprints allowed)
		)
		(placement
			(enabled no)
			(sheetname "")
		)
		(fill
			(thermal_gap 0.5)
			(thermal_bridge_width 0.5)
			(island_removal_mode 0)
		)
		(polygon
			(pts
				(arc
					(start 163.088828 -389.467344)
					(mid 162.707828 -389.467344)
					(end 163.088828 -389.467344)
				)
			)
		)
	)
	(zone
		(layer "In1.Cu")
		(hatch none 0.5)
		(connect_pads
			(clearance 0)
		)
		(min_thickness 0.25)
		(keepout
			(tracks not_allowed)
			(vias allowed)
			(pads allowed)
			(copperpour not_allowed)
			(footprints allowed)
		)
		(placement
			(enabled no)
			(sheetname "")
		)
		(fill
			(thermal_gap 0.5)
			(thermal_bridge_width 0.5)
			(island_removal_mode 0)
		)
		(polygon
			(pts
				(arc
					(start 22.45741 -261.332472)
					(mid 22.45369 -261.341452)
					(end 22.44471 -261.345172)
				)
				(arc
					(start 20.97151 -261.345172)
					(mid 20.96253 -261.341452)
					(end 20.95881 -261.332472)
				)
				(arc
					(start 20.95881 -260.837934)
					(mid 20.96253 -260.828954)
					(end 20.97151 -260.825234)
				)
				(arc
					(start 22.44471 -260.825234)
					(mid 22.45369 -260.828954)
					(end 22.45741 -260.837934)
				)
			)
		)
	)
	(zone
		(layer "In1.Cu")
		(hatch none 0.5)
		(connect_pads
			(clearance 0)
		)
		(min_thickness 0.25)
		(keepout
			(tracks not_allowed)
			(vias allowed)
			(pads allowed)
			(copperpour not_allowed)
			(footprints allowed)
		)
		(placement
			(enabled no)
			(sheetname "")
		)
		(fill
			(thermal_gap 0.5)
			(thermal_bridge_width 0.5)
			(island_removal_mode 0)
		)
		(polygon
			(pts
				(arc
					(start 56.561736 -11.91768)
					(mid 56.539418 -11.971562)
					(end 56.485536 -11.99388)
				)
				(arc
					(start 55.448962 -11.99388)
					(mid 55.39508 -11.971562)
					(end 55.372762 -11.91768)
				)
				(arc
					(start 55.372762 -10.51814)
					(mid 55.39508 -10.464258)
					(end 55.448962 -10.44194)
				)
				(arc
					(start 56.485536 -10.44194)
					(mid 56.539418 -10.464258)
					(end 56.561736 -10.51814)
				)
			)
		)
	)
	(zone
		(layer "In1.Cu")
		(hatch none 0.5)
		(connect_pads
			(clearance 0)
		)
		(min_thickness 0.25)
		(keepout
			(tracks not_allowed)
			(vias allowed)
			(pads allowed)
			(copperpour not_allowed)
			(footprints allowed)
		)
		(placement
			(enabled no)
			(sheetname "")
		)
		(fill
			(thermal_gap 0.5)
			(thermal_bridge_width 0.5)
			(island_removal_mode 0)
		)
		(polygon
			(pts
				(arc
					(start 447.393568 -239.232186)
					(mid 447.389848 -239.241166)
					(end 447.380868 -239.244886)
				)
				(arc
					(start 445.907668 -239.244886)
					(mid 445.898688 -239.241166)
					(end 445.894968 -239.232186)
				)
				(arc
					(start 445.894968 -238.737648)
					(mid 445.898688 -238.728668)
					(end 445.907668 -238.724948)
				)
				(arc
					(start 447.380868 -238.724948)
					(mid 447.389848 -238.728668)
					(end 447.393568 -238.737648)
				)
			)
		)
	)
	(zone
		(layer "In1.Cu")
		(hatch none 0.5)
		(connect_pads
			(clearance 0)
		)
		(min_thickness 0.25)
		(keepout
			(tracks not_allowed)
			(vias allowed)
			(pads allowed)
			(copperpour not_allowed)
			(footprints allowed)
		)
		(placement
			(enabled no)
			(sheetname "")
		)
		(fill
			(thermal_gap 0.5)
			(thermal_bridge_width 0.5)
			(island_removal_mode 0)
		)
		(polygon
			(pts
				(arc
					(start 266.29741 -248.58218)
					(mid 266.29369 -248.59116)
					(end 266.28471 -248.59488)
				)
				(arc
					(start 264.81151 -248.59488)
					(mid 264.80253 -248.59116)
					(end 264.79881 -248.58218)
				)
				(arc
					(start 264.79881 -248.087642)
					(mid 264.80253 -248.078662)
					(end 264.81151 -248.074942)
				)
				(arc
					(start 266.28471 -248.074942)
					(mid 266.29369 -248.078662)
					(end 266.29741 -248.087642)
				)
			)
		)
	)
	(zone
		(layer "In1.Cu")
		(hatch none 0.5)
		(connect_pads
			(clearance 0)
		)
		(min_thickness 0.25)
		(keepout
			(tracks not_allowed)
			(vias allowed)
			(pads allowed)
			(copperpour not_allowed)
			(footprints allowed)
		)
		(placement
			(enabled no)
			(sheetname "")
		)
		(fill
			(thermal_gap 0.5)
			(thermal_bridge_width 0.5)
			(island_removal_mode 0)
		)
		(polygon
			(pts
				(arc
					(start 288.929318 -297.88231)
					(mid 288.925598 -297.89129)
					(end 288.916618 -297.89501)
				)
				(arc
					(start 287.443418 -297.89501)
					(mid 287.434438 -297.89129)
					(end 287.430718 -297.88231)
				)
				(arc
					(start 287.430718 -297.387772)
					(mid 287.434438 -297.378792)
					(end 287.443418 -297.375072)
				)
				(arc
					(start 288.916618 -297.375072)
					(mid 288.925598 -297.378792)
					(end 288.929318 -297.387772)
				)
			)
		)
	)
	(zone
		(layer "In1.Cu")
		(hatch none 0.5)
		(connect_pads
			(clearance 0)
		)
		(min_thickness 0.25)
		(keepout
			(tracks not_allowed)
			(vias allowed)
			(pads allowed)
			(copperpour not_allowed)
			(footprints allowed)
		)
		(placement
			(enabled no)
			(sheetname "")
		)
		(fill
			(thermal_gap 0.5)
			(thermal_bridge_width 0.5)
			(island_removal_mode 0)
		)
		(polygon
			(pts
				(arc
					(start 417.217352 -234.982258)
					(mid 417.213632 -234.991238)
					(end 417.204652 -234.994958)
				)
				(arc
					(start 415.731452 -234.994958)
					(mid 415.722472 -234.991238)
					(end 415.718752 -234.982258)
				)
				(arc
					(start 415.718752 -234.48772)
					(mid 415.722472 -234.47874)
					(end 415.731452 -234.47502)
				)
				(arc
					(start 417.204652 -234.47502)
					(mid 417.213632 -234.47874)
					(end 417.217352 -234.48772)
				)
			)
		)
	)
	(zone
		(layer "In1.Cu")
		(hatch none 0.5)
		(connect_pads
			(clearance 0)
		)
		(min_thickness 0.25)
		(keepout
			(tracks not_allowed)
			(vias allowed)
			(pads allowed)
			(copperpour not_allowed)
			(footprints allowed)
		)
		(placement
			(enabled no)
			(sheetname "")
		)
		(fill
			(thermal_gap 0.5)
			(thermal_bridge_width 0.5)
			(island_removal_mode 0)
		)
		(polygon
			(pts
				(arc
					(start 184.365392 -268.13256)
					(mid 184.361672 -268.14154)
					(end 184.352692 -268.14526)
				)
				(arc
					(start 182.879492 -268.14526)
					(mid 182.870512 -268.14154)
					(end 182.866792 -268.13256)
				)
				(arc
					(start 182.866792 -267.638022)
					(mid 182.870512 -267.629042)
					(end 182.879492 -267.625322)
				)
				(arc
					(start 184.352692 -267.625322)
					(mid 184.361672 -267.629042)
					(end 184.365392 -267.638022)
				)
			)
		)
	)
	(zone
		(layer "In1.Cu")
		(hatch none 0.5)
		(connect_pads
			(clearance 0)
		)
		(min_thickness 0.25)
		(keepout
			(tracks not_allowed)
			(vias allowed)
			(pads allowed)
			(copperpour not_allowed)
			(footprints allowed)
		)
		(placement
			(enabled no)
			(sheetname "")
		)
		(fill
			(thermal_gap 0.5)
			(thermal_bridge_width 0.5)
			(island_removal_mode 0)
		)
		(polygon
			(pts
				(arc
					(start 22.45741 -229.032562)
					(mid 22.45369 -229.041542)
					(end 22.44471 -229.045262)
				)
				(arc
					(start 20.97151 -229.045262)
					(mid 20.96253 -229.041542)
					(end 20.95881 -229.032562)
				)
				(arc
					(start 20.95881 -228.538024)
					(mid 20.96253 -228.529044)
					(end 20.97151 -228.525324)
				)
				(arc
					(start 22.44471 -228.525324)
					(mid 22.45369 -228.529044)
					(end 22.45741 -228.538024)
				)
			)
		)
	)
	(zone
		(layer "In1.Cu")
		(hatch none 0.5)
		(connect_pads
			(clearance 0)
		)
		(min_thickness 0.25)
		(keepout
			(tracks not_allowed)
			(vias allowed)
			(pads allowed)
			(copperpour not_allowed)
			(footprints allowed)
		)
		(placement
			(enabled no)
			(sheetname "")
		)
		(fill
			(thermal_gap 0.5)
			(thermal_bridge_width 0.5)
			(island_removal_mode 0)
		)
		(polygon
			(pts
				(arc
					(start 56.077358 -212.032342)
					(mid 56.073638 -212.041322)
					(end 56.064658 -212.045042)
				)
				(arc
					(start 54.591458 -212.045042)
					(mid 54.582478 -212.041322)
					(end 54.578758 -212.032342)
				)
				(arc
					(start 54.578758 -211.537804)
					(mid 54.582478 -211.528824)
					(end 54.591458 -211.525104)
				)
				(arc
					(start 56.064658 -211.525104)
					(mid 56.073638 -211.528824)
					(end 56.077358 -211.537804)
				)
			)
		)
	)
	(zone
		(layer "In1.Cu")
		(hatch none 0.5)
		(connect_pads
			(clearance 0)
		)
		(min_thickness 0.25)
		(keepout
			(tracks not_allowed)
			(vias allowed)
			(pads allowed)
			(copperpour not_allowed)
			(footprints allowed)
		)
		(placement
			(enabled no)
			(sheetname "")
		)
		(fill
			(thermal_gap 0.5)
			(thermal_bridge_width 0.5)
			(island_removal_mode 0)
		)
		(polygon
			(pts
				(arc
					(start 176.821338 -214.582502)
					(mid 176.817618 -214.591482)
					(end 176.808638 -214.595202)
				)
				(arc
					(start 175.335438 -214.595202)
					(mid 175.326458 -214.591482)
					(end 175.322738 -214.582502)
				)
				(arc
					(start 175.322738 -214.087964)
					(mid 175.326458 -214.078984)
					(end 175.335438 -214.075264)
				)
				(arc
					(start 176.808638 -214.075264)
					(mid 176.817618 -214.078984)
					(end 176.821338 -214.087964)
				)
			)
		)
	)
	(zone
		(layer "In1.Cu")
		(hatch none 0.5)
		(connect_pads
			(clearance 0)
		)
		(min_thickness 0.25)
		(keepout
			(tracks not_allowed)
			(vias allowed)
			(pads allowed)
			(copperpour not_allowed)
			(footprints allowed)
		)
		(placement
			(enabled no)
			(sheetname "")
		)
		(fill
			(thermal_gap 0.5)
			(thermal_bridge_width 0.5)
			(island_removal_mode 0)
		)
		(polygon
			(pts
				(arc
					(start 206.5782 -223.685354)
					(mid 205.9178 -223.685354)
					(end 206.5782 -223.685354)
				)
			)
		)
	)
	(zone
		(layer "In1.Cu")
		(hatch none 0.5)
		(connect_pads
			(clearance 0)
		)
		(min_thickness 0.25)
		(keepout
			(tracks not_allowed)
			(vias allowed)
			(pads allowed)
			(copperpour not_allowed)
			(footprints allowed)
		)
		(placement
			(enabled no)
			(sheetname "")
		)
		(fill
			(thermal_gap 0.5)
			(thermal_bridge_width 0.5)
			(island_removal_mode 0)
		)
		(polygon
			(pts
				(arc
					(start 285.485332 -264.732262)
					(mid 285.481612 -264.741242)
					(end 285.472632 -264.744962)
				)
				(arc
					(start 283.999432 -264.744962)
					(mid 283.990452 -264.741242)
					(end 283.986732 -264.732262)
				)
				(arc
					(start 283.986732 -264.237724)
					(mid 283.990452 -264.228744)
					(end 283.999432 -264.225024)
				)
				(arc
					(start 285.472632 -264.225024)
					(mid 285.481612 -264.228744)
					(end 285.485332 -264.237724)
				)
			)
		)
	)
	(zone
		(layer "In1.Cu")
		(hatch none 0.5)
		(connect_pads
			(clearance 0)
		)
		(min_thickness 0.25)
		(keepout
			(tracks not_allowed)
			(vias allowed)
			(pads allowed)
			(copperpour not_allowed)
			(footprints allowed)
		)
		(placement
			(enabled no)
			(sheetname "")
		)
		(fill
			(thermal_gap 0.5)
			(thermal_bridge_width 0.5)
			(island_removal_mode 0)
		)
		(polygon
			(pts
				(arc
					(start 454.937368 -239.232186)
					(mid 454.933648 -239.241166)
					(end 454.924668 -239.244886)
				)
				(arc
					(start 453.451468 -239.244886)
					(mid 453.442488 -239.241166)
					(end 453.438768 -239.232186)
				)
				(arc
					(start 453.438768 -238.737648)
					(mid 453.442488 -238.728668)
					(end 453.451468 -238.724948)
				)
				(arc
					(start 454.924668 -238.724948)
					(mid 454.933648 -238.728668)
					(end 454.937368 -238.737648)
				)
			)
		)
	)
	(zone
		(layer "In1.Cu")
		(hatch none 0.5)
		(connect_pads
			(clearance 0)
		)
		(min_thickness 0.25)
		(keepout
			(tracks not_allowed)
			(vias allowed)
			(pads allowed)
			(copperpour not_allowed)
			(footprints allowed)
		)
		(placement
			(enabled no)
			(sheetname "")
		)
		(fill
			(thermal_gap 0.5)
			(thermal_bridge_width 0.5)
			(island_removal_mode 0)
		)
		(polygon
			(pts
				(arc
					(start 60.177426 -285.98241)
					(mid 60.173706 -285.99139)
					(end 60.164726 -285.99511)
				)
				(arc
					(start 58.691526 -285.99511)
					(mid 58.682546 -285.99139)
					(end 58.678826 -285.98241)
				)
				(arc
					(start 58.678826 -285.487872)
					(mid 58.682546 -285.478892)
					(end 58.691526 -285.475172)
				)
				(arc
					(start 60.164726 -285.475172)
					(mid 60.173706 -285.478892)
					(end 60.177426 -285.487872)
				)
			)
		)
	)
	(zone
		(layer "In1.Cu")
		(hatch none 0.5)
		(connect_pads
			(clearance 0)
		)
		(min_thickness 0.25)
		(keepout
			(tracks not_allowed)
			(vias allowed)
			(pads allowed)
			(copperpour not_allowed)
			(footprints allowed)
		)
		(placement
			(enabled no)
			(sheetname "")
		)
		(fill
			(thermal_gap 0.5)
			(thermal_bridge_width 0.5)
			(island_removal_mode 0)
		)
		(polygon
			(pts
				(arc
					(start 22.45741 -217.982546)
					(mid 22.45369 -217.991526)
					(end 22.44471 -217.995246)
				)
				(arc
					(start 20.97151 -217.995246)
					(mid 20.96253 -217.991526)
					(end 20.95881 -217.982546)
				)
				(arc
					(start 20.95881 -217.488008)
					(mid 20.96253 -217.479028)
					(end 20.97151 -217.475308)
				)
				(arc
					(start 22.44471 -217.475308)
					(mid 22.45369 -217.479028)
					(end 22.45741 -217.488008)
				)
			)
		)
	)
	(zone
		(layer "In1.Cu")
		(hatch none 0.5)
		(connect_pads
			(clearance 0)
		)
		(min_thickness 0.25)
		(keepout
			(tracks not_allowed)
			(vias allowed)
			(pads allowed)
			(copperpour not_allowed)
			(footprints allowed)
		)
		(placement
			(enabled no)
			(sheetname "")
		)
		(fill
			(thermal_gap 0.5)
			(thermal_bridge_width 0.5)
			(island_removal_mode 0)
		)
		(polygon
			(pts
				(arc
					(start 447.393568 -229.032308)
					(mid 447.389848 -229.041288)
					(end 447.380868 -229.045008)
				)
				(arc
					(start 445.907668 -229.045008)
					(mid 445.898688 -229.041288)
					(end 445.894968 -229.032308)
				)
				(arc
					(start 445.894968 -228.53777)
					(mid 445.898688 -228.52879)
					(end 445.907668 -228.52507)
				)
				(arc
					(start 447.380868 -228.52507)
					(mid 447.389848 -228.52879)
					(end 447.393568 -228.53777)
				)
			)
		)
	)
	(zone
		(layer "In1.Cu")
		(hatch none 0.5)
		(connect_pads
			(clearance 0)
		)
		(min_thickness 0.25)
		(keepout
			(tracks not_allowed)
			(vias allowed)
			(pads allowed)
			(copperpour not_allowed)
			(footprints allowed)
		)
		(placement
			(enabled no)
			(sheetname "")
		)
		(fill
			(thermal_gap 0.5)
			(thermal_bridge_width 0.5)
			(island_removal_mode 0)
		)
		(polygon
			(pts
				(arc
					(start 420.661338 -241.782092)
					(mid 420.657618 -241.791072)
					(end 420.648638 -241.794792)
				)
				(arc
					(start 419.175438 -241.794792)
					(mid 419.166458 -241.791072)
					(end 419.162738 -241.782092)
				)
				(arc
					(start 419.162738 -241.287554)
					(mid 419.166458 -241.278574)
					(end 419.175438 -241.274854)
				)
				(arc
					(start 420.648638 -241.274854)
					(mid 420.657618 -241.278574)
					(end 420.661338 -241.287554)
				)
			)
		)
	)
	(zone
		(layer "In1.Cu")
		(hatch none 0.5)
		(connect_pads
			(clearance 0)
		)
		(min_thickness 0.25)
		(keepout
			(tracks not_allowed)
			(vias allowed)
			(pads allowed)
			(copperpour not_allowed)
			(footprints allowed)
		)
		(placement
			(enabled no)
			(sheetname "")
		)
		(fill
			(thermal_gap 0.5)
			(thermal_bridge_width 0.5)
			(island_removal_mode 0)
		)
		(polygon
			(pts
				(arc
					(start 443.2935 -268.98219)
					(mid 443.28978 -268.99117)
					(end 443.2808 -268.99489)
				)
				(arc
					(start 441.8076 -268.99489)
					(mid 441.79862 -268.99117)
					(end 441.7949 -268.98219)
				)
				(arc
					(start 441.7949 -268.487652)
					(mid 441.79862 -268.478672)
					(end 441.8076 -268.474952)
				)
				(arc
					(start 443.2808 -268.474952)
					(mid 443.28978 -268.478672)
					(end 443.2935 -268.487652)
				)
			)
		)
	)
	(zone
		(layer "In1.Cu")
		(hatch none 0.5)
		(connect_pads
			(clearance 0)
		)
		(min_thickness 0.25)
		(keepout
			(tracks not_allowed)
			(vias allowed)
			(pads allowed)
			(copperpour not_allowed)
			(footprints allowed)
		)
		(placement
			(enabled no)
			(sheetname "")
		)
		(fill
			(thermal_gap 0.5)
			(thermal_bridge_width 0.5)
			(island_removal_mode 0)
		)
		(polygon
			(pts
				(arc
					(start 454.937368 -275.782278)
					(mid 454.933648 -275.791258)
					(end 454.924668 -275.794978)
				)
				(arc
					(start 453.451468 -275.794978)
					(mid 453.442488 -275.791258)
					(end 453.438768 -275.782278)
				)
				(arc
					(start 453.438768 -275.28774)
					(mid 453.442488 -275.27876)
					(end 453.451468 -275.27504)
				)
				(arc
					(start 454.924668 -275.27504)
					(mid 454.933648 -275.27876)
					(end 454.937368 -275.28774)
				)
			)
		)
	)
	(zone
		(layer "In1.Cu")
		(hatch none 0.5)
		(connect_pads
			(clearance 0)
		)
		(min_thickness 0.25)
		(keepout
			(tracks not_allowed)
			(vias allowed)
			(pads allowed)
			(copperpour not_allowed)
			(footprints allowed)
		)
		(placement
			(enabled no)
			(sheetname "")
		)
		(fill
			(thermal_gap 0.5)
			(thermal_bridge_width 0.5)
			(island_removal_mode 0)
		)
		(polygon
			(pts
				(arc
					(start 48.533304 -230.732584)
					(mid 48.529584 -230.741564)
					(end 48.520604 -230.745284)
				)
				(arc
					(start 47.047404 -230.745284)
					(mid 47.038424 -230.741564)
					(end 47.034704 -230.732584)
				)
				(arc
					(start 47.034704 -230.238046)
					(mid 47.038424 -230.229066)
					(end 47.047404 -230.225346)
				)
				(arc
					(start 48.520604 -230.225346)
					(mid 48.529584 -230.229066)
					(end 48.533304 -230.238046)
				)
			)
		)
	)
	(zone
		(layer "In1.Cu")
		(hatch none 0.5)
		(connect_pads
			(clearance 0)
		)
		(min_thickness 0.25)
		(keepout
			(tracks not_allowed)
			(vias allowed)
			(pads allowed)
			(copperpour not_allowed)
			(footprints allowed)
		)
		(placement
			(enabled no)
			(sheetname "")
		)
		(fill
			(thermal_gap 0.5)
			(thermal_bridge_width 0.5)
			(island_removal_mode 0)
		)
		(polygon
			(pts
				(arc
					(start 29.285692 -17.967198)
					(mid 29.30801 -18.02108)
					(end 29.361892 -18.043398)
				)
				(arc
					(start 29.557472 -18.043398)
					(mid 29.579348 -18.040266)
					(end 29.599382 -18.030952)
				)
				(arc
					(start 29.893006 -17.83842)
					(mid 29.934662 -17.826018)
					(end 29.976318 -17.83842)
				)
				(arc
					(start 30.271212 -18.030952)
					(mid 30.291136 -18.040188)
					(end 30.312868 -18.043398)
				)
				(arc
					(start 30.507432 -18.043398)
					(mid 30.561314 -18.02108)
					(end 30.583632 -17.967198)
				)
				(arc
					(start 30.583632 -17.281398)
					(mid 30.561314 -17.227516)
					(end 30.507432 -17.205198)
				)
				(arc
					(start 30.312868 -17.205198)
					(mid 30.291124 -17.208366)
					(end 30.271212 -17.217644)
				)
				(arc
					(start 29.975048 -17.41043)
					(mid 29.933364 -17.422652)
					(end 29.891736 -17.410176)
				)
				(arc
					(start 29.598112 -17.217644)
					(mid 29.578188 -17.208408)
					(end 29.556456 -17.205198)
				)
				(arc
					(start 29.361892 -17.205198)
					(mid 29.30801 -17.227516)
					(end 29.285692 -17.281398)
				)
			)
		)
	)
	(zone
		(layer "In1.Cu")
		(hatch none 0.5)
		(connect_pads
			(clearance 0)
		)
		(min_thickness 0.25)
		(keepout
			(tracks not_allowed)
			(vias allowed)
			(pads allowed)
			(copperpour not_allowed)
			(footprints allowed)
		)
		(placement
			(enabled no)
			(sheetname "")
		)
		(fill
			(thermal_gap 0.5)
			(thermal_bridge_width 0.5)
			(island_removal_mode 0)
		)
		(polygon
			(pts
				(arc
					(start 60.177426 -294.48252)
					(mid 60.173706 -294.4915)
					(end 60.164726 -294.49522)
				)
				(arc
					(start 58.691526 -294.49522)
					(mid 58.682546 -294.4915)
					(end 58.678826 -294.48252)
				)
				(arc
					(start 58.678826 -293.987982)
					(mid 58.682546 -293.979002)
					(end 58.691526 -293.975282)
				)
				(arc
					(start 60.164726 -293.975282)
					(mid 60.173706 -293.979002)
					(end 60.177426 -293.987982)
				)
			)
		)
	)
	(zone
		(layer "In1.Cu")
		(hatch none 0.5)
		(connect_pads
			(clearance 0)
		)
		(min_thickness 0.25)
		(keepout
			(tracks not_allowed)
			(vias allowed)
			(pads allowed)
			(copperpour not_allowed)
			(footprints allowed)
		)
		(placement
			(enabled no)
			(sheetname "")
		)
		(fill
			(thermal_gap 0.5)
			(thermal_bridge_width 0.5)
			(island_removal_mode 0)
		)
		(polygon
			(pts
				(arc
					(start 25.901396 -224.78238)
					(mid 25.897676 -224.79136)
					(end 25.888696 -224.79508)
				)
				(arc
					(start 24.415496 -224.79508)
					(mid 24.406516 -224.79136)
					(end 24.402796 -224.78238)
				)
				(arc
					(start 24.402796 -224.287842)
					(mid 24.406516 -224.278862)
					(end 24.415496 -224.275142)
				)
				(arc
					(start 25.888696 -224.275142)
					(mid 25.897676 -224.278862)
					(end 25.901396 -224.287842)
				)
			)
		)
	)
	(zone
		(layer "In1.Cu")
		(hatch none 0.5)
		(connect_pads
			(clearance 0)
		)
		(min_thickness 0.25)
		(keepout
			(tracks not_allowed)
			(vias allowed)
			(pads allowed)
			(copperpour not_allowed)
			(footprints allowed)
		)
		(placement
			(enabled no)
			(sheetname "")
		)
		(fill
			(thermal_gap 0.5)
			(thermal_bridge_width 0.5)
			(island_removal_mode 0)
		)
		(polygon
			(pts
				(arc
					(start 411.018736 -391.822686)
					(mid 411.145736 -391.949686)
					(end 411.272736 -391.822686)
				)
				(arc
					(start 411.272736 -391.746486)
					(mid 411.145736 -391.619486)
					(end 411.018736 -391.746486)
				)
			)
		)
	)
	(zone
		(layer "In1.Cu")
		(hatch none 0.5)
		(connect_pads
			(clearance 0)
		)
		(min_thickness 0.25)
		(keepout
			(tracks not_allowed)
			(vias allowed)
			(pads allowed)
			(copperpour not_allowed)
			(footprints allowed)
		)
		(placement
			(enabled no)
			(sheetname "")
		)
		(fill
			(thermal_gap 0.5)
			(thermal_bridge_width 0.5)
			(island_removal_mode 0)
		)
		(polygon
			(pts
				(arc
					(start 432.30546 -292.782244)
					(mid 432.30174 -292.791224)
					(end 432.29276 -292.794944)
				)
				(arc
					(start 430.81956 -292.794944)
					(mid 430.81058 -292.791224)
					(end 430.80686 -292.782244)
				)
				(arc
					(start 430.80686 -292.287706)
					(mid 430.81058 -292.278726)
					(end 430.81956 -292.275006)
				)
				(arc
					(start 432.29276 -292.275006)
					(mid 432.30174 -292.278726)
					(end 432.30546 -292.287706)
				)
			)
		)
	)
	(zone
		(layer "In1.Cu")
		(hatch none 0.5)
		(connect_pads
			(clearance 0)
		)
		(min_thickness 0.25)
		(keepout
			(tracks not_allowed)
			(vias allowed)
			(pads allowed)
			(copperpour not_allowed)
			(footprints allowed)
		)
		(placement
			(enabled no)
			(sheetname "")
		)
		(fill
			(thermal_gap 0.5)
			(thermal_bridge_width 0.5)
			(island_removal_mode 0)
		)
		(polygon
			(pts
				(arc
					(start 22.45741 -295.332404)
					(mid 22.45369 -295.341384)
					(end 22.44471 -295.345104)
				)
				(arc
					(start 20.97151 -295.345104)
					(mid 20.96253 -295.341384)
					(end 20.95881 -295.332404)
				)
				(arc
					(start 20.95881 -294.837866)
					(mid 20.96253 -294.828886)
					(end 20.97151 -294.825166)
				)
				(arc
					(start 22.44471 -294.825166)
					(mid 22.45369 -294.828886)
					(end 22.45741 -294.837866)
				)
			)
		)
	)
	(zone
		(layer "In1.Cu")
		(hatch none 0.5)
		(connect_pads
			(clearance 0)
		)
		(min_thickness 0.25)
		(keepout
			(tracks not_allowed)
			(vias allowed)
			(pads allowed)
			(copperpour not_allowed)
			(footprints allowed)
		)
		(placement
			(enabled no)
			(sheetname "")
		)
		(fill
			(thermal_gap 0.5)
			(thermal_bridge_width 0.5)
			(island_removal_mode 0)
		)
		(polygon
			(pts
				(arc
					(start 308.117494 -270.682212)
					(mid 308.113774 -270.691192)
					(end 308.104794 -270.694912)
				)
				(arc
					(start 306.631594 -270.694912)
					(mid 306.622614 -270.691192)
					(end 306.618894 -270.682212)
				)
				(arc
					(start 306.618894 -270.187674)
					(mid 306.622614 -270.178694)
					(end 306.631594 -270.174974)
				)
				(arc
					(start 308.104794 -270.174974)
					(mid 308.113774 -270.178694)
					(end 308.117494 -270.187674)
				)
			)
		)
	)
	(zone
		(layer "In1.Cu")
		(hatch none 0.5)
		(connect_pads
			(clearance 0)
		)
		(min_thickness 0.25)
		(keepout
			(tracks not_allowed)
			(vias allowed)
			(pads allowed)
			(copperpour not_allowed)
			(footprints allowed)
		)
		(placement
			(enabled no)
			(sheetname "")
		)
		(fill
			(thermal_gap 0.5)
			(thermal_bridge_width 0.5)
			(island_removal_mode 0)
		)
		(polygon
			(pts
				(arc
					(start 37.545264 -317.432436)
					(mid 37.541544 -317.441416)
					(end 37.532564 -317.445136)
				)
				(arc
					(start 36.059364 -317.445136)
					(mid 36.050384 -317.441416)
					(end 36.046664 -317.432436)
				)
				(arc
					(start 36.046664 -316.937898)
					(mid 36.050384 -316.928918)
					(end 36.059364 -316.925198)
				)
				(arc
					(start 37.532564 -316.925198)
					(mid 37.541544 -316.928918)
					(end 37.545264 -316.937898)
				)
			)
		)
	)
	(zone
		(layer "In1.Cu")
		(hatch none 0.5)
		(connect_pads
			(clearance 0)
		)
		(min_thickness 0.25)
		(keepout
			(tracks not_allowed)
			(vias allowed)
			(pads allowed)
			(copperpour not_allowed)
			(footprints allowed)
		)
		(placement
			(enabled no)
			(sheetname "")
		)
		(fill
			(thermal_gap 0.5)
			(thermal_bridge_width 0.5)
			(island_removal_mode 0)
		)
		(polygon
			(pts
				(arc
					(start 40.98925 -308.93258)
					(mid 40.98553 -308.94156)
					(end 40.97655 -308.94528)
				)
				(arc
					(start 39.50335 -308.94528)
					(mid 39.49437 -308.94156)
					(end 39.49065 -308.93258)
				)
				(arc
					(start 39.49065 -308.438042)
					(mid 39.49437 -308.429062)
					(end 39.50335 -308.425342)
				)
				(arc
					(start 40.97655 -308.425342)
					(mid 40.98553 -308.429062)
					(end 40.98925 -308.438042)
				)
			)
		)
	)
	(zone
		(layer "In1.Cu")
		(hatch none 0.5)
		(connect_pads
			(clearance 0)
		)
		(min_thickness 0.25)
		(keepout
			(tracks not_allowed)
			(vias allowed)
			(pads allowed)
			(copperpour not_allowed)
			(footprints allowed)
		)
		(placement
			(enabled no)
			(sheetname "")
		)
		(fill
			(thermal_gap 0.5)
			(thermal_bridge_width 0.5)
			(island_removal_mode 0)
		)
		(polygon
			(pts
				(arc
					(start 414.618678 -391.822686)
					(mid 414.745678 -391.949686)
					(end 414.872678 -391.822686)
				)
				(arc
					(start 414.872678 -391.746486)
					(mid 414.745678 -391.619486)
					(end 414.618678 -391.746486)
				)
			)
		)
	)
	(zone
		(layer "In1.Cu")
		(hatch none 0.5)
		(connect_pads
			(clearance 0)
		)
		(min_thickness 0.25)
		(keepout
			(tracks not_allowed)
			(vias allowed)
			(pads allowed)
			(copperpour not_allowed)
			(footprints allowed)
		)
		(placement
			(enabled no)
			(sheetname "")
		)
		(fill
			(thermal_gap 0.5)
			(thermal_bridge_width 0.5)
			(island_removal_mode 0)
		)
		(polygon
			(pts
				(arc
					(start 447.393568 -295.33215)
					(mid 447.389848 -295.34113)
					(end 447.380868 -295.34485)
				)
				(arc
					(start 445.907668 -295.34485)
					(mid 445.898688 -295.34113)
					(end 445.894968 -295.33215)
				)
				(arc
					(start 445.894968 -294.837612)
					(mid 445.898688 -294.828632)
					(end 445.907668 -294.824912)
				)
				(arc
					(start 447.380868 -294.824912)
					(mid 447.389848 -294.828632)
					(end 447.393568 -294.837612)
				)
			)
		)
	)
	(zone
		(layer "In1.Cu")
		(hatch none 0.5)
		(connect_pads
			(clearance 0)
		)
		(min_thickness 0.25)
		(keepout
			(tracks not_allowed)
			(vias allowed)
			(pads allowed)
			(copperpour not_allowed)
			(footprints allowed)
		)
		(placement
			(enabled no)
			(sheetname "")
		)
		(fill
			(thermal_gap 0.5)
			(thermal_bridge_width 0.5)
			(island_removal_mode 0)
		)
		(polygon
			(pts
				(arc
					(start 45.089318 -236.682534)
					(mid 45.085598 -236.691514)
					(end 45.076618 -236.695234)
				)
				(arc
					(start 43.603418 -236.695234)
					(mid 43.594438 -236.691514)
					(end 43.590718 -236.682534)
				)
				(arc
					(start 43.590718 -236.187996)
					(mid 43.594438 -236.179016)
					(end 43.603418 -236.175296)
				)
				(arc
					(start 45.076618 -236.175296)
					(mid 45.085598 -236.179016)
					(end 45.089318 -236.187996)
				)
			)
		)
	)
	(zone
		(layer "In1.Cu")
		(hatch none 0.5)
		(connect_pads
			(clearance 0)
		)
		(min_thickness 0.25)
		(keepout
			(tracks not_allowed)
			(vias allowed)
			(pads allowed)
			(copperpour not_allowed)
			(footprints allowed)
		)
		(placement
			(enabled no)
			(sheetname "")
		)
		(fill
			(thermal_gap 0.5)
			(thermal_bridge_width 0.5)
			(island_removal_mode 0)
		)
		(polygon
			(pts
				(arc
					(start 18.357342 -220.532452)
					(mid 18.353622 -220.541432)
					(end 18.344642 -220.545152)
				)
				(arc
					(start 16.871442 -220.545152)
					(mid 16.862462 -220.541432)
					(end 16.858742 -220.532452)
				)
				(arc
					(start 16.858742 -220.037914)
					(mid 16.862462 -220.028934)
					(end 16.871442 -220.025214)
				)
				(arc
					(start 18.344642 -220.025214)
					(mid 18.353622 -220.028934)
					(end 18.357342 -220.037914)
				)
			)
		)
	)
	(zone
		(layer "In1.Cu")
		(hatch none 0.5)
		(connect_pads
			(clearance 0)
		)
		(min_thickness 0.25)
		(keepout
			(tracks not_allowed)
			(vias allowed)
			(pads allowed)
			(copperpour not_allowed)
			(footprints allowed)
		)
		(placement
			(enabled no)
			(sheetname "")
		)
		(fill
			(thermal_gap 0.5)
			(thermal_bridge_width 0.5)
			(island_removal_mode 0)
		)
		(polygon
			(pts
				(arc
					(start 300.57344 -205.232254)
					(mid 300.56972 -205.241234)
					(end 300.56074 -205.244954)
				)
				(arc
					(start 299.08754 -205.244954)
					(mid 299.07856 -205.241234)
					(end 299.07484 -205.232254)
				)
				(arc
					(start 299.07484 -204.737716)
					(mid 299.07856 -204.728736)
					(end 299.08754 -204.725016)
				)
				(arc
					(start 300.56074 -204.725016)
					(mid 300.56972 -204.728736)
					(end 300.57344 -204.737716)
				)
			)
		)
	)
	(zone
		(layer "In1.Cu")
		(hatch none 0.5)
		(connect_pads
			(clearance 0)
		)
		(min_thickness 0.25)
		(keepout
			(tracks not_allowed)
			(vias allowed)
			(pads allowed)
			(copperpour not_allowed)
			(footprints allowed)
		)
		(placement
			(enabled no)
			(sheetname "")
		)
		(fill
			(thermal_gap 0.5)
			(thermal_bridge_width 0.5)
			(island_removal_mode 0)
		)
		(polygon
			(pts
				(arc
					(start 296.473372 -304.682144)
					(mid 296.469652 -304.691124)
					(end 296.460672 -304.694844)
				)
				(arc
					(start 294.987472 -304.694844)
					(mid 294.978492 -304.691124)
					(end 294.974772 -304.682144)
				)
				(arc
					(start 294.974772 -304.187606)
					(mid 294.978492 -304.178626)
					(end 294.987472 -304.174906)
				)
				(arc
					(start 296.460672 -304.174906)
					(mid 296.469652 -304.178626)
					(end 296.473372 -304.187606)
				)
			)
		)
	)
	(zone
		(layer "In1.Cu")
		(hatch none 0.5)
		(connect_pads
			(clearance 0)
		)
		(min_thickness 0.25)
		(keepout
			(tracks not_allowed)
			(vias allowed)
			(pads allowed)
			(copperpour not_allowed)
			(footprints allowed)
		)
		(placement
			(enabled no)
			(sheetname "")
		)
		(fill
			(thermal_gap 0.5)
			(thermal_bridge_width 0.5)
			(island_removal_mode 0)
		)
		(polygon
			(pts
				(arc
					(start 199.4535 -270.682466)
					(mid 199.44978 -270.691446)
					(end 199.4408 -270.695166)
				)
				(arc
					(start 197.9676 -270.695166)
					(mid 197.95862 -270.691446)
					(end 197.9549 -270.682466)
				)
				(arc
					(start 197.9549 -270.187928)
					(mid 197.95862 -270.178948)
					(end 197.9676 -270.175228)
				)
				(arc
					(start 199.4408 -270.175228)
					(mid 199.44978 -270.178948)
					(end 199.4535 -270.187928)
				)
			)
		)
	)
	(zone
		(layer "In1.Cu")
		(hatch none 0.5)
		(connect_pads
			(clearance 0)
		)
		(min_thickness 0.25)
		(keepout
			(tracks not_allowed)
			(vias allowed)
			(pads allowed)
			(copperpour not_allowed)
			(footprints allowed)
		)
		(placement
			(enabled no)
			(sheetname "")
		)
		(fill
			(thermal_gap 0.5)
			(thermal_bridge_width 0.5)
			(island_removal_mode 0)
		)
		(polygon
			(pts
				(arc
					(start 206.9973 -205.232508)
					(mid 206.99358 -205.241488)
					(end 206.9846 -205.245208)
				)
				(arc
					(start 205.5114 -205.245208)
					(mid 205.50242 -205.241488)
					(end 205.4987 -205.232508)
				)
				(arc
					(start 205.4987 -204.73797)
					(mid 205.50242 -204.72899)
					(end 205.5114 -204.72527)
				)
				(arc
					(start 206.9846 -204.72527)
					(mid 206.99358 -204.72899)
					(end 206.9973 -204.73797)
				)
			)
		)
	)
	(zone
		(layer "In1.Cu")
		(hatch none 0.5)
		(connect_pads
			(clearance 0)
		)
		(min_thickness 0.25)
		(keepout
			(tracks not_allowed)
			(vias allowed)
			(pads allowed)
			(copperpour not_allowed)
			(footprints allowed)
		)
		(placement
			(enabled no)
			(sheetname "")
		)
		(fill
			(thermal_gap 0.5)
			(thermal_bridge_width 0.5)
			(island_removal_mode 0)
		)
		(polygon
			(pts
				(arc
					(start 281.385264 -241.782092)
					(mid 281.381544 -241.791072)
					(end 281.372564 -241.794792)
				)
				(arc
					(start 279.899364 -241.794792)
					(mid 279.890384 -241.791072)
					(end 279.886664 -241.782092)
				)
				(arc
					(start 279.886664 -241.287554)
					(mid 279.890384 -241.278574)
					(end 279.899364 -241.274854)
				)
				(arc
					(start 281.372564 -241.274854)
					(mid 281.381544 -241.278574)
					(end 281.385264 -241.287554)
				)
			)
		)
	)
	(zone
		(layer "In1.Cu")
		(hatch none 0.5)
		(connect_pads
			(clearance 0)
		)
		(min_thickness 0.25)
		(keepout
			(tracks not_allowed)
			(vias allowed)
			(pads allowed)
			(copperpour not_allowed)
			(footprints allowed)
		)
		(placement
			(enabled no)
			(sheetname "")
		)
		(fill
			(thermal_gap 0.5)
			(thermal_bridge_width 0.5)
			(island_removal_mode 0)
		)
		(polygon
			(pts
				(arc
					(start 281.385264 -239.232186)
					(mid 281.381544 -239.241166)
					(end 281.372564 -239.244886)
				)
				(arc
					(start 279.899364 -239.244886)
					(mid 279.890384 -239.241166)
					(end 279.886664 -239.232186)
				)
				(arc
					(start 279.886664 -238.737648)
					(mid 279.890384 -238.728668)
					(end 279.899364 -238.724948)
				)
				(arc
					(start 281.372564 -238.724948)
					(mid 281.381544 -238.728668)
					(end 281.385264 -238.737648)
				)
			)
		)
	)
	(zone
		(layer "In1.Cu")
		(hatch none 0.5)
		(connect_pads
			(clearance 0)
		)
		(min_thickness 0.25)
		(keepout
			(tracks not_allowed)
			(vias allowed)
			(pads allowed)
			(copperpour not_allowed)
			(footprints allowed)
		)
		(placement
			(enabled no)
			(sheetname "")
		)
		(fill
			(thermal_gap 0.5)
			(thermal_bridge_width 0.5)
			(island_removal_mode 0)
		)
		(polygon
			(pts
				(arc
					(start 37.545264 -225.632518)
					(mid 37.541544 -225.641498)
					(end 37.532564 -225.645218)
				)
				(arc
					(start 36.059364 -225.645218)
					(mid 36.050384 -225.641498)
					(end 36.046664 -225.632518)
				)
				(arc
					(start 36.046664 -225.13798)
					(mid 36.050384 -225.129)
					(end 36.059364 -225.12528)
				)
				(arc
					(start 37.532564 -225.12528)
					(mid 37.541544 -225.129)
					(end 37.545264 -225.13798)
				)
			)
		)
	)
	(zone
		(layer "In1.Cu")
		(hatch none 0.5)
		(connect_pads
			(clearance 0)
		)
		(min_thickness 0.25)
		(keepout
			(tracks not_allowed)
			(vias allowed)
			(pads allowed)
			(copperpour not_allowed)
			(footprints allowed)
		)
		(placement
			(enabled no)
			(sheetname "")
		)
		(fill
			(thermal_gap 0.5)
			(thermal_bridge_width 0.5)
			(island_removal_mode 0)
		)
		(polygon
			(pts
				(arc
					(start 450.8373 -265.582146)
					(mid 450.83358 -265.591126)
					(end 450.8246 -265.594846)
				)
				(arc
					(start 449.3514 -265.594846)
					(mid 449.34242 -265.591126)
					(end 449.3387 -265.582146)
				)
				(arc
					(start 449.3387 -265.087608)
					(mid 449.34242 -265.078628)
					(end 449.3514 -265.074908)
				)
				(arc
					(start 450.8246 -265.074908)
					(mid 450.83358 -265.078628)
					(end 450.8373 -265.087608)
				)
			)
		)
	)
	(zone
		(layer "In1.Cu")
		(hatch none 0.5)
		(connect_pads
			(clearance 0)
		)
		(min_thickness 0.25)
		(keepout
			(tracks not_allowed)
			(vias allowed)
			(pads allowed)
			(copperpour not_allowed)
			(footprints allowed)
		)
		(placement
			(enabled no)
			(sheetname "")
		)
		(fill
			(thermal_gap 0.5)
			(thermal_bridge_width 0.5)
			(island_removal_mode 0)
		)
		(polygon
			(pts
				(arc
					(start 184.365392 -200.98258)
					(mid 184.361672 -200.99156)
					(end 184.352692 -200.99528)
				)
				(arc
					(start 182.879492 -200.99528)
					(mid 182.870512 -200.99156)
					(end 182.866792 -200.98258)
				)
				(arc
					(start 182.866792 -200.488042)
					(mid 182.870512 -200.479062)
					(end 182.879492 -200.475342)
				)
				(arc
					(start 184.352692 -200.475342)
					(mid 184.361672 -200.479062)
					(end 184.365392 -200.488042)
				)
			)
		)
	)
	(zone
		(layer "In1.Cu")
		(hatch none 0.5)
		(connect_pads
			(clearance 0)
		)
		(min_thickness 0.25)
		(keepout
			(tracks not_allowed)
			(vias allowed)
			(pads allowed)
			(copperpour not_allowed)
			(footprints allowed)
		)
		(placement
			(enabled no)
			(sheetname "")
		)
		(fill
			(thermal_gap 0.5)
			(thermal_bridge_width 0.5)
			(island_removal_mode 0)
		)
		(polygon
			(pts
				(arc
					(start 30.001464 -261.332472)
					(mid 29.997744 -261.341452)
					(end 29.988764 -261.345172)
				)
				(arc
					(start 28.515564 -261.345172)
					(mid 28.506584 -261.341452)
					(end 28.502864 -261.332472)
				)
				(arc
					(start 28.502864 -260.837934)
					(mid 28.506584 -260.828954)
					(end 28.515564 -260.825234)
				)
				(arc
					(start 29.988764 -260.825234)
					(mid 29.997744 -260.828954)
					(end 30.001464 -260.837934)
				)
			)
		)
	)
	(zone
		(layer "In1.Cu")
		(hatch none 0.5)
		(connect_pads
			(clearance 0)
		)
		(min_thickness 0.25)
		(keepout
			(tracks not_allowed)
			(vias allowed)
			(pads allowed)
			(copperpour not_allowed)
			(footprints allowed)
		)
		(placement
			(enabled no)
			(sheetname "")
		)
		(fill
			(thermal_gap 0.5)
			(thermal_bridge_width 0.5)
			(island_removal_mode 0)
		)
		(polygon
			(pts
				(arc
					(start 270.397478 -308.082188)
					(mid 270.393758 -308.091168)
					(end 270.384778 -308.094888)
				)
				(arc
					(start 268.911578 -308.094888)
					(mid 268.902598 -308.091168)
					(end 268.898878 -308.082188)
				)
				(arc
					(start 268.898878 -307.58765)
					(mid 268.902598 -307.57867)
					(end 268.911578 -307.57495)
				)
				(arc
					(start 270.384778 -307.57495)
					(mid 270.393758 -307.57867)
					(end 270.397478 -307.58765)
				)
			)
		)
	)
	(zone
		(layer "In1.Cu")
		(hatch none 0.5)
		(connect_pads
			(clearance 0)
		)
		(min_thickness 0.25)
		(keepout
			(tracks not_allowed)
			(vias allowed)
			(pads allowed)
			(copperpour not_allowed)
			(footprints allowed)
		)
		(placement
			(enabled no)
			(sheetname "")
		)
		(fill
			(thermal_gap 0.5)
			(thermal_bridge_width 0.5)
			(island_removal_mode 0)
		)
		(polygon
			(pts
				(arc
					(start 416.288982 -393.69238)
					(mid 415.907982 -393.69238)
					(end 416.288982 -393.69238)
				)
			)
		)
	)
	(zone
		(layer "In1.Cu")
		(hatch none 0.5)
		(connect_pads
			(clearance 0)
		)
		(min_thickness 0.25)
		(keepout
			(tracks not_allowed)
			(vias allowed)
			(pads allowed)
			(copperpour not_allowed)
			(footprints allowed)
		)
		(placement
			(enabled no)
			(sheetname "")
		)
		(fill
			(thermal_gap 0.5)
			(thermal_bridge_width 0.5)
			(island_removal_mode 0)
		)
		(polygon
			(pts
				(arc
					(start 48.533304 -314.032392)
					(mid 48.529584 -314.041372)
					(end 48.520604 -314.045092)
				)
				(arc
					(start 47.047404 -314.045092)
					(mid 47.038424 -314.041372)
					(end 47.034704 -314.032392)
				)
				(arc
					(start 47.034704 -313.537854)
					(mid 47.038424 -313.528874)
					(end 47.047404 -313.525154)
				)
				(arc
					(start 48.520604 -313.525154)
					(mid 48.529584 -313.528874)
					(end 48.533304 -313.537854)
				)
			)
		)
	)
	(zone
		(layer "In1.Cu")
		(hatch none 0.5)
		(connect_pads
			(clearance 0)
		)
		(min_thickness 0.25)
		(keepout
			(tracks not_allowed)
			(vias allowed)
			(pads allowed)
			(copperpour not_allowed)
			(footprints allowed)
		)
		(placement
			(enabled no)
			(sheetname "")
		)
		(fill
			(thermal_gap 0.5)
			(thermal_bridge_width 0.5)
			(island_removal_mode 0)
		)
		(polygon
			(pts
				(arc
					(start 420.661338 -318.28232)
					(mid 420.657618 -318.2913)
					(end 420.648638 -318.29502)
				)
				(arc
					(start 419.175438 -318.29502)
					(mid 419.166458 -318.2913)
					(end 419.162738 -318.28232)
				)
				(arc
					(start 419.162738 -317.787782)
					(mid 419.166458 -317.778802)
					(end 419.175438 -317.775082)
				)
				(arc
					(start 420.648638 -317.775082)
					(mid 420.657618 -317.778802)
					(end 420.661338 -317.787782)
				)
			)
		)
	)
	(zone
		(layer "In1.Cu")
		(hatch none 0.5)
		(connect_pads
			(clearance 0)
		)
		(min_thickness 0.25)
		(keepout
			(tracks not_allowed)
			(vias allowed)
			(pads allowed)
			(copperpour not_allowed)
			(footprints allowed)
		)
		(placement
			(enabled no)
			(sheetname "")
		)
		(fill
			(thermal_gap 0.5)
			(thermal_bridge_width 0.5)
			(island_removal_mode 0)
		)
		(polygon
			(pts
				(arc
					(start 435.749446 -207.78216)
					(mid 435.745726 -207.79114)
					(end 435.736746 -207.79486)
				)
				(arc
					(start 434.263546 -207.79486)
					(mid 434.254566 -207.79114)
					(end 434.250846 -207.78216)
				)
				(arc
					(start 434.250846 -207.287622)
					(mid 434.254566 -207.278642)
					(end 434.263546 -207.274922)
				)
				(arc
					(start 435.736746 -207.274922)
					(mid 435.745726 -207.278642)
					(end 435.749446 -207.287622)
				)
			)
		)
	)
	(zone
		(layer "In1.Cu")
		(hatch none 0.5)
		(connect_pads
			(clearance 0)
		)
		(min_thickness 0.25)
		(keepout
			(tracks not_allowed)
			(vias allowed)
			(pads allowed)
			(copperpour not_allowed)
			(footprints allowed)
		)
		(placement
			(enabled no)
			(sheetname "")
		)
		(fill
			(thermal_gap 0.5)
			(thermal_bridge_width 0.5)
			(island_removal_mode 0)
		)
		(polygon
			(pts
				(arc
					(start 373.36095 -397.849344)
					(mid 372.97995 -397.849344)
					(end 373.36095 -397.849344)
				)
			)
		)
	)
	(zone
		(layer "In1.Cu")
		(hatch none 0.5)
		(connect_pads
			(clearance 0)
		)
		(min_thickness 0.25)
		(keepout
			(tracks not_allowed)
			(vias allowed)
			(pads allowed)
			(copperpour not_allowed)
			(footprints allowed)
		)
		(placement
			(enabled no)
			(sheetname "")
		)
		(fill
			(thermal_gap 0.5)
			(thermal_bridge_width 0.5)
			(island_removal_mode 0)
		)
		(polygon
			(pts
				(arc
					(start 165.198044 -390.761474)
					(mid 164.893244 -390.761474)
					(end 165.198044 -390.761474)
				)
			)
		)
	)
	(zone
		(layer "In1.Cu")
		(hatch none 0.5)
		(connect_pads
			(clearance 0)
		)
		(min_thickness 0.25)
		(keepout
			(tracks not_allowed)
			(vias allowed)
			(pads allowed)
			(copperpour not_allowed)
			(footprints allowed)
		)
		(placement
			(enabled no)
			(sheetname "")
		)
		(fill
			(thermal_gap 0.5)
			(thermal_bridge_width 0.5)
			(island_removal_mode 0)
		)
		(polygon
			(pts
				(arc
					(start 184.365392 -309.782464)
					(mid 184.361672 -309.791444)
					(end 184.352692 -309.795164)
				)
				(arc
					(start 182.879492 -309.795164)
					(mid 182.870512 -309.791444)
					(end 182.866792 -309.782464)
				)
				(arc
					(start 182.866792 -309.287926)
					(mid 182.870512 -309.278946)
					(end 182.879492 -309.275226)
				)
				(arc
					(start 184.352692 -309.275226)
					(mid 184.361672 -309.278946)
					(end 184.365392 -309.287926)
				)
			)
		)
	)
	(zone
		(layer "In1.Cu")
		(hatch none 0.5)
		(connect_pads
			(clearance 0)
		)
		(min_thickness 0.25)
		(keepout
			(tracks not_allowed)
			(vias allowed)
			(pads allowed)
			(copperpour not_allowed)
			(footprints allowed)
		)
		(placement
			(enabled no)
			(sheetname "")
		)
		(fill
			(thermal_gap 0.5)
			(thermal_bridge_width 0.5)
			(island_removal_mode 0)
		)
		(polygon
			(pts
				(arc
					(start 199.4535 -214.582502)
					(mid 199.44978 -214.591482)
					(end 199.4408 -214.595202)
				)
				(arc
					(start 197.9676 -214.595202)
					(mid 197.95862 -214.591482)
					(end 197.9549 -214.582502)
				)
				(arc
					(start 197.9549 -214.087964)
					(mid 197.95862 -214.078984)
					(end 197.9676 -214.075264)
				)
				(arc
					(start 199.4408 -214.075264)
					(mid 199.44978 -214.078984)
					(end 199.4535 -214.087964)
				)
			)
		)
	)
	(zone
		(layer "In1.Cu")
		(hatch none 0.5)
		(connect_pads
			(clearance 0)
		)
		(min_thickness 0.25)
		(keepout
			(tracks not_allowed)
			(vias allowed)
			(pads allowed)
			(copperpour not_allowed)
			(footprints allowed)
		)
		(placement
			(enabled no)
			(sheetname "")
		)
		(fill
			(thermal_gap 0.5)
			(thermal_bridge_width 0.5)
			(island_removal_mode 0)
		)
		(polygon
			(pts
				(arc
					(start 48.533304 -284.282388)
					(mid 48.529584 -284.291368)
					(end 48.520604 -284.295088)
				)
				(arc
					(start 47.047404 -284.295088)
					(mid 47.038424 -284.291368)
					(end 47.034704 -284.282388)
				)
				(arc
					(start 47.034704 -283.78785)
					(mid 47.038424 -283.77887)
					(end 47.047404 -283.77515)
				)
				(arc
					(start 48.520604 -283.77515)
					(mid 48.529584 -283.77887)
					(end 48.533304 -283.78785)
				)
			)
		)
	)
	(zone
		(layer "In1.Cu")
		(hatch none 0.5)
		(connect_pads
			(clearance 0)
		)
		(min_thickness 0.25)
		(keepout
			(tracks not_allowed)
			(vias allowed)
			(pads allowed)
			(copperpour not_allowed)
			(footprints allowed)
		)
		(placement
			(enabled no)
			(sheetname "")
		)
		(fill
			(thermal_gap 0.5)
			(thermal_bridge_width 0.5)
			(island_removal_mode 0)
		)
		(polygon
			(pts
				(arc
					(start 288.929318 -267.282168)
					(mid 288.925598 -267.291148)
					(end 288.916618 -267.294868)
				)
				(arc
					(start 287.443418 -267.294868)
					(mid 287.434438 -267.291148)
					(end 287.430718 -267.282168)
				)
				(arc
					(start 287.430718 -266.78763)
					(mid 287.434438 -266.77865)
					(end 287.443418 -266.77493)
				)
				(arc
					(start 288.916618 -266.77493)
					(mid 288.925598 -266.77865)
					(end 288.929318 -266.78763)
				)
			)
		)
	)
	(zone
		(layer "In1.Cu")
		(hatch none 0.5)
		(connect_pads
			(clearance 0)
		)
		(min_thickness 0.25)
		(keepout
			(tracks not_allowed)
			(vias allowed)
			(pads allowed)
			(copperpour not_allowed)
			(footprints allowed)
		)
		(placement
			(enabled no)
			(sheetname "")
		)
		(fill
			(thermal_gap 0.5)
			(thermal_bridge_width 0.5)
			(island_removal_mode 0)
		)
		(polygon
			(pts
				(arc
					(start 52.633372 -205.232508)
					(mid 52.629652 -205.241488)
					(end 52.620672 -205.245208)
				)
				(arc
					(start 51.147472 -205.245208)
					(mid 51.138492 -205.241488)
					(end 51.134772 -205.232508)
				)
				(arc
					(start 51.134772 -204.73797)
					(mid 51.138492 -204.72899)
					(end 51.147472 -204.72527)
				)
				(arc
					(start 52.620672 -204.72527)
					(mid 52.629652 -204.72899)
					(end 52.633372 -204.73797)
				)
			)
		)
	)
	(zone
		(layer "In1.Cu")
		(hatch none 0.5)
		(connect_pads
			(clearance 0)
		)
		(min_thickness 0.25)
		(keepout
			(tracks not_allowed)
			(vias allowed)
			(pads allowed)
			(copperpour not_allowed)
			(footprints allowed)
		)
		(placement
			(enabled no)
			(sheetname "")
		)
		(fill
			(thermal_gap 0.5)
			(thermal_bridge_width 0.5)
			(island_removal_mode 0)
		)
		(polygon
			(pts
				(arc
					(start 417.217352 -229.882192)
					(mid 417.213632 -229.891172)
					(end 417.204652 -229.894892)
				)
				(arc
					(start 415.731452 -229.894892)
					(mid 415.722472 -229.891172)
					(end 415.718752 -229.882192)
				)
				(arc
					(start 415.718752 -229.387654)
					(mid 415.722472 -229.378674)
					(end 415.731452 -229.374954)
				)
				(arc
					(start 417.204652 -229.374954)
					(mid 417.213632 -229.378674)
					(end 417.217352 -229.387654)
				)
			)
		)
	)
	(zone
		(layer "In1.Cu")
		(hatch none 0.5)
		(connect_pads
			(clearance 0)
		)
		(min_thickness 0.25)
		(keepout
			(tracks not_allowed)
			(vias allowed)
			(pads allowed)
			(copperpour not_allowed)
			(footprints allowed)
		)
		(placement
			(enabled no)
			(sheetname "")
		)
		(fill
			(thermal_gap 0.5)
			(thermal_bridge_width 0.5)
			(island_removal_mode 0)
		)
		(polygon
			(pts
				(arc
					(start 56.077358 -223.082358)
					(mid 56.073638 -223.091338)
					(end 56.064658 -223.095058)
				)
				(arc
					(start 54.591458 -223.095058)
					(mid 54.582478 -223.091338)
					(end 54.578758 -223.082358)
				)
				(arc
					(start 54.578758 -222.58782)
					(mid 54.582478 -222.57884)
					(end 54.591458 -222.57512)
				)
				(arc
					(start 56.064658 -222.57512)
					(mid 56.073638 -222.57884)
					(end 56.077358 -222.58782)
				)
			)
		)
	)
	(zone
		(layer "In1.Cu")
		(hatch none 0.5)
		(connect_pads
			(clearance 0)
		)
		(min_thickness 0.25)
		(keepout
			(tracks not_allowed)
			(vias allowed)
			(pads allowed)
			(copperpour not_allowed)
			(footprints allowed)
		)
		(placement
			(enabled no)
			(sheetname "")
		)
		(fill
			(thermal_gap 0.5)
			(thermal_bridge_width 0.5)
			(island_removal_mode 0)
		)
		(polygon
			(pts
				(arc
					(start 25.901396 -318.282574)
					(mid 25.897676 -318.291554)
					(end 25.888696 -318.295274)
				)
				(arc
					(start 24.415496 -318.295274)
					(mid 24.406516 -318.291554)
					(end 24.402796 -318.282574)
				)
				(arc
					(start 24.402796 -317.788036)
					(mid 24.406516 -317.779056)
					(end 24.415496 -317.775336)
				)
				(arc
					(start 25.888696 -317.775336)
					(mid 25.897676 -317.779056)
					(end 25.901396 -317.788036)
				)
			)
		)
	)
	(zone
		(layer "In1.Cu")
		(hatch none 0.5)
		(connect_pads
			(clearance 0)
		)
		(min_thickness 0.25)
		(keepout
			(tracks not_allowed)
			(vias allowed)
			(pads allowed)
			(copperpour not_allowed)
			(footprints allowed)
		)
		(placement
			(enabled no)
			(sheetname "")
		)
		(fill
			(thermal_gap 0.5)
			(thermal_bridge_width 0.5)
			(island_removal_mode 0)
		)
		(polygon
			(pts
				(arc
					(start 46.991016 -383.440686)
					(mid 47.118016 -383.567686)
					(end 47.245016 -383.440686)
				)
				(arc
					(start 47.245016 -383.364486)
					(mid 47.118016 -383.237486)
					(end 46.991016 -383.364486)
				)
			)
		)
	)
	(zone
		(layer "In1.Cu")
		(hatch none 0.5)
		(connect_pads
			(clearance 0)
		)
		(min_thickness 0.25)
		(keepout
			(tracks not_allowed)
			(vias allowed)
			(pads allowed)
			(copperpour not_allowed)
			(footprints allowed)
		)
		(placement
			(enabled no)
			(sheetname "")
		)
		(fill
			(thermal_gap 0.5)
			(thermal_bridge_width 0.5)
			(island_removal_mode 0)
		)
		(polygon
			(pts
				(arc
					(start 48.533304 -251.982478)
					(mid 48.529584 -251.991458)
					(end 48.520604 -251.995178)
				)
				(arc
					(start 47.047404 -251.995178)
					(mid 47.038424 -251.991458)
					(end 47.034704 -251.982478)
				)
				(arc
					(start 47.034704 -251.48794)
					(mid 47.038424 -251.47896)
					(end 47.047404 -251.47524)
				)
				(arc
					(start 48.520604 -251.47524)
					(mid 48.529584 -251.47896)
					(end 48.533304 -251.48794)
				)
			)
		)
	)
	(zone
		(layer "In1.Cu")
		(hatch none 0.5)
		(connect_pads
			(clearance 0)
		)
		(min_thickness 0.25)
		(keepout
			(tracks not_allowed)
			(vias allowed)
			(pads allowed)
			(copperpour not_allowed)
			(footprints allowed)
		)
		(placement
			(enabled no)
			(sheetname "")
		)
		(fill
			(thermal_gap 0.5)
			(thermal_bridge_width 0.5)
			(island_removal_mode 0)
		)
		(polygon
			(pts
				(arc
					(start 40.98925 -299.582586)
					(mid 40.98553 -299.591566)
					(end 40.97655 -299.595286)
				)
				(arc
					(start 39.50335 -299.595286)
					(mid 39.49437 -299.591566)
					(end 39.49065 -299.582586)
				)
				(arc
					(start 39.49065 -299.088048)
					(mid 39.49437 -299.079068)
					(end 39.50335 -299.075348)
				)
				(arc
					(start 40.97655 -299.075348)
					(mid 40.98553 -299.079068)
					(end 40.98925 -299.088048)
				)
			)
		)
	)
	(zone
		(layer "In1.Cu")
		(hatch none 0.5)
		(connect_pads
			(clearance 0)
		)
		(min_thickness 0.25)
		(keepout
			(tracks not_allowed)
			(vias allowed)
			(pads allowed)
			(copperpour not_allowed)
			(footprints allowed)
		)
		(placement
			(enabled no)
			(sheetname "")
		)
		(fill
			(thermal_gap 0.5)
			(thermal_bridge_width 0.5)
			(island_removal_mode 0)
		)
		(polygon
			(pts
				(arc
					(start 60.177426 -247.73255)
					(mid 60.173706 -247.74153)
					(end 60.164726 -247.74525)
				)
				(arc
					(start 58.691526 -247.74525)
					(mid 58.682546 -247.74153)
					(end 58.678826 -247.73255)
				)
				(arc
					(start 58.678826 -247.238012)
					(mid 58.682546 -247.229032)
					(end 58.691526 -247.225312)
				)
				(arc
					(start 60.164726 -247.225312)
					(mid 60.173706 -247.229032)
					(end 60.177426 -247.238012)
				)
			)
		)
	)
	(zone
		(layer "In1.Cu")
		(hatch none 0.5)
		(connect_pads
			(clearance 0)
		)
		(min_thickness 0.25)
		(keepout
			(tracks not_allowed)
			(vias allowed)
			(pads allowed)
			(copperpour not_allowed)
			(footprints allowed)
		)
		(placement
			(enabled no)
			(sheetname "")
		)
		(fill
			(thermal_gap 0.5)
			(thermal_bridge_width 0.5)
			(island_removal_mode 0)
		)
		(polygon
			(pts
				(arc
					(start 206.5782 -261.08533)
					(mid 205.9178 -261.08533)
					(end 206.5782 -261.08533)
				)
			)
		)
	)
	(zone
		(layer "In1.Cu")
		(hatch none 0.5)
		(connect_pads
			(clearance 0)
		)
		(min_thickness 0.25)
		(keepout
			(tracks not_allowed)
			(vias allowed)
			(pads allowed)
			(copperpour not_allowed)
			(footprints allowed)
		)
		(placement
			(enabled no)
			(sheetname "")
		)
		(fill
			(thermal_gap 0.5)
			(thermal_bridge_width 0.5)
			(island_removal_mode 0)
		)
		(polygon
			(pts
				(arc
					(start 169.277284 -263.032494)
					(mid 169.273564 -263.041474)
					(end 169.264584 -263.045194)
				)
				(arc
					(start 167.791384 -263.045194)
					(mid 167.782404 -263.041474)
					(end 167.778684 -263.032494)
				)
				(arc
					(start 167.778684 -262.537956)
					(mid 167.782404 -262.528976)
					(end 167.791384 -262.525256)
				)
				(arc
					(start 169.264584 -262.525256)
					(mid 169.273564 -262.528976)
					(end 169.277284 -262.537956)
				)
			)
		)
	)
	(zone
		(layer "In1.Cu")
		(hatch none 0.5)
		(connect_pads
			(clearance 0)
		)
		(min_thickness 0.25)
		(keepout
			(tracks not_allowed)
			(vias allowed)
			(pads allowed)
			(copperpour not_allowed)
			(footprints allowed)
		)
		(placement
			(enabled no)
			(sheetname "")
		)
		(fill
			(thermal_gap 0.5)
			(thermal_bridge_width 0.5)
			(island_removal_mode 0)
		)
		(polygon
			(pts
				(arc
					(start 121.87047 -390.761474)
					(mid 121.56567 -390.761474)
					(end 121.87047 -390.761474)
				)
			)
		)
	)
	(zone
		(layer "In1.Cu")
		(hatch none 0.5)
		(connect_pads
			(clearance 0)
		)
		(min_thickness 0.25)
		(keepout
			(tracks not_allowed)
			(vias allowed)
			(pads allowed)
			(copperpour not_allowed)
			(footprints allowed)
		)
		(placement
			(enabled no)
			(sheetname "")
		)
		(fill
			(thermal_gap 0.5)
			(thermal_bridge_width 0.5)
			(island_removal_mode 0)
		)
		(polygon
			(pts
				(arc
					(start 265.87831 -216.885012)
					(mid 265.21791 -216.885012)
					(end 265.87831 -216.885012)
				)
			)
		)
	)
	(zone
		(layer "In1.Cu")
		(hatch none 0.5)
		(connect_pads
			(clearance 0)
		)
		(min_thickness 0.25)
		(keepout
			(tracks not_allowed)
			(vias allowed)
			(pads allowed)
			(copperpour not_allowed)
			(footprints allowed)
		)
		(placement
			(enabled no)
			(sheetname "")
		)
		(fill
			(thermal_gap 0.5)
			(thermal_bridge_width 0.5)
			(island_removal_mode 0)
		)
		(polygon
			(pts
				(arc
					(start 60.177426 -283.432504)
					(mid 60.173706 -283.441484)
					(end 60.164726 -283.445204)
				)
				(arc
					(start 58.691526 -283.445204)
					(mid 58.682546 -283.441484)
					(end 58.678826 -283.432504)
				)
				(arc
					(start 58.678826 -282.937966)
					(mid 58.682546 -282.928986)
					(end 58.691526 -282.925266)
				)
				(arc
					(start 60.164726 -282.925266)
					(mid 60.173706 -282.928986)
					(end 60.177426 -282.937966)
				)
			)
		)
	)
	(zone
		(layer "In1.Cu")
		(hatch none 0.5)
		(connect_pads
			(clearance 0)
		)
		(min_thickness 0.25)
		(keepout
			(tracks not_allowed)
			(vias allowed)
			(pads allowed)
			(copperpour not_allowed)
			(footprints allowed)
		)
		(placement
			(enabled no)
			(sheetname "")
		)
		(fill
			(thermal_gap 0.5)
			(thermal_bridge_width 0.5)
			(island_removal_mode 0)
		)
		(polygon
			(pts
				(arc
					(start 162.689032 -388.774432)
					(mid 162.308032 -388.774432)
					(end 162.689032 -388.774432)
				)
			)
		)
	)
	(zone
		(layer "In1.Cu")
		(hatch none 0.5)
		(connect_pads
			(clearance 0)
		)
		(min_thickness 0.25)
		(keepout
			(tracks not_allowed)
			(vias allowed)
			(pads allowed)
			(copperpour not_allowed)
			(footprints allowed)
		)
		(placement
			(enabled no)
			(sheetname "")
		)
		(fill
			(thermal_gap 0.5)
			(thermal_bridge_width 0.5)
			(island_removal_mode 0)
		)
		(polygon
			(pts
				(arc
					(start 25.901396 -251.982478)
					(mid 25.897676 -251.991458)
					(end 25.888696 -251.995178)
				)
				(arc
					(start 24.415496 -251.995178)
					(mid 24.406516 -251.991458)
					(end 24.402796 -251.982478)
				)
				(arc
					(start 24.402796 -251.48794)
					(mid 24.406516 -251.47896)
					(end 24.415496 -251.47524)
				)
				(arc
					(start 25.888696 -251.47524)
					(mid 25.897676 -251.47896)
					(end 25.901396 -251.48794)
				)
			)
		)
	)
	(zone
		(layer "In1.Cu")
		(hatch none 0.5)
		(connect_pads
			(clearance 0)
		)
		(min_thickness 0.25)
		(keepout
			(tracks not_allowed)
			(vias allowed)
			(pads allowed)
			(copperpour not_allowed)
			(footprints allowed)
		)
		(placement
			(enabled no)
			(sheetname "")
		)
		(fill
			(thermal_gap 0.5)
			(thermal_bridge_width 0.5)
			(island_removal_mode 0)
		)
		(polygon
			(pts
				(arc
					(start 424.761406 -276.632162)
					(mid 424.757686 -276.641142)
					(end 424.748706 -276.644862)
				)
				(arc
					(start 423.275506 -276.644862)
					(mid 423.266526 -276.641142)
					(end 423.262806 -276.632162)
				)
				(arc
					(start 423.262806 -276.137624)
					(mid 423.266526 -276.128644)
					(end 423.275506 -276.124924)
				)
				(arc
					(start 424.748706 -276.124924)
					(mid 424.757686 -276.128644)
					(end 424.761406 -276.137624)
				)
			)
		)
	)
	(zone
		(layer "In1.Cu")
		(hatch none 0.5)
		(connect_pads
			(clearance 0)
		)
		(min_thickness 0.25)
		(keepout
			(tracks not_allowed)
			(vias allowed)
			(pads allowed)
			(copperpour not_allowed)
			(footprints allowed)
		)
		(placement
			(enabled no)
			(sheetname "")
		)
		(fill
			(thermal_gap 0.5)
			(thermal_bridge_width 0.5)
			(island_removal_mode 0)
		)
		(polygon
			(pts
				(arc
					(start 206.9973 -216.282524)
					(mid 206.99358 -216.291504)
					(end 206.9846 -216.295224)
				)
				(arc
					(start 205.5114 -216.295224)
					(mid 205.50242 -216.291504)
					(end 205.4987 -216.282524)
				)
				(arc
					(start 205.4987 -215.787986)
					(mid 205.50242 -215.779006)
					(end 205.5114 -215.775286)
				)
				(arc
					(start 206.9846 -215.775286)
					(mid 206.99358 -215.779006)
					(end 206.9973 -215.787986)
				)
			)
		)
	)
	(zone
		(layer "In1.Cu")
		(hatch none 0.5)
		(connect_pads
			(clearance 0)
		)
		(min_thickness 0.25)
		(keepout
			(tracks not_allowed)
			(vias allowed)
			(pads allowed)
			(copperpour not_allowed)
			(footprints allowed)
		)
		(placement
			(enabled no)
			(sheetname "")
		)
		(fill
			(thermal_gap 0.5)
			(thermal_bridge_width 0.5)
			(island_removal_mode 0)
		)
		(polygon
			(pts
				(arc
					(start 153.488898 -386.003292)
					(mid 153.107898 -386.003292)
					(end 153.488898 -386.003292)
				)
			)
		)
	)
	(zone
		(layer "In1.Cu")
		(hatch none 0.5)
		(connect_pads
			(clearance 0)
		)
		(min_thickness 0.25)
		(keepout
			(tracks not_allowed)
			(vias allowed)
			(pads allowed)
			(copperpour not_allowed)
			(footprints allowed)
		)
		(placement
			(enabled no)
			(sheetname "")
		)
		(fill
			(thermal_gap 0.5)
			(thermal_bridge_width 0.5)
			(island_removal_mode 0)
		)
		(polygon
			(pts
				(arc
					(start 337.588606 -394.385292)
					(mid 337.207606 -394.385292)
					(end 337.588606 -394.385292)
				)
			)
		)
	)
	(zone
		(layer "In1.Cu")
		(hatch none 0.5)
		(connect_pads
			(clearance 0)
		)
		(min_thickness 0.25)
		(keepout
			(tracks not_allowed)
			(vias allowed)
			(pads allowed)
			(copperpour not_allowed)
			(footprints allowed)
		)
		(placement
			(enabled no)
			(sheetname "")
		)
		(fill
			(thermal_gap 0.5)
			(thermal_bridge_width 0.5)
			(island_removal_mode 0)
		)
		(polygon
			(pts
				(arc
					(start 386.561076 -394.385292)
					(mid 386.180076 -394.385292)
					(end 386.561076 -394.385292)
				)
			)
		)
	)
	(zone
		(layer "In1.Cu")
		(hatch none 0.5)
		(connect_pads
			(clearance 0)
		)
		(min_thickness 0.25)
		(keepout
			(tracks not_allowed)
			(vias allowed)
			(pads allowed)
			(copperpour not_allowed)
			(footprints allowed)
		)
		(placement
			(enabled no)
			(sheetname "")
		)
		(fill
			(thermal_gap 0.5)
			(thermal_bridge_width 0.5)
			(island_removal_mode 0)
		)
		(polygon
			(pts
				(arc
					(start 337.297776 -392.30427)
					(mid 336.992976 -392.30427)
					(end 337.297776 -392.30427)
				)
			)
		)
	)
	(zone
		(layer "In1.Cu")
		(hatch none 0.5)
		(connect_pads
			(clearance 0)
		)
		(min_thickness 0.25)
		(keepout
			(tracks not_allowed)
			(vias allowed)
			(pads allowed)
			(copperpour not_allowed)
			(footprints allowed)
		)
		(placement
			(enabled no)
			(sheetname "")
		)
		(fill
			(thermal_gap 0.5)
			(thermal_bridge_width 0.5)
			(island_removal_mode 0)
		)
		(polygon
			(pts
				(arc
					(start 348.718632 -399.701258)
					(mid 348.845632 -399.828258)
					(end 348.972632 -399.701258)
				)
				(arc
					(start 348.972632 -399.625058)
					(mid 348.845632 -399.498058)
					(end 348.718632 -399.625058)
				)
			)
		)
	)
	(zone
		(layer "In1.Cu")
		(hatch none 0.5)
		(connect_pads
			(clearance 0)
		)
		(min_thickness 0.25)
		(keepout
			(tracks not_allowed)
			(vias allowed)
			(pads allowed)
			(copperpour not_allowed)
			(footprints allowed)
		)
		(placement
			(enabled no)
			(sheetname "")
		)
		(fill
			(thermal_gap 0.5)
			(thermal_bridge_width 0.5)
			(island_removal_mode 0)
		)
		(polygon
			(pts
				(arc
					(start 84.89823 -390.761474)
					(mid 84.59343 -390.761474)
					(end 84.89823 -390.761474)
				)
			)
		)
	)
	(zone
		(layer "In1.Cu")
		(hatch none 0.5)
		(connect_pads
			(clearance 0)
		)
		(min_thickness 0.25)
		(keepout
			(tracks not_allowed)
			(vias allowed)
			(pads allowed)
			(copperpour not_allowed)
			(footprints allowed)
		)
		(placement
			(enabled no)
			(sheetname "")
		)
		(fill
			(thermal_gap 0.5)
			(thermal_bridge_width 0.5)
			(island_removal_mode 0)
		)
		(polygon
			(pts
				(arc
					(start 48.533304 -265.5824)
					(mid 48.529584 -265.59138)
					(end 48.520604 -265.5951)
				)
				(arc
					(start 47.047404 -265.5951)
					(mid 47.038424 -265.59138)
					(end 47.034704 -265.5824)
				)
				(arc
					(start 47.034704 -265.087862)
					(mid 47.038424 -265.078882)
					(end 47.047404 -265.075162)
				)
				(arc
					(start 48.520604 -265.075162)
					(mid 48.529584 -265.078882)
					(end 48.533304 -265.087862)
				)
			)
		)
	)
	(zone
		(layer "In1.Cu")
		(hatch none 0.5)
		(connect_pads
			(clearance 0)
		)
		(min_thickness 0.25)
		(keepout
			(tracks not_allowed)
			(vias allowed)
			(pads allowed)
			(copperpour not_allowed)
			(footprints allowed)
		)
		(placement
			(enabled no)
			(sheetname "")
		)
		(fill
			(thermal_gap 0.5)
			(thermal_bridge_width 0.5)
			(island_removal_mode 0)
		)
		(polygon
			(pts
				(arc
					(start 266.29741 -223.082104)
					(mid 266.29369 -223.091084)
					(end 266.28471 -223.094804)
				)
				(arc
					(start 264.81151 -223.094804)
					(mid 264.80253 -223.091084)
					(end 264.79881 -223.082104)
				)
				(arc
					(start 264.79881 -222.587566)
					(mid 264.80253 -222.578586)
					(end 264.81151 -222.574866)
				)
				(arc
					(start 266.28471 -222.574866)
					(mid 266.29369 -222.578586)
					(end 266.29741 -222.587566)
				)
			)
		)
	)
	(zone
		(layer "In1.Cu")
		(hatch none 0.5)
		(connect_pads
			(clearance 0)
		)
		(min_thickness 0.25)
		(keepout
			(tracks not_allowed)
			(vias allowed)
			(pads allowed)
			(copperpour not_allowed)
			(footprints allowed)
		)
		(placement
			(enabled no)
			(sheetname "")
		)
		(fill
			(thermal_gap 0.5)
			(thermal_bridge_width 0.5)
			(island_removal_mode 0)
		)
		(polygon
			(pts
				(arc
					(start 424.761406 -287.682178)
					(mid 424.757686 -287.691158)
					(end 424.748706 -287.694878)
				)
				(arc
					(start 423.275506 -287.694878)
					(mid 423.266526 -287.691158)
					(end 423.262806 -287.682178)
				)
				(arc
					(start 423.262806 -287.18764)
					(mid 423.266526 -287.17866)
					(end 423.275506 -287.17494)
				)
				(arc
					(start 424.748706 -287.17494)
					(mid 424.757686 -287.17866)
					(end 424.761406 -287.18764)
				)
			)
		)
	)
	(zone
		(layer "In1.Cu")
		(hatch none 0.5)
		(connect_pads
			(clearance 0)
		)
		(min_thickness 0.25)
		(keepout
			(tracks not_allowed)
			(vias allowed)
			(pads allowed)
			(copperpour not_allowed)
			(footprints allowed)
		)
		(placement
			(enabled no)
			(sheetname "")
		)
		(fill
			(thermal_gap 0.5)
			(thermal_bridge_width 0.5)
			(island_removal_mode 0)
		)
		(polygon
			(pts
				(arc
					(start 22.45741 -306.38242)
					(mid 22.45369 -306.3914)
					(end 22.44471 -306.39512)
				)
				(arc
					(start 20.97151 -306.39512)
					(mid 20.96253 -306.3914)
					(end 20.95881 -306.38242)
				)
				(arc
					(start 20.95881 -305.887882)
					(mid 20.96253 -305.878902)
					(end 20.97151 -305.875182)
				)
				(arc
					(start 22.44471 -305.875182)
					(mid 22.45369 -305.878902)
					(end 22.45741 -305.887882)
				)
			)
		)
	)
	(zone
		(layer "In1.Cu")
		(hatch none 0.5)
		(connect_pads
			(clearance 0)
		)
		(min_thickness 0.25)
		(keepout
			(tracks not_allowed)
			(vias allowed)
			(pads allowed)
			(copperpour not_allowed)
			(footprints allowed)
		)
		(placement
			(enabled no)
			(sheetname "")
		)
		(fill
			(thermal_gap 0.5)
			(thermal_bridge_width 0.5)
			(island_removal_mode 0)
		)
		(polygon
			(pts
				(arc
					(start 48.533304 -215.432386)
					(mid 48.529584 -215.441366)
					(end 48.520604 -215.445086)
				)
				(arc
					(start 47.047404 -215.445086)
					(mid 47.038424 -215.441366)
					(end 47.034704 -215.432386)
				)
				(arc
					(start 47.034704 -214.937848)
					(mid 47.038424 -214.928868)
					(end 47.047404 -214.925148)
				)
				(arc
					(start 48.520604 -214.925148)
					(mid 48.529584 -214.928868)
					(end 48.533304 -214.937848)
				)
			)
		)
	)
	(zone
		(layer "In1.Cu")
		(hatch none 0.5)
		(connect_pads
			(clearance 0)
		)
		(min_thickness 0.25)
		(keepout
			(tracks not_allowed)
			(vias allowed)
			(pads allowed)
			(copperpour not_allowed)
			(footprints allowed)
		)
		(placement
			(enabled no)
			(sheetname "")
		)
		(fill
			(thermal_gap 0.5)
			(thermal_bridge_width 0.5)
			(island_removal_mode 0)
		)
		(polygon
			(pts
				(arc
					(start 424.761406 -225.632264)
					(mid 424.757686 -225.641244)
					(end 424.748706 -225.644964)
				)
				(arc
					(start 423.275506 -225.644964)
					(mid 423.266526 -225.641244)
					(end 423.262806 -225.632264)
				)
				(arc
					(start 423.262806 -225.137726)
					(mid 423.266526 -225.128746)
					(end 423.275506 -225.125026)
				)
				(arc
					(start 424.748706 -225.125026)
					(mid 424.757686 -225.128746)
					(end 424.761406 -225.137726)
				)
			)
		)
	)
	(zone
		(layer "In1.Cu")
		(hatch none 0.5)
		(connect_pads
			(clearance 0)
		)
		(min_thickness 0.25)
		(keepout
			(tracks not_allowed)
			(vias allowed)
			(pads allowed)
			(copperpour not_allowed)
			(footprints allowed)
		)
		(placement
			(enabled no)
			(sheetname "")
		)
		(fill
			(thermal_gap 0.5)
			(thermal_bridge_width 0.5)
			(island_removal_mode 0)
		)
		(polygon
			(pts
				(arc
					(start 206.5782 -254.285242)
					(mid 205.9178 -254.285242)
					(end 206.5782 -254.285242)
				)
			)
		)
	)
	(zone
		(layer "In1.Cu")
		(hatch none 0.5)
		(connect_pads
			(clearance 0)
		)
		(min_thickness 0.25)
		(keepout
			(tracks not_allowed)
			(vias allowed)
			(pads allowed)
			(copperpour not_allowed)
			(footprints allowed)
		)
		(placement
			(enabled no)
			(sheetname "")
		)
		(fill
			(thermal_gap 0.5)
			(thermal_bridge_width 0.5)
			(island_removal_mode 0)
		)
		(polygon
			(pts
				(arc
					(start 60.177426 -317.432436)
					(mid 60.173706 -317.441416)
					(end 60.164726 -317.445136)
				)
				(arc
					(start 58.691526 -317.445136)
					(mid 58.682546 -317.441416)
					(end 58.678826 -317.432436)
				)
				(arc
					(start 58.678826 -316.937898)
					(mid 58.682546 -316.928918)
					(end 58.691526 -316.925198)
				)
				(arc
					(start 60.164726 -316.925198)
					(mid 60.173706 -316.928918)
					(end 60.177426 -316.937898)
				)
			)
		)
	)
	(zone
		(layer "In1.Cu")
		(hatch none 0.5)
		(connect_pads
			(clearance 0)
		)
		(min_thickness 0.25)
		(keepout
			(tracks not_allowed)
			(vias allowed)
			(pads allowed)
			(copperpour not_allowed)
			(footprints allowed)
		)
		(placement
			(enabled no)
			(sheetname "")
		)
		(fill
			(thermal_gap 0.5)
			(thermal_bridge_width 0.5)
			(island_removal_mode 0)
		)
		(polygon
			(pts
				(arc
					(start 169.277284 -205.232508)
					(mid 169.273564 -205.241488)
					(end 169.264584 -205.245208)
				)
				(arc
					(start 167.791384 -205.245208)
					(mid 167.782404 -205.241488)
					(end 167.778684 -205.232508)
				)
				(arc
					(start 167.778684 -204.73797)
					(mid 167.782404 -204.72899)
					(end 167.791384 -204.72527)
				)
				(arc
					(start 169.264584 -204.72527)
					(mid 169.273564 -204.72899)
					(end 169.277284 -204.73797)
				)
			)
		)
	)
	(zone
		(layer "In1.Cu")
		(hatch none 0.5)
		(connect_pads
			(clearance 0)
		)
		(min_thickness 0.25)
		(keepout
			(tracks not_allowed)
			(vias allowed)
			(pads allowed)
			(copperpour not_allowed)
			(footprints allowed)
		)
		(placement
			(enabled no)
			(sheetname "")
		)
		(fill
			(thermal_gap 0.5)
			(thermal_bridge_width 0.5)
			(island_removal_mode 0)
		)
		(polygon
			(pts
				(arc
					(start 375.47042 -392.30427)
					(mid 375.16562 -392.30427)
					(end 375.47042 -392.30427)
				)
			)
		)
	)
	(zone
		(layer "In1.Cu")
		(hatch none 0.5)
		(connect_pads
			(clearance 0)
		)
		(min_thickness 0.25)
		(keepout
			(tracks not_allowed)
			(vias allowed)
			(pads allowed)
			(copperpour not_allowed)
			(footprints allowed)
		)
		(placement
			(enabled no)
			(sheetname "")
		)
		(fill
			(thermal_gap 0.5)
			(thermal_bridge_width 0.5)
			(island_removal_mode 0)
		)
		(polygon
			(pts
				(arc
					(start 298.560744 -385.11861)
					(mid 298.551508 -385.138534)
					(end 298.548298 -385.160266)
				)
				(arc
					(start 298.548298 -385.35483)
					(mid 298.570616 -385.408712)
					(end 298.624498 -385.43103)
				)
				(arc
					(start 299.310298 -385.43103)
					(mid 299.36418 -385.408712)
					(end 299.386498 -385.35483)
				)
				(arc
					(start 299.386498 -385.160266)
					(mid 299.38333 -385.138522)
					(end 299.374052 -385.11861)
				)
				(arc
					(start 299.181266 -384.822446)
					(mid 299.169044 -384.780762)
					(end 299.18152 -384.739134)
				)
				(arc
					(start 299.374052 -384.44551)
					(mid 299.383288 -384.425586)
					(end 299.386498 -384.403854)
				)
				(arc
					(start 299.386498 -384.20929)
					(mid 299.36418 -384.155408)
					(end 299.310298 -384.13309)
				)
				(arc
					(start 298.624498 -384.13309)
					(mid 298.570616 -384.155408)
					(end 298.548298 -384.20929)
				)
				(arc
					(start 298.548298 -384.405124)
					(mid 298.551466 -384.426868)
					(end 298.560744 -384.44678)
				)
				(arc
					(start 298.753276 -384.740404)
					(mid 298.765678 -384.78206)
					(end 298.753276 -384.823716)
				)
			)
		)
	)
	(zone
		(layer "In1.Cu")
		(hatch none 0.5)
		(connect_pads
			(clearance 0)
		)
		(min_thickness 0.25)
		(keepout
			(tracks not_allowed)
			(vias allowed)
			(pads allowed)
			(copperpour not_allowed)
			(footprints allowed)
		)
		(placement
			(enabled no)
			(sheetname "")
		)
		(fill
			(thermal_gap 0.5)
			(thermal_bridge_width 0.5)
			(island_removal_mode 0)
		)
		(polygon
			(pts
				(arc
					(start 450.8373 -240.082324)
					(mid 450.83358 -240.091304)
					(end 450.8246 -240.095024)
				)
				(arc
					(start 449.3514 -240.095024)
					(mid 449.34242 -240.091304)
					(end 449.3387 -240.082324)
				)
				(arc
					(start 449.3387 -239.587786)
					(mid 449.34242 -239.578806)
					(end 449.3514 -239.575086)
				)
				(arc
					(start 450.8246 -239.575086)
					(mid 450.83358 -239.578806)
					(end 450.8373 -239.587786)
				)
			)
		)
	)
	(zone
		(layer "In1.Cu")
		(hatch none 0.5)
		(connect_pads
			(clearance 0)
		)
		(min_thickness 0.25)
		(keepout
			(tracks not_allowed)
			(vias allowed)
			(pads allowed)
			(copperpour not_allowed)
			(footprints allowed)
		)
		(placement
			(enabled no)
			(sheetname "")
		)
		(fill
			(thermal_gap 0.5)
			(thermal_bridge_width 0.5)
			(island_removal_mode 0)
		)
		(polygon
			(pts
				(arc
					(start 285.485332 -283.43225)
					(mid 285.481612 -283.44123)
					(end 285.472632 -283.44495)
				)
				(arc
					(start 283.999432 -283.44495)
					(mid 283.990452 -283.44123)
					(end 283.986732 -283.43225)
				)
				(arc
					(start 283.986732 -282.937712)
					(mid 283.990452 -282.928732)
					(end 283.999432 -282.925012)
				)
				(arc
					(start 285.472632 -282.925012)
					(mid 285.481612 -282.928732)
					(end 285.485332 -282.937712)
				)
			)
		)
	)
	(zone
		(layer "In1.Cu")
		(hatch none 0.5)
		(connect_pads
			(clearance 0)
		)
		(min_thickness 0.25)
		(keepout
			(tracks not_allowed)
			(vias allowed)
			(pads allowed)
			(copperpour not_allowed)
			(footprints allowed)
		)
		(placement
			(enabled no)
			(sheetname "")
		)
		(fill
			(thermal_gap 0.5)
			(thermal_bridge_width 0.5)
			(island_removal_mode 0)
		)
		(polygon
			(pts
				(arc
					(start 420.661338 -198.432166)
					(mid 420.657618 -198.441146)
					(end 420.648638 -198.444866)
				)
				(arc
					(start 419.175438 -198.444866)
					(mid 419.166458 -198.441146)
					(end 419.162738 -198.432166)
				)
				(arc
					(start 419.162738 -197.937628)
					(mid 419.166458 -197.928648)
					(end 419.175438 -197.924928)
				)
				(arc
					(start 420.648638 -197.924928)
					(mid 420.657618 -197.928648)
					(end 420.661338 -197.937628)
				)
			)
		)
	)
	(zone
		(layer "In1.Cu")
		(hatch none 0.5)
		(connect_pads
			(clearance 0)
		)
		(min_thickness 0.25)
		(keepout
			(tracks not_allowed)
			(vias allowed)
			(pads allowed)
			(copperpour not_allowed)
			(footprints allowed)
		)
		(placement
			(enabled no)
			(sheetname "")
		)
		(fill
			(thermal_gap 0.5)
			(thermal_bridge_width 0.5)
			(island_removal_mode 0)
		)
		(polygon
			(pts
				(arc
					(start 352.897948 -392.30427)
					(mid 352.593148 -392.30427)
					(end 352.897948 -392.30427)
				)
			)
		)
	)
	(zone
		(layer "In1.Cu")
		(hatch none 0.5)
		(connect_pads
			(clearance 0)
		)
		(min_thickness 0.25)
		(keepout
			(tracks not_allowed)
			(vias allowed)
			(pads allowed)
			(copperpour not_allowed)
			(footprints allowed)
		)
		(placement
			(enabled no)
			(sheetname "")
		)
		(fill
			(thermal_gap 0.5)
			(thermal_bridge_width 0.5)
			(island_removal_mode 0)
		)
		(polygon
			(pts
				(arc
					(start 147.19808 -383.92227)
					(mid 146.89328 -383.92227)
					(end 147.19808 -383.92227)
				)
			)
		)
	)
	(zone
		(layer "In1.Cu")
		(hatch none 0.5)
		(connect_pads
			(clearance 0)
		)
		(min_thickness 0.25)
		(keepout
			(tracks not_allowed)
			(vias allowed)
			(pads allowed)
			(copperpour not_allowed)
			(footprints allowed)
		)
		(placement
			(enabled no)
			(sheetname "")
		)
		(fill
			(thermal_gap 0.5)
			(thermal_bridge_width 0.5)
			(island_removal_mode 0)
		)
		(polygon
			(pts
				(arc
					(start 97.988882 -385.31038)
					(mid 97.607882 -385.31038)
					(end 97.988882 -385.31038)
				)
			)
		)
	)
	(zone
		(layer "In1.Cu")
		(hatch none 0.5)
		(connect_pads
			(clearance 0)
		)
		(min_thickness 0.25)
		(keepout
			(tracks not_allowed)
			(vias allowed)
			(pads allowed)
			(copperpour not_allowed)
			(footprints allowed)
		)
		(placement
			(enabled no)
			(sheetname "")
		)
		(fill
			(thermal_gap 0.5)
			(thermal_bridge_width 0.5)
			(island_removal_mode 0)
		)
		(polygon
			(pts
				(arc
					(start 195.353432 -232.432352)
					(mid 195.349712 -232.441332)
					(end 195.340732 -232.445052)
				)
				(arc
					(start 193.867532 -232.445052)
					(mid 193.858552 -232.441332)
					(end 193.854832 -232.432352)
				)
				(arc
					(start 193.854832 -231.937814)
					(mid 193.858552 -231.928834)
					(end 193.867532 -231.925114)
				)
				(arc
					(start 195.340732 -231.925114)
					(mid 195.349712 -231.928834)
					(end 195.353432 -231.937814)
				)
			)
		)
	)
	(zone
		(layer "In1.Cu")
		(hatch none 0.5)
		(connect_pads
			(clearance 0)
		)
		(min_thickness 0.25)
		(keepout
			(tracks not_allowed)
			(vias allowed)
			(pads allowed)
			(copperpour not_allowed)
			(footprints allowed)
		)
		(placement
			(enabled no)
			(sheetname "")
		)
		(fill
			(thermal_gap 0.5)
			(thermal_bridge_width 0.5)
			(island_removal_mode 0)
		)
		(polygon
			(pts
				(arc
					(start 413.117284 -198.432166)
					(mid 413.113564 -198.441146)
					(end 413.104584 -198.444866)
				)
				(arc
					(start 411.631384 -198.444866)
					(mid 411.622404 -198.441146)
					(end 411.618684 -198.432166)
				)
				(arc
					(start 411.618684 -197.937628)
					(mid 411.622404 -197.928648)
					(end 411.631384 -197.924928)
				)
				(arc
					(start 413.104584 -197.924928)
					(mid 413.113564 -197.928648)
					(end 413.117284 -197.937628)
				)
			)
		)
	)
	(zone
		(layer "In1.Cu")
		(hatch none 0.5)
		(connect_pads
			(clearance 0)
		)
		(min_thickness 0.25)
		(keepout
			(tracks not_allowed)
			(vias allowed)
			(pads allowed)
			(copperpour not_allowed)
			(footprints allowed)
		)
		(placement
			(enabled no)
			(sheetname "")
		)
		(fill
			(thermal_gap 0.5)
			(thermal_bridge_width 0.5)
			(island_removal_mode 0)
		)
		(polygon
			(pts
				(arc
					(start 54.770528 -383.92227)
					(mid 54.465728 -383.92227)
					(end 54.770528 -383.92227)
				)
			)
		)
	)
	(zone
		(layer "In1.Cu")
		(hatch none 0.5)
		(connect_pads
			(clearance 0)
		)
		(min_thickness 0.25)
		(keepout
			(tracks not_allowed)
			(vias allowed)
			(pads allowed)
			(copperpour not_allowed)
			(footprints allowed)
		)
		(placement
			(enabled no)
			(sheetname "")
		)
		(fill
			(thermal_gap 0.5)
			(thermal_bridge_width 0.5)
			(island_removal_mode 0)
		)
		(polygon
			(pts
				(arc
					(start 160.398206 -383.92227)
					(mid 160.093406 -383.92227)
					(end 160.398206 -383.92227)
				)
			)
		)
	)
	(zone
		(layer "In1.Cu")
		(hatch none 0.5)
		(connect_pads
			(clearance 0)
		)
		(min_thickness 0.25)
		(keepout
			(tracks not_allowed)
			(vias allowed)
			(pads allowed)
			(copperpour not_allowed)
			(footprints allowed)
		)
		(placement
			(enabled no)
			(sheetname "")
		)
		(fill
			(thermal_gap 0.5)
			(thermal_bridge_width 0.5)
			(island_removal_mode 0)
		)
		(polygon
			(pts
				(arc
					(start 454.937368 -231.582214)
					(mid 454.933648 -231.591194)
					(end 454.924668 -231.594914)
				)
				(arc
					(start 453.451468 -231.594914)
					(mid 453.442488 -231.591194)
					(end 453.438768 -231.582214)
				)
				(arc
					(start 453.438768 -231.087676)
					(mid 453.442488 -231.078696)
					(end 453.451468 -231.074976)
				)
				(arc
					(start 454.924668 -231.074976)
					(mid 454.933648 -231.078696)
					(end 454.937368 -231.087676)
				)
			)
		)
	)
	(zone
		(layer "In1.Cu")
		(hatch none 0.5)
		(connect_pads
			(clearance 0)
		)
		(min_thickness 0.25)
		(keepout
			(tracks not_allowed)
			(vias allowed)
			(pads allowed)
			(copperpour not_allowed)
			(footprints allowed)
		)
		(placement
			(enabled no)
			(sheetname "")
		)
		(fill
			(thermal_gap 0.5)
			(thermal_bridge_width 0.5)
			(island_removal_mode 0)
		)
		(polygon
			(pts
				(arc
					(start 180.265324 -291.93236)
					(mid 180.261604 -291.94134)
					(end 180.252624 -291.94506)
				)
				(arc
					(start 178.779424 -291.94506)
					(mid 178.770444 -291.94134)
					(end 178.766724 -291.93236)
				)
				(arc
					(start 178.766724 -291.437822)
					(mid 178.770444 -291.428842)
					(end 178.779424 -291.425122)
				)
				(arc
					(start 180.252624 -291.425122)
					(mid 180.261604 -291.428842)
					(end 180.265324 -291.437822)
				)
			)
		)
	)
	(zone
		(layer "In1.Cu")
		(hatch none 0.5)
		(connect_pads
			(clearance 0)
		)
		(min_thickness 0.25)
		(keepout
			(tracks not_allowed)
			(vias allowed)
			(pads allowed)
			(copperpour not_allowed)
			(footprints allowed)
		)
		(placement
			(enabled no)
			(sheetname "")
		)
		(fill
			(thermal_gap 0.5)
			(thermal_bridge_width 0.5)
			(island_removal_mode 0)
		)
		(polygon
			(pts
				(arc
					(start 158.288736 -389.467344)
					(mid 157.907736 -389.467344)
					(end 158.288736 -389.467344)
				)
			)
		)
	)
	(zone
		(layer "In1.Cu")
		(hatch none 0.5)
		(connect_pads
			(clearance 0)
		)
		(min_thickness 0.25)
		(keepout
			(tracks not_allowed)
			(vias allowed)
			(pads allowed)
			(copperpour not_allowed)
			(footprints allowed)
		)
		(placement
			(enabled no)
			(sheetname "")
		)
		(fill
			(thermal_gap 0.5)
			(thermal_bridge_width 0.5)
			(island_removal_mode 0)
		)
		(polygon
			(pts
				(arc
					(start 156.689044 -385.31038)
					(mid 156.308044 -385.31038)
					(end 156.689044 -385.31038)
				)
			)
		)
	)
	(zone
		(layer "In1.Cu")
		(hatch none 0.5)
		(connect_pads
			(clearance 0)
		)
		(min_thickness 0.25)
		(keepout
			(tracks not_allowed)
			(vias allowed)
			(pads allowed)
			(copperpour not_allowed)
			(footprints allowed)
		)
		(placement
			(enabled no)
			(sheetname "")
		)
		(fill
			(thermal_gap 0.5)
			(thermal_bridge_width 0.5)
			(island_removal_mode 0)
		)
		(polygon
			(pts
				(arc
					(start 25.901396 -234.132374)
					(mid 25.897676 -234.141354)
					(end 25.888696 -234.145074)
				)
				(arc
					(start 24.415496 -234.145074)
					(mid 24.406516 -234.141354)
					(end 24.402796 -234.132374)
				)
				(arc
					(start 24.402796 -233.637836)
					(mid 24.406516 -233.628856)
					(end 24.415496 -233.625136)
				)
				(arc
					(start 25.888696 -233.625136)
					(mid 25.897676 -233.628856)
					(end 25.901396 -233.637836)
				)
			)
		)
	)
	(zone
		(layer "In1.Cu")
		(hatch none 0.5)
		(connect_pads
			(clearance 0)
		)
		(min_thickness 0.25)
		(keepout
			(tracks not_allowed)
			(vias allowed)
			(pads allowed)
			(copperpour not_allowed)
			(footprints allowed)
		)
		(placement
			(enabled no)
			(sheetname "")
		)
		(fill
			(thermal_gap 0.5)
			(thermal_bridge_width 0.5)
			(island_removal_mode 0)
		)
		(polygon
			(pts
				(arc
					(start 25.901396 -250.282456)
					(mid 25.897676 -250.291436)
					(end 25.888696 -250.295156)
				)
				(arc
					(start 24.415496 -250.295156)
					(mid 24.406516 -250.291436)
					(end 24.402796 -250.282456)
				)
				(arc
					(start 24.402796 -249.787918)
					(mid 24.406516 -249.778938)
					(end 24.415496 -249.775218)
				)
				(arc
					(start 25.888696 -249.775218)
					(mid 25.897676 -249.778938)
					(end 25.901396 -249.787918)
				)
			)
		)
	)
	(zone
		(layer "In1.Cu")
		(hatch none 0.5)
		(connect_pads
			(clearance 0)
		)
		(min_thickness 0.25)
		(keepout
			(tracks not_allowed)
			(vias allowed)
			(pads allowed)
			(copperpour not_allowed)
			(footprints allowed)
		)
		(placement
			(enabled no)
			(sheetname "")
		)
		(fill
			(thermal_gap 0.5)
			(thermal_bridge_width 0.5)
			(island_removal_mode 0)
		)
		(polygon
			(pts
				(arc
					(start 25.901396 -276.632416)
					(mid 25.897676 -276.641396)
					(end 25.888696 -276.645116)
				)
				(arc
					(start 24.415496 -276.645116)
					(mid 24.406516 -276.641396)
					(end 24.402796 -276.632416)
				)
				(arc
					(start 24.402796 -276.137878)
					(mid 24.406516 -276.128898)
					(end 24.415496 -276.125178)
				)
				(arc
					(start 25.888696 -276.125178)
					(mid 25.897676 -276.128898)
					(end 25.901396 -276.137878)
				)
			)
		)
	)
	(zone
		(layer "In1.Cu")
		(hatch none 0.5)
		(connect_pads
			(clearance 0)
		)
		(min_thickness 0.25)
		(keepout
			(tracks not_allowed)
			(vias allowed)
			(pads allowed)
			(copperpour not_allowed)
			(footprints allowed)
		)
		(placement
			(enabled no)
			(sheetname "")
		)
		(fill
			(thermal_gap 0.5)
			(thermal_bridge_width 0.5)
			(island_removal_mode 0)
		)
		(polygon
			(pts
				(arc
					(start 161.018728 -383.440686)
					(mid 161.145728 -383.567686)
					(end 161.272728 -383.440686)
				)
				(arc
					(start 161.272728 -383.364486)
					(mid 161.145728 -383.237486)
					(end 161.018728 -383.364486)
				)
			)
		)
	)
	(zone
		(layer "In1.Cu")
		(hatch none 0.5)
		(connect_pads
			(clearance 0)
		)
		(min_thickness 0.25)
		(keepout
			(tracks not_allowed)
			(vias allowed)
			(pads allowed)
			(copperpour not_allowed)
			(footprints allowed)
		)
		(placement
			(enabled no)
			(sheetname "")
		)
		(fill
			(thermal_gap 0.5)
			(thermal_bridge_width 0.5)
			(island_removal_mode 0)
		)
		(polygon
			(pts
				(arc
					(start 373.070374 -399.143474)
					(mid 372.765574 -399.143474)
					(end 373.070374 -399.143474)
				)
			)
		)
	)
	(zone
		(layer "In1.Cu")
		(hatch none 0.5)
		(connect_pads
			(clearance 0)
		)
		(min_thickness 0.25)
		(keepout
			(tracks not_allowed)
			(vias allowed)
			(pads allowed)
			(copperpour not_allowed)
			(footprints allowed)
		)
		(placement
			(enabled no)
			(sheetname "")
		)
		(fill
			(thermal_gap 0.5)
			(thermal_bridge_width 0.5)
			(island_removal_mode 0)
		)
		(polygon
			(pts
				(arc
					(start 424.761406 -295.33215)
					(mid 424.757686 -295.34113)
					(end 424.748706 -295.34485)
				)
				(arc
					(start 423.275506 -295.34485)
					(mid 423.266526 -295.34113)
					(end 423.262806 -295.33215)
				)
				(arc
					(start 423.262806 -294.837612)
					(mid 423.266526 -294.828632)
					(end 423.275506 -294.824912)
				)
				(arc
					(start 424.748706 -294.824912)
					(mid 424.757686 -294.828632)
					(end 424.761406 -294.837612)
				)
			)
		)
	)
	(zone
		(layer "In1.Cu")
		(hatch none 0.5)
		(connect_pads
			(clearance 0)
		)
		(min_thickness 0.25)
		(keepout
			(tracks not_allowed)
			(vias allowed)
			(pads allowed)
			(copperpour not_allowed)
			(footprints allowed)
		)
		(placement
			(enabled no)
			(sheetname "")
		)
		(fill
			(thermal_gap 0.5)
			(thermal_bridge_width 0.5)
			(island_removal_mode 0)
		)
		(polygon
			(pts
				(arc
					(start 340.820248 -379.360684)
					(mid 340.840172 -379.36992)
					(end 340.861904 -379.37313)
				)
				(arc
					(start 341.056468 -379.37313)
					(mid 341.11035 -379.350812)
					(end 341.132668 -379.29693)
				)
				(arc
					(start 341.132668 -378.61113)
					(mid 341.11035 -378.557248)
					(end 341.056468 -378.53493)
				)
				(arc
					(start 340.861904 -378.53493)
					(mid 340.84016 -378.538098)
					(end 340.820248 -378.547376)
				)
				(arc
					(start 340.524084 -378.740162)
					(mid 340.4824 -378.752384)
					(end 340.440772 -378.739908)
				)
				(arc
					(start 340.147148 -378.547376)
					(mid 340.127224 -378.53814)
					(end 340.105492 -378.53493)
				)
				(arc
					(start 339.910928 -378.53493)
					(mid 339.857046 -378.557248)
					(end 339.834728 -378.61113)
				)
				(arc
					(start 339.834728 -379.29693)
					(mid 339.857046 -379.350812)
					(end 339.910928 -379.37313)
				)
				(arc
					(start 340.106762 -379.37313)
					(mid 340.128506 -379.369962)
					(end 340.148418 -379.360684)
				)
				(arc
					(start 340.442042 -379.168152)
					(mid 340.483698 -379.15575)
					(end 340.525354 -379.168152)
				)
			)
		)
	)
	(zone
		(layer "In1.Cu")
		(hatch none 0.5)
		(connect_pads
			(clearance 0)
		)
		(min_thickness 0.25)
		(keepout
			(tracks not_allowed)
			(vias allowed)
			(pads allowed)
			(copperpour not_allowed)
			(footprints allowed)
		)
		(placement
			(enabled no)
			(sheetname "")
		)
		(fill
			(thermal_gap 0.5)
			(thermal_bridge_width 0.5)
			(island_removal_mode 0)
		)
		(polygon
			(pts
				(arc
					(start 347.188536 -394.385292)
					(mid 346.807536 -394.385292)
					(end 347.188536 -394.385292)
				)
			)
		)
	)
	(zone
		(layer "In1.Cu")
		(hatch none 0.5)
		(connect_pads
			(clearance 0)
		)
		(min_thickness 0.25)
		(keepout
			(tracks not_allowed)
			(vias allowed)
			(pads allowed)
			(copperpour not_allowed)
			(footprints allowed)
		)
		(placement
			(enabled no)
			(sheetname "")
		)
		(fill
			(thermal_gap 0.5)
			(thermal_bridge_width 0.5)
			(island_removal_mode 0)
		)
		(polygon
			(pts
				(arc
					(start 60.177426 -201.832464)
					(mid 60.173706 -201.841444)
					(end 60.164726 -201.845164)
				)
				(arc
					(start 58.691526 -201.845164)
					(mid 58.682546 -201.841444)
					(end 58.678826 -201.832464)
				)
				(arc
					(start 58.678826 -201.337926)
					(mid 58.682546 -201.328946)
					(end 58.691526 -201.325226)
				)
				(arc
					(start 60.164726 -201.325226)
					(mid 60.173706 -201.328946)
					(end 60.177426 -201.337926)
				)
			)
		)
	)
	(zone
		(layer "In1.Cu")
		(hatch none 0.5)
		(connect_pads
			(clearance 0)
		)
		(min_thickness 0.25)
		(keepout
			(tracks not_allowed)
			(vias allowed)
			(pads allowed)
			(copperpour not_allowed)
			(footprints allowed)
		)
		(placement
			(enabled no)
			(sheetname "")
		)
		(fill
			(thermal_gap 0.5)
			(thermal_bridge_width 0.5)
			(island_removal_mode 0)
		)
		(polygon
			(pts
				(arc
					(start 277.941532 -214.582248)
					(mid 277.937812 -214.591228)
					(end 277.928832 -214.594948)
				)
				(arc
					(start 276.455632 -214.594948)
					(mid 276.446652 -214.591228)
					(end 276.442932 -214.582248)
				)
				(arc
					(start 276.442932 -214.08771)
					(mid 276.446652 -214.07873)
					(end 276.455632 -214.07501)
				)
				(arc
					(start 277.928832 -214.07501)
					(mid 277.937812 -214.07873)
					(end 277.941532 -214.08771)
				)
			)
		)
	)
	(zone
		(layer "In1.Cu")
		(hatch none 0.5)
		(connect_pads
			(clearance 0)
		)
		(min_thickness 0.25)
		(keepout
			(tracks not_allowed)
			(vias allowed)
			(pads allowed)
			(copperpour not_allowed)
			(footprints allowed)
		)
		(placement
			(enabled no)
			(sheetname "")
		)
		(fill
			(thermal_gap 0.5)
			(thermal_bridge_width 0.5)
			(island_removal_mode 0)
		)
		(polygon
			(pts
				(arc
					(start 195.353432 -280.882344)
					(mid 195.349712 -280.891324)
					(end 195.340732 -280.895044)
				)
				(arc
					(start 193.867532 -280.895044)
					(mid 193.858552 -280.891324)
					(end 193.854832 -280.882344)
				)
				(arc
					(start 193.854832 -280.387806)
					(mid 193.858552 -280.378826)
					(end 193.867532 -280.375106)
				)
				(arc
					(start 195.340732 -280.375106)
					(mid 195.349712 -280.378826)
					(end 195.353432 -280.387806)
				)
			)
		)
	)
	(zone
		(layer "In1.Cu")
		(hatch none 0.5)
		(connect_pads
			(clearance 0)
		)
		(min_thickness 0.25)
		(keepout
			(tracks not_allowed)
			(vias allowed)
			(pads allowed)
			(copperpour not_allowed)
			(footprints allowed)
		)
		(placement
			(enabled no)
			(sheetname "")
		)
		(fill
			(thermal_gap 0.5)
			(thermal_bridge_width 0.5)
			(island_removal_mode 0)
		)
		(polygon
			(pts
				(arc
					(start 293.029386 -205.232254)
					(mid 293.025666 -205.241234)
					(end 293.016686 -205.244954)
				)
				(arc
					(start 291.543486 -205.244954)
					(mid 291.534506 -205.241234)
					(end 291.530786 -205.232254)
				)
				(arc
					(start 291.530786 -204.737716)
					(mid 291.534506 -204.728736)
					(end 291.543486 -204.725016)
				)
				(arc
					(start 293.016686 -204.725016)
					(mid 293.025666 -204.728736)
					(end 293.029386 -204.737716)
				)
			)
		)
	)
	(zone
		(layer "In1.Cu")
		(hatch none 0.5)
		(connect_pads
			(clearance 0)
		)
		(min_thickness 0.25)
		(keepout
			(tracks not_allowed)
			(vias allowed)
			(pads allowed)
			(copperpour not_allowed)
			(footprints allowed)
		)
		(placement
			(enabled no)
			(sheetname "")
		)
		(fill
			(thermal_gap 0.5)
			(thermal_bridge_width 0.5)
			(island_removal_mode 0)
		)
		(polygon
			(pts
				(arc
					(start 52.633372 -317.432436)
					(mid 52.629652 -317.441416)
					(end 52.620672 -317.445136)
				)
				(arc
					(start 51.147472 -317.445136)
					(mid 51.138492 -317.441416)
					(end 51.134772 -317.432436)
				)
				(arc
					(start 51.134772 -316.937898)
					(mid 51.138492 -316.928918)
					(end 51.147472 -316.925198)
				)
				(arc
					(start 52.620672 -316.925198)
					(mid 52.629652 -316.928918)
					(end 52.633372 -316.937898)
				)
			)
		)
	)
	(zone
		(layer "In1.Cu")
		(hatch none 0.5)
		(connect_pads
			(clearance 0)
		)
		(min_thickness 0.25)
		(keepout
			(tracks not_allowed)
			(vias allowed)
			(pads allowed)
			(copperpour not_allowed)
			(footprints allowed)
		)
		(placement
			(enabled no)
			(sheetname "")
		)
		(fill
			(thermal_gap 0.5)
			(thermal_bridge_width 0.5)
			(island_removal_mode 0)
		)
		(polygon
			(pts
				(arc
					(start 417.488878 -393.69238)
					(mid 417.107878 -393.69238)
					(end 417.488878 -393.69238)
				)
			)
		)
	)
	(zone
		(layer "In1.Cu")
		(hatch none 0.5)
		(connect_pads
			(clearance 0)
		)
		(min_thickness 0.25)
		(keepout
			(tracks not_allowed)
			(vias allowed)
			(pads allowed)
			(copperpour not_allowed)
			(footprints allowed)
		)
		(placement
			(enabled no)
			(sheetname "")
		)
		(fill
			(thermal_gap 0.5)
			(thermal_bridge_width 0.5)
			(island_removal_mode 0)
		)
		(polygon
			(pts
				(arc
					(start 435.749446 -246.882158)
					(mid 435.745726 -246.891138)
					(end 435.736746 -246.894858)
				)
				(arc
					(start 434.263546 -246.894858)
					(mid 434.254566 -246.891138)
					(end 434.250846 -246.882158)
				)
				(arc
					(start 434.250846 -246.38762)
					(mid 434.254566 -246.37864)
					(end 434.263546 -246.37492)
				)
				(arc
					(start 435.736746 -246.37492)
					(mid 435.745726 -246.37864)
					(end 435.749446 -246.38762)
				)
			)
		)
	)
	(zone
		(layer "In1.Cu")
		(hatch none 0.5)
		(connect_pads
			(clearance 0)
		)
		(min_thickness 0.25)
		(keepout
			(tracks not_allowed)
			(vias allowed)
			(pads allowed)
			(copperpour not_allowed)
			(footprints allowed)
		)
		(placement
			(enabled no)
			(sheetname "")
		)
		(fill
			(thermal_gap 0.5)
			(thermal_bridge_width 0.5)
			(island_removal_mode 0)
		)
		(polygon
			(pts
				(arc
					(start 443.2935 -223.082104)
					(mid 443.28978 -223.091084)
					(end 443.2808 -223.094804)
				)
				(arc
					(start 441.8076 -223.094804)
					(mid 441.79862 -223.091084)
					(end 441.7949 -223.082104)
				)
				(arc
					(start 441.7949 -222.587566)
					(mid 441.79862 -222.578586)
					(end 441.8076 -222.574866)
				)
				(arc
					(start 443.2808 -222.574866)
					(mid 443.28978 -222.578586)
					(end 443.2935 -222.587566)
				)
			)
		)
	)
	(zone
		(layer "In1.Cu")
		(hatch none 0.5)
		(connect_pads
			(clearance 0)
		)
		(min_thickness 0.25)
		(keepout
			(tracks not_allowed)
			(vias allowed)
			(pads allowed)
			(copperpour not_allowed)
			(footprints allowed)
		)
		(placement
			(enabled no)
			(sheetname "")
		)
		(fill
			(thermal_gap 0.5)
			(thermal_bridge_width 0.5)
			(island_removal_mode 0)
		)
		(polygon
			(pts
				(arc
					(start 176.821338 -281.732482)
					(mid 176.817618 -281.741462)
					(end 176.808638 -281.745182)
				)
				(arc
					(start 175.335438 -281.745182)
					(mid 175.326458 -281.741462)
					(end 175.322738 -281.732482)
				)
				(arc
					(start 175.322738 -281.237944)
					(mid 175.326458 -281.228964)
					(end 175.335438 -281.225244)
				)
				(arc
					(start 176.808638 -281.225244)
					(mid 176.817618 -281.228964)
					(end 176.821338 -281.237944)
				)
			)
		)
	)
	(zone
		(layer "In1.Cu")
		(hatch none 0.5)
		(connect_pads
			(clearance 0)
		)
		(min_thickness 0.25)
		(keepout
			(tracks not_allowed)
			(vias allowed)
			(pads allowed)
			(copperpour not_allowed)
			(footprints allowed)
		)
		(placement
			(enabled no)
			(sheetname "")
		)
		(fill
			(thermal_gap 0.5)
			(thermal_bridge_width 0.5)
			(island_removal_mode 0)
		)
		(polygon
			(pts
				(arc
					(start 428.205392 -240.082324)
					(mid 428.201672 -240.091304)
					(end 428.192692 -240.095024)
				)
				(arc
					(start 426.719492 -240.095024)
					(mid 426.710512 -240.091304)
					(end 426.706792 -240.082324)
				)
				(arc
					(start 426.706792 -239.587786)
					(mid 426.710512 -239.578806)
					(end 426.719492 -239.575086)
				)
				(arc
					(start 428.192692 -239.575086)
					(mid 428.201672 -239.578806)
					(end 428.205392 -239.587786)
				)
			)
		)
	)
	(zone
		(layer "In1.Cu")
		(hatch none 0.5)
		(connect_pads
			(clearance 0)
		)
		(min_thickness 0.25)
		(keepout
			(tracks not_allowed)
			(vias allowed)
			(pads allowed)
			(copperpour not_allowed)
			(footprints allowed)
		)
		(placement
			(enabled no)
			(sheetname "")
		)
		(fill
			(thermal_gap 0.5)
			(thermal_bridge_width 0.5)
			(island_removal_mode 0)
		)
		(polygon
			(pts
				(arc
					(start 18.357342 -284.282388)
					(mid 18.353622 -284.291368)
					(end 18.344642 -284.295088)
				)
				(arc
					(start 16.871442 -284.295088)
					(mid 16.862462 -284.291368)
					(end 16.858742 -284.282388)
				)
				(arc
					(start 16.858742 -283.78785)
					(mid 16.862462 -283.77887)
					(end 16.871442 -283.77515)
				)
				(arc
					(start 18.344642 -283.77515)
					(mid 18.353622 -283.77887)
					(end 18.357342 -283.78785)
				)
			)
		)
	)
	(zone
		(layer "In1.Cu")
		(hatch none 0.5)
		(connect_pads
			(clearance 0)
		)
		(min_thickness 0.25)
		(keepout
			(tracks not_allowed)
			(vias allowed)
			(pads allowed)
			(copperpour not_allowed)
			(footprints allowed)
		)
		(placement
			(enabled no)
			(sheetname "")
		)
		(fill
			(thermal_gap 0.5)
			(thermal_bridge_width 0.5)
			(island_removal_mode 0)
		)
		(polygon
			(pts
				(arc
					(start 312.260742 -394.385292)
					(mid 311.879742 -394.385292)
					(end 312.260742 -394.385292)
				)
			)
		)
	)
	(zone
		(layer "In1.Cu")
		(hatch none 0.5)
		(connect_pads
			(clearance 0)
		)
		(min_thickness 0.25)
		(keepout
			(tracks not_allowed)
			(vias allowed)
			(pads allowed)
			(copperpour not_allowed)
			(footprints allowed)
		)
		(placement
			(enabled no)
			(sheetname "")
		)
		(fill
			(thermal_gap 0.5)
			(thermal_bridge_width 0.5)
			(island_removal_mode 0)
		)
		(polygon
			(pts
				(arc
					(start 191.909446 -214.582502)
					(mid 191.905726 -214.591482)
					(end 191.896746 -214.595202)
				)
				(arc
					(start 190.423546 -214.595202)
					(mid 190.414566 -214.591482)
					(end 190.410846 -214.582502)
				)
				(arc
					(start 190.410846 -214.087964)
					(mid 190.414566 -214.078984)
					(end 190.423546 -214.075264)
				)
				(arc
					(start 191.896746 -214.075264)
					(mid 191.905726 -214.078984)
					(end 191.909446 -214.087964)
				)
			)
		)
	)
	(zone
		(layer "In1.Cu")
		(hatch none 0.5)
		(connect_pads
			(clearance 0)
		)
		(min_thickness 0.25)
		(keepout
			(tracks not_allowed)
			(vias allowed)
			(pads allowed)
			(copperpour not_allowed)
			(footprints allowed)
		)
		(placement
			(enabled no)
			(sheetname "")
		)
		(fill
			(thermal_gap 0.5)
			(thermal_bridge_width 0.5)
			(island_removal_mode 0)
		)
		(polygon
			(pts
				(arc
					(start 439.849514 -208.632298)
					(mid 439.845794 -208.641278)
					(end 439.836814 -208.644998)
				)
				(arc
					(start 438.363614 -208.644998)
					(mid 438.354634 -208.641278)
					(end 438.350914 -208.632298)
				)
				(arc
					(start 438.350914 -208.13776)
					(mid 438.354634 -208.12878)
					(end 438.363614 -208.12506)
				)
				(arc
					(start 439.836814 -208.12506)
					(mid 439.845794 -208.12878)
					(end 439.849514 -208.13776)
				)
			)
		)
	)
	(zone
		(layer "In1.Cu")
		(hatch none 0.5)
		(connect_pads
			(clearance 0)
		)
		(min_thickness 0.25)
		(keepout
			(tracks not_allowed)
			(vias allowed)
			(pads allowed)
			(copperpour not_allowed)
			(footprints allowed)
		)
		(placement
			(enabled no)
			(sheetname "")
		)
		(fill
			(thermal_gap 0.5)
			(thermal_bridge_width 0.5)
			(island_removal_mode 0)
		)
		(polygon
			(pts
				(arc
					(start 22.45741 -238.382556)
					(mid 22.45369 -238.391536)
					(end 22.44471 -238.395256)
				)
				(arc
					(start 20.97151 -238.395256)
					(mid 20.96253 -238.391536)
					(end 20.95881 -238.382556)
				)
				(arc
					(start 20.95881 -237.888018)
					(mid 20.96253 -237.879038)
					(end 20.97151 -237.875318)
				)
				(arc
					(start 22.44471 -237.875318)
					(mid 22.45369 -237.879038)
					(end 22.45741 -237.888018)
				)
			)
		)
	)
	(zone
		(layer "In1.Cu")
		(hatch none 0.5)
		(connect_pads
			(clearance 0)
		)
		(min_thickness 0.25)
		(keepout
			(tracks not_allowed)
			(vias allowed)
			(pads allowed)
			(copperpour not_allowed)
			(footprints allowed)
		)
		(placement
			(enabled no)
			(sheetname "")
		)
		(fill
			(thermal_gap 0.5)
			(thermal_bridge_width 0.5)
			(island_removal_mode 0)
		)
		(polygon
			(pts
				(arc
					(start 98.388932 -386.003292)
					(mid 98.007932 -386.003292)
					(end 98.388932 -386.003292)
				)
			)
		)
	)
	(zone
		(layer "In1.Cu")
		(hatch none 0.5)
		(connect_pads
			(clearance 0)
		)
		(min_thickness 0.25)
		(keepout
			(tracks not_allowed)
			(vias allowed)
			(pads allowed)
			(copperpour not_allowed)
			(footprints allowed)
		)
		(placement
			(enabled no)
			(sheetname "")
		)
		(fill
			(thermal_gap 0.5)
			(thermal_bridge_width 0.5)
			(island_removal_mode 0)
		)
		(polygon
			(pts
				(arc
					(start 37.545264 -254.532384)
					(mid 37.541544 -254.541364)
					(end 37.532564 -254.545084)
				)
				(arc
					(start 36.059364 -254.545084)
					(mid 36.050384 -254.541364)
					(end 36.046664 -254.532384)
				)
				(arc
					(start 36.046664 -254.037846)
					(mid 36.050384 -254.028866)
					(end 36.059364 -254.025146)
				)
				(arc
					(start 37.532564 -254.025146)
					(mid 37.541544 -254.028866)
					(end 37.545264 -254.037846)
				)
			)
		)
	)
	(zone
		(layer "In1.Cu")
		(hatch none 0.5)
		(connect_pads
			(clearance 0)
		)
		(min_thickness 0.25)
		(keepout
			(tracks not_allowed)
			(vias allowed)
			(pads allowed)
			(copperpour not_allowed)
			(footprints allowed)
		)
		(placement
			(enabled no)
			(sheetname "")
		)
		(fill
			(thermal_gap 0.5)
			(thermal_bridge_width 0.5)
			(island_removal_mode 0)
		)
		(polygon
			(pts
				(arc
					(start 30.001464 -225.632518)
					(mid 29.997744 -225.641498)
					(end 29.988764 -225.645218)
				)
				(arc
					(start 28.515564 -225.645218)
					(mid 28.506584 -225.641498)
					(end 28.502864 -225.632518)
				)
				(arc
					(start 28.502864 -225.13798)
					(mid 28.506584 -225.129)
					(end 28.515564 -225.12528)
				)
				(arc
					(start 29.988764 -225.12528)
					(mid 29.997744 -225.129)
					(end 30.001464 -225.13798)
				)
			)
		)
	)
	(zone
		(layer "In1.Cu")
		(hatch none 0.5)
		(connect_pads
			(clearance 0)
		)
		(min_thickness 0.25)
		(keepout
			(tracks not_allowed)
			(vias allowed)
			(pads allowed)
			(copperpour not_allowed)
			(footprints allowed)
		)
		(placement
			(enabled no)
			(sheetname "")
		)
		(fill
			(thermal_gap 0.5)
			(thermal_bridge_width 0.5)
			(island_removal_mode 0)
		)
		(polygon
			(pts
				(arc
					(start 304.017426 -302.982122)
					(mid 304.013706 -302.991102)
					(end 304.004726 -302.994822)
				)
				(arc
					(start 302.531526 -302.994822)
					(mid 302.522546 -302.991102)
					(end 302.518826 -302.982122)
				)
				(arc
					(start 302.518826 -302.487584)
					(mid 302.522546 -302.478604)
					(end 302.531526 -302.474884)
				)
				(arc
					(start 304.004726 -302.474884)
					(mid 304.013706 -302.478604)
					(end 304.017426 -302.487584)
				)
			)
		)
	)
	(zone
		(layer "In1.Cu")
		(hatch none 0.5)
		(connect_pads
			(clearance 0)
		)
		(min_thickness 0.25)
		(keepout
			(tracks not_allowed)
			(vias allowed)
			(pads allowed)
			(copperpour not_allowed)
			(footprints allowed)
		)
		(placement
			(enabled no)
			(sheetname "")
		)
		(fill
			(thermal_gap 0.5)
			(thermal_bridge_width 0.5)
			(island_removal_mode 0)
		)
		(polygon
			(pts
				(arc
					(start 184.365392 -285.98241)
					(mid 184.361672 -285.99139)
					(end 184.352692 -285.99511)
				)
				(arc
					(start 182.879492 -285.99511)
					(mid 182.870512 -285.99139)
					(end 182.866792 -285.98241)
				)
				(arc
					(start 182.866792 -285.487872)
					(mid 182.870512 -285.478892)
					(end 182.879492 -285.475172)
				)
				(arc
					(start 184.352692 -285.475172)
					(mid 184.361672 -285.478892)
					(end 184.365392 -285.487872)
				)
			)
		)
	)
	(zone
		(layer "In1.Cu")
		(hatch none 0.5)
		(connect_pads
			(clearance 0)
		)
		(min_thickness 0.25)
		(keepout
			(tracks not_allowed)
			(vias allowed)
			(pads allowed)
			(copperpour not_allowed)
			(footprints allowed)
		)
		(placement
			(enabled no)
			(sheetname "")
		)
		(fill
			(thermal_gap 0.5)
			(thermal_bridge_width 0.5)
			(island_removal_mode 0)
		)
		(polygon
			(pts
				(arc
					(start 435.749446 -253.682246)
					(mid 435.745726 -253.691226)
					(end 435.736746 -253.694946)
				)
				(arc
					(start 434.263546 -253.694946)
					(mid 434.254566 -253.691226)
					(end 434.250846 -253.682246)
				)
				(arc
					(start 434.250846 -253.187708)
					(mid 434.254566 -253.178728)
					(end 434.263546 -253.175008)
				)
				(arc
					(start 435.736746 -253.175008)
					(mid 435.745726 -253.178728)
					(end 435.749446 -253.187708)
				)
			)
		)
	)
	(zone
		(layer "In1.Cu")
		(hatch none 0.5)
		(connect_pads
			(clearance 0)
		)
		(min_thickness 0.25)
		(keepout
			(tracks not_allowed)
			(vias allowed)
			(pads allowed)
			(copperpour not_allowed)
			(footprints allowed)
		)
		(placement
			(enabled no)
			(sheetname "")
		)
		(fill
			(thermal_gap 0.5)
			(thermal_bridge_width 0.5)
			(island_removal_mode 0)
		)
		(polygon
			(pts
				(arc
					(start 420.661338 -290.232338)
					(mid 420.657618 -290.241318)
					(end 420.648638 -290.245038)
				)
				(arc
					(start 419.175438 -290.245038)
					(mid 419.166458 -290.241318)
					(end 419.162738 -290.232338)
				)
				(arc
					(start 419.162738 -289.7378)
					(mid 419.166458 -289.72882)
					(end 419.175438 -289.7251)
				)
				(arc
					(start 420.648638 -289.7251)
					(mid 420.657618 -289.72882)
					(end 420.661338 -289.7378)
				)
			)
		)
	)
	(zone
		(layer "In1.Cu")
		(hatch none 0.5)
		(connect_pads
			(clearance 0)
		)
		(min_thickness 0.25)
		(keepout
			(tracks not_allowed)
			(vias allowed)
			(pads allowed)
			(copperpour not_allowed)
			(footprints allowed)
		)
		(placement
			(enabled no)
			(sheetname "")
		)
		(fill
			(thermal_gap 0.5)
			(thermal_bridge_width 0.5)
			(island_removal_mode 0)
		)
		(polygon
			(pts
				(arc
					(start 416.688778 -394.385292)
					(mid 416.307778 -394.385292)
					(end 416.688778 -394.385292)
				)
			)
		)
	)
	(zone
		(layer "In1.Cu")
		(hatch none 0.5)
		(connect_pads
			(clearance 0)
		)
		(min_thickness 0.25)
		(keepout
			(tracks not_allowed)
			(vias allowed)
			(pads allowed)
			(copperpour not_allowed)
			(footprints allowed)
		)
		(placement
			(enabled no)
			(sheetname "")
		)
		(fill
			(thermal_gap 0.5)
			(thermal_bridge_width 0.5)
			(island_removal_mode 0)
		)
		(polygon
			(pts
				(arc
					(start 191.909446 -314.032392)
					(mid 191.905726 -314.041372)
					(end 191.896746 -314.045092)
				)
				(arc
					(start 190.423546 -314.045092)
					(mid 190.414566 -314.041372)
					(end 190.410846 -314.032392)
				)
				(arc
					(start 190.410846 -313.537854)
					(mid 190.414566 -313.528874)
					(end 190.423546 -313.525154)
				)
				(arc
					(start 191.896746 -313.525154)
					(mid 191.905726 -313.528874)
					(end 191.909446 -313.537854)
				)
			)
		)
	)
	(zone
		(layer "In1.Cu")
		(hatch none 0.5)
		(connect_pads
			(clearance 0)
		)
		(min_thickness 0.25)
		(keepout
			(tracks not_allowed)
			(vias allowed)
			(pads allowed)
			(copperpour not_allowed)
			(footprints allowed)
		)
		(placement
			(enabled no)
			(sheetname "")
		)
		(fill
			(thermal_gap 0.5)
			(thermal_bridge_width 0.5)
			(island_removal_mode 0)
		)
		(polygon
			(pts
				(arc
					(start 165.177216 -302.982376)
					(mid 165.173496 -302.991356)
					(end 165.164516 -302.995076)
				)
				(arc
					(start 163.691316 -302.995076)
					(mid 163.682336 -302.991356)
					(end 163.678616 -302.982376)
				)
				(arc
					(start 163.678616 -302.487838)
					(mid 163.682336 -302.478858)
					(end 163.691316 -302.475138)
				)
				(arc
					(start 165.164516 -302.475138)
					(mid 165.173496 -302.478858)
					(end 165.177216 -302.487838)
				)
			)
		)
	)
	(zone
		(layer "In1.Cu")
		(hatch none 0.5)
		(connect_pads
			(clearance 0)
		)
		(min_thickness 0.25)
		(keepout
			(tracks not_allowed)
			(vias allowed)
			(pads allowed)
			(copperpour not_allowed)
			(footprints allowed)
		)
		(placement
			(enabled no)
			(sheetname "")
		)
		(fill
			(thermal_gap 0.5)
			(thermal_bridge_width 0.5)
			(island_removal_mode 0)
		)
		(polygon
			(pts
				(arc
					(start 300.57344 -276.632162)
					(mid 300.56972 -276.641142)
					(end 300.56074 -276.644862)
				)
				(arc
					(start 299.08754 -276.644862)
					(mid 299.07856 -276.641142)
					(end 299.07484 -276.632162)
				)
				(arc
					(start 299.07484 -276.137624)
					(mid 299.07856 -276.128644)
					(end 299.08754 -276.124924)
				)
				(arc
					(start 300.56074 -276.124924)
					(mid 300.56972 -276.128644)
					(end 300.57344 -276.137624)
				)
			)
		)
	)
	(zone
		(layer "In1.Cu")
		(hatch none 0.5)
		(connect_pads
			(clearance 0)
		)
		(min_thickness 0.25)
		(keepout
			(tracks not_allowed)
			(vias allowed)
			(pads allowed)
			(copperpour not_allowed)
			(footprints allowed)
		)
		(placement
			(enabled no)
			(sheetname "")
		)
		(fill
			(thermal_gap 0.5)
			(thermal_bridge_width 0.5)
			(island_removal_mode 0)
		)
		(polygon
			(pts
				(arc
					(start 411.48889 -397.156432)
					(mid 411.10789 -397.156432)
					(end 411.48889 -397.156432)
				)
			)
		)
	)
	(zone
		(layer "In1.Cu")
		(hatch none 0.5)
		(connect_pads
			(clearance 0)
		)
		(min_thickness 0.25)
		(keepout
			(tracks not_allowed)
			(vias allowed)
			(pads allowed)
			(copperpour not_allowed)
			(footprints allowed)
		)
		(placement
			(enabled no)
			(sheetname "")
		)
		(fill
			(thermal_gap 0.5)
			(thermal_bridge_width 0.5)
			(island_removal_mode 0)
		)
		(polygon
			(pts
				(arc
					(start 285.485332 -298.732194)
					(mid 285.481612 -298.741174)
					(end 285.472632 -298.744894)
				)
				(arc
					(start 283.999432 -298.744894)
					(mid 283.990452 -298.741174)
					(end 283.986732 -298.732194)
				)
				(arc
					(start 283.986732 -298.237656)
					(mid 283.990452 -298.228676)
					(end 283.999432 -298.224956)
				)
				(arc
					(start 285.472632 -298.224956)
					(mid 285.481612 -298.228676)
					(end 285.485332 -298.237656)
				)
			)
		)
	)
	(zone
		(layer "In1.Cu")
		(hatch none 0.5)
		(connect_pads
			(clearance 0)
		)
		(min_thickness 0.25)
		(keepout
			(tracks not_allowed)
			(vias allowed)
			(pads allowed)
			(copperpour not_allowed)
			(footprints allowed)
		)
		(placement
			(enabled no)
			(sheetname "")
		)
		(fill
			(thermal_gap 0.5)
			(thermal_bridge_width 0.5)
			(island_removal_mode 0)
		)
		(polygon
			(pts
				(arc
					(start 285.485332 -289.3822)
					(mid 285.481612 -289.39118)
					(end 285.472632 -289.3949)
				)
				(arc
					(start 283.999432 -289.3949)
					(mid 283.990452 -289.39118)
					(end 283.986732 -289.3822)
				)
				(arc
					(start 283.986732 -288.887662)
					(mid 283.990452 -288.878682)
					(end 283.999432 -288.874962)
				)
				(arc
					(start 285.472632 -288.874962)
					(mid 285.481612 -288.878682)
					(end 285.485332 -288.887662)
				)
			)
		)
	)
	(zone
		(layer "In1.Cu")
		(hatch none 0.5)
		(connect_pads
			(clearance 0)
		)
		(min_thickness 0.25)
		(keepout
			(tracks not_allowed)
			(vias allowed)
			(pads allowed)
			(copperpour not_allowed)
			(footprints allowed)
		)
		(placement
			(enabled no)
			(sheetname "")
		)
		(fill
			(thermal_gap 0.5)
			(thermal_bridge_width 0.5)
			(island_removal_mode 0)
		)
		(polygon
			(pts
				(arc
					(start 339.118448 -399.701258)
					(mid 339.245448 -399.828258)
					(end 339.372448 -399.701258)
				)
				(arc
					(start 339.372448 -399.625058)
					(mid 339.245448 -399.498058)
					(end 339.118448 -399.625058)
				)
			)
		)
	)
	(zone
		(layer "In1.Cu")
		(hatch none 0.5)
		(connect_pads
			(clearance 0)
		)
		(min_thickness 0.25)
		(keepout
			(tracks not_allowed)
			(vias allowed)
			(pads allowed)
			(copperpour not_allowed)
			(footprints allowed)
		)
		(placement
			(enabled no)
			(sheetname "")
		)
		(fill
			(thermal_gap 0.5)
			(thermal_bridge_width 0.5)
			(island_removal_mode 0)
		)
		(polygon
			(pts
				(arc
					(start 266.29741 -201.83221)
					(mid 266.29369 -201.84119)
					(end 266.28471 -201.84491)
				)
				(arc
					(start 264.81151 -201.84491)
					(mid 264.80253 -201.84119)
					(end 264.79881 -201.83221)
				)
				(arc
					(start 264.79881 -201.337672)
					(mid 264.80253 -201.328692)
					(end 264.81151 -201.324972)
				)
				(arc
					(start 266.28471 -201.324972)
					(mid 266.29369 -201.328692)
					(end 266.29741 -201.337672)
				)
			)
		)
	)
	(zone
		(layer "In1.Cu")
		(hatch none 0.5)
		(connect_pads
			(clearance 0)
		)
		(min_thickness 0.25)
		(keepout
			(tracks not_allowed)
			(vias allowed)
			(pads allowed)
			(copperpour not_allowed)
			(footprints allowed)
		)
		(placement
			(enabled no)
			(sheetname "")
		)
		(fill
			(thermal_gap 0.5)
			(thermal_bridge_width 0.5)
			(island_removal_mode 0)
		)
		(polygon
			(pts
				(arc
					(start 424.761406 -298.732194)
					(mid 424.757686 -298.741174)
					(end 424.748706 -298.744894)
				)
				(arc
					(start 423.275506 -298.744894)
					(mid 423.266526 -298.741174)
					(end 423.262806 -298.732194)
				)
				(arc
					(start 423.262806 -298.237656)
					(mid 423.266526 -298.228676)
					(end 423.275506 -298.224956)
				)
				(arc
					(start 424.748706 -298.224956)
					(mid 424.757686 -298.228676)
					(end 424.761406 -298.237656)
				)
			)
		)
	)
	(zone
		(layer "In1.Cu")
		(hatch none 0.5)
		(connect_pads
			(clearance 0)
		)
		(min_thickness 0.25)
		(keepout
			(tracks not_allowed)
			(vias allowed)
			(pads allowed)
			(copperpour not_allowed)
			(footprints allowed)
		)
		(placement
			(enabled no)
			(sheetname "")
		)
		(fill
			(thermal_gap 0.5)
			(thermal_bridge_width 0.5)
			(island_removal_mode 0)
		)
		(polygon
			(pts
				(arc
					(start 428.205392 -297.88231)
					(mid 428.201672 -297.89129)
					(end 428.192692 -297.89501)
				)
				(arc
					(start 426.719492 -297.89501)
					(mid 426.710512 -297.89129)
					(end 426.706792 -297.88231)
				)
				(arc
					(start 426.706792 -297.387772)
					(mid 426.710512 -297.378792)
					(end 426.719492 -297.375072)
				)
				(arc
					(start 428.192692 -297.375072)
					(mid 428.201672 -297.378792)
					(end 428.205392 -297.387772)
				)
			)
		)
	)
	(zone
		(layer "In1.Cu")
		(hatch none 0.5)
		(connect_pads
			(clearance 0)
		)
		(min_thickness 0.25)
		(keepout
			(tracks not_allowed)
			(vias allowed)
			(pads allowed)
			(copperpour not_allowed)
			(footprints allowed)
		)
		(placement
			(enabled no)
			(sheetname "")
		)
		(fill
			(thermal_gap 0.5)
			(thermal_bridge_width 0.5)
			(island_removal_mode 0)
		)
		(polygon
			(pts
				(arc
					(start 180.265324 -230.732584)
					(mid 180.261604 -230.741564)
					(end 180.252624 -230.745284)
				)
				(arc
					(start 178.779424 -230.745284)
					(mid 178.770444 -230.741564)
					(end 178.766724 -230.732584)
				)
				(arc
					(start 178.766724 -230.238046)
					(mid 178.770444 -230.229066)
					(end 178.779424 -230.225346)
				)
				(arc
					(start 180.252624 -230.225346)
					(mid 180.261604 -230.229066)
					(end 180.265324 -230.238046)
				)
			)
		)
	)
	(zone
		(layer "In1.Cu")
		(hatch none 0.5)
		(connect_pads
			(clearance 0)
		)
		(min_thickness 0.25)
		(keepout
			(tracks not_allowed)
			(vias allowed)
			(pads allowed)
			(copperpour not_allowed)
			(footprints allowed)
		)
		(placement
			(enabled no)
			(sheetname "")
		)
		(fill
			(thermal_gap 0.5)
			(thermal_bridge_width 0.5)
			(island_removal_mode 0)
		)
		(polygon
			(pts
				(arc
					(start 148.28901 -385.31038)
					(mid 147.90801 -385.31038)
					(end 148.28901 -385.31038)
				)
			)
		)
	)
	(zone
		(layer "In1.Cu")
		(hatch none 0.5)
		(connect_pads
			(clearance 0)
		)
		(min_thickness 0.25)
		(keepout
			(tracks not_allowed)
			(vias allowed)
			(pads allowed)
			(copperpour not_allowed)
			(footprints allowed)
		)
		(placement
			(enabled no)
			(sheetname "")
		)
		(fill
			(thermal_gap 0.5)
			(thermal_bridge_width 0.5)
			(island_removal_mode 0)
		)
		(polygon
			(pts
				(arc
					(start 40.98925 -254.532384)
					(mid 40.98553 -254.541364)
					(end 40.97655 -254.545084)
				)
				(arc
					(start 39.50335 -254.545084)
					(mid 39.49437 -254.541364)
					(end 39.49065 -254.532384)
				)
				(arc
					(start 39.49065 -254.037846)
					(mid 39.49437 -254.028866)
					(end 39.50335 -254.025146)
				)
				(arc
					(start 40.97655 -254.025146)
					(mid 40.98553 -254.028866)
					(end 40.98925 -254.037846)
				)
			)
		)
	)
	(zone
		(layer "In1.Cu")
		(hatch none 0.5)
		(connect_pads
			(clearance 0)
		)
		(min_thickness 0.25)
		(keepout
			(tracks not_allowed)
			(vias allowed)
			(pads allowed)
			(copperpour not_allowed)
			(footprints allowed)
		)
		(placement
			(enabled no)
			(sheetname "")
		)
		(fill
			(thermal_gap 0.5)
			(thermal_bridge_width 0.5)
			(island_removal_mode 0)
		)
		(polygon
			(pts
				(arc
					(start 165.177216 -201.832464)
					(mid 165.173496 -201.841444)
					(end 165.164516 -201.845164)
				)
				(arc
					(start 163.691316 -201.845164)
					(mid 163.682336 -201.841444)
					(end 163.678616 -201.832464)
				)
				(arc
					(start 163.678616 -201.337926)
					(mid 163.682336 -201.328946)
					(end 163.691316 -201.325226)
				)
				(arc
					(start 165.164516 -201.325226)
					(mid 165.173496 -201.328946)
					(end 165.177216 -201.337926)
				)
			)
		)
	)
	(zone
		(layer "In1.Cu")
		(hatch none 0.5)
		(connect_pads
			(clearance 0)
		)
		(min_thickness 0.25)
		(keepout
			(tracks not_allowed)
			(vias allowed)
			(pads allowed)
			(copperpour not_allowed)
			(footprints allowed)
		)
		(placement
			(enabled no)
			(sheetname "")
		)
		(fill
			(thermal_gap 0.5)
			(thermal_bridge_width 0.5)
			(island_removal_mode 0)
		)
		(polygon
			(pts
				(arc
					(start 388.670292 -399.143474)
					(mid 388.365492 -399.143474)
					(end 388.670292 -399.143474)
				)
			)
		)
	)
	(zone
		(layer "In1.Cu")
		(hatch none 0.5)
		(connect_pads
			(clearance 0)
		)
		(min_thickness 0.25)
		(keepout
			(tracks not_allowed)
			(vias allowed)
			(pads allowed)
			(copperpour not_allowed)
			(footprints allowed)
		)
		(placement
			(enabled no)
			(sheetname "")
		)
		(fill
			(thermal_gap 0.5)
			(thermal_bridge_width 0.5)
			(island_removal_mode 0)
		)
		(polygon
			(pts
				(arc
					(start 304.661062 -397.156432)
					(mid 304.280062 -397.156432)
					(end 304.661062 -397.156432)
				)
			)
		)
	)
	(zone
		(layer "In1.Cu")
		(hatch none 0.5)
		(connect_pads
			(clearance 0)
		)
		(min_thickness 0.25)
		(keepout
			(tracks not_allowed)
			(vias allowed)
			(pads allowed)
			(copperpour not_allowed)
			(footprints allowed)
		)
		(placement
			(enabled no)
			(sheetname "")
		)
		(fill
			(thermal_gap 0.5)
			(thermal_bridge_width 0.5)
			(island_removal_mode 0)
		)
		(polygon
			(pts
				(arc
					(start 428.205392 -280.88209)
					(mid 428.201672 -280.89107)
					(end 428.192692 -280.89479)
				)
				(arc
					(start 426.719492 -280.89479)
					(mid 426.710512 -280.89107)
					(end 426.706792 -280.88209)
				)
				(arc
					(start 426.706792 -280.387552)
					(mid 426.710512 -280.378572)
					(end 426.719492 -280.374852)
				)
				(arc
					(start 428.192692 -280.374852)
					(mid 428.201672 -280.378572)
					(end 428.205392 -280.387552)
				)
			)
		)
	)
	(zone
		(layer "In1.Cu")
		(hatch none 0.5)
		(connect_pads
			(clearance 0)
		)
		(min_thickness 0.25)
		(keepout
			(tracks not_allowed)
			(vias allowed)
			(pads allowed)
			(copperpour not_allowed)
			(footprints allowed)
		)
		(placement
			(enabled no)
			(sheetname "")
		)
		(fill
			(thermal_gap 0.5)
			(thermal_bridge_width 0.5)
			(island_removal_mode 0)
		)
		(polygon
			(pts
				(arc
					(start 30.001464 -210.332574)
					(mid 29.997744 -210.341554)
					(end 29.988764 -210.345274)
				)
				(arc
					(start 28.515564 -210.345274)
					(mid 28.506584 -210.341554)
					(end 28.502864 -210.332574)
				)
				(arc
					(start 28.502864 -209.838036)
					(mid 28.506584 -209.829056)
					(end 28.515564 -209.825336)
				)
				(arc
					(start 29.988764 -209.825336)
					(mid 29.997744 -209.829056)
					(end 30.001464 -209.838036)
				)
			)
		)
	)
	(zone
		(layer "In1.Cu")
		(hatch none 0.5)
		(connect_pads
			(clearance 0)
		)
		(min_thickness 0.25)
		(keepout
			(tracks not_allowed)
			(vias allowed)
			(pads allowed)
			(copperpour not_allowed)
			(footprints allowed)
		)
		(placement
			(enabled no)
			(sheetname "")
		)
		(fill
			(thermal_gap 0.5)
			(thermal_bridge_width 0.5)
			(island_removal_mode 0)
		)
		(polygon
			(pts
				(arc
					(start 308.117494 -280.032206)
					(mid 308.113774 -280.041186)
					(end 308.104794 -280.044906)
				)
				(arc
					(start 306.631594 -280.044906)
					(mid 306.622614 -280.041186)
					(end 306.618894 -280.032206)
				)
				(arc
					(start 306.618894 -279.537668)
					(mid 306.622614 -279.528688)
					(end 306.631594 -279.524968)
				)
				(arc
					(start 308.104794 -279.524968)
					(mid 308.113774 -279.528688)
					(end 308.117494 -279.537668)
				)
			)
		)
	)
	(zone
		(layer "In1.Cu")
		(hatch none 0.5)
		(connect_pads
			(clearance 0)
		)
		(min_thickness 0.25)
		(keepout
			(tracks not_allowed)
			(vias allowed)
			(pads allowed)
			(copperpour not_allowed)
			(footprints allowed)
		)
		(placement
			(enabled no)
			(sheetname "")
		)
		(fill
			(thermal_gap 0.5)
			(thermal_bridge_width 0.5)
			(island_removal_mode 0)
		)
		(polygon
			(pts
				(arc
					(start 47.461424 -388.774432)
					(mid 47.080424 -388.774432)
					(end 47.461424 -388.774432)
				)
			)
		)
	)
	(zone
		(layer "In1.Cu")
		(hatch none 0.5)
		(connect_pads
			(clearance 0)
		)
		(min_thickness 0.25)
		(keepout
			(tracks not_allowed)
			(vias allowed)
			(pads allowed)
			(copperpour not_allowed)
			(footprints allowed)
		)
		(placement
			(enabled no)
			(sheetname "")
		)
		(fill
			(thermal_gap 0.5)
			(thermal_bridge_width 0.5)
			(island_removal_mode 0)
		)
		(polygon
			(pts
				(arc
					(start 45.089318 -274.08251)
					(mid 45.085598 -274.09149)
					(end 45.076618 -274.09521)
				)
				(arc
					(start 43.603418 -274.09521)
					(mid 43.594438 -274.09149)
					(end 43.590718 -274.08251)
				)
				(arc
					(start 43.590718 -273.587972)
					(mid 43.594438 -273.578992)
					(end 43.603418 -273.575272)
				)
				(arc
					(start 45.076618 -273.575272)
					(mid 45.085598 -273.578992)
					(end 45.089318 -273.587972)
				)
			)
		)
	)
	(zone
		(layer "In1.Cu")
		(hatch none 0.5)
		(connect_pads
			(clearance 0)
		)
		(min_thickness 0.25)
		(keepout
			(tracks not_allowed)
			(vias allowed)
			(pads allowed)
			(copperpour not_allowed)
			(footprints allowed)
		)
		(placement
			(enabled no)
			(sheetname "")
		)
		(fill
			(thermal_gap 0.5)
			(thermal_bridge_width 0.5)
			(island_removal_mode 0)
		)
		(polygon
			(pts
				(arc
					(start 102.995222 -29.476954)
					(mid 103.01754 -29.423072)
					(end 103.071422 -29.400754)
				)
				(arc
					(start 103.300022 -29.400754)
					(mid 103.353904 -29.423072)
					(end 103.376222 -29.476954)
				)
				(arc
					(start 103.376222 -29.629354)
					(mid 103.353904 -29.683236)
					(end 103.300022 -29.705554)
				)
				(arc
					(start 103.071422 -29.705554)
					(mid 103.01754 -29.683236)
					(end 102.995222 -29.629354)
				)
			)
		)
	)
	(zone
		(layer "In1.Cu")
		(hatch none 0.5)
		(connect_pads
			(clearance 0)
		)
		(min_thickness 0.25)
		(keepout
			(tracks not_allowed)
			(vias allowed)
			(pads allowed)
			(copperpour not_allowed)
			(footprints allowed)
		)
		(placement
			(enabled no)
			(sheetname "")
		)
		(fill
			(thermal_gap 0.5)
			(thermal_bridge_width 0.5)
			(island_removal_mode 0)
		)
		(polygon
			(pts
				(arc
					(start 424.761406 -297.032172)
					(mid 424.757686 -297.041152)
					(end 424.748706 -297.044872)
				)
				(arc
					(start 423.275506 -297.044872)
					(mid 423.266526 -297.041152)
					(end 423.262806 -297.032172)
				)
				(arc
					(start 423.262806 -296.537634)
					(mid 423.266526 -296.528654)
					(end 423.275506 -296.524934)
				)
				(arc
					(start 424.748706 -296.524934)
					(mid 424.757686 -296.528654)
					(end 424.761406 -296.537634)
				)
			)
		)
	)
	(zone
		(layer "In1.Cu")
		(hatch none 0.5)
		(connect_pads
			(clearance 0)
		)
		(min_thickness 0.25)
		(keepout
			(tracks not_allowed)
			(vias allowed)
			(pads allowed)
			(copperpour not_allowed)
			(footprints allowed)
		)
		(placement
			(enabled no)
			(sheetname "")
		)
		(fill
			(thermal_gap 0.5)
			(thermal_bridge_width 0.5)
			(island_removal_mode 0)
		)
		(polygon
			(pts
				(arc
					(start 97.188782 -386.003292)
					(mid 96.807782 -386.003292)
					(end 97.188782 -386.003292)
				)
			)
		)
	)
	(zone
		(layer "In1.Cu")
		(hatch none 0.5)
		(connect_pads
			(clearance 0)
		)
		(min_thickness 0.25)
		(keepout
			(tracks not_allowed)
			(vias allowed)
			(pads allowed)
			(copperpour not_allowed)
			(footprints allowed)
		)
		(placement
			(enabled no)
			(sheetname "")
		)
		(fill
			(thermal_gap 0.5)
			(thermal_bridge_width 0.5)
			(island_removal_mode 0)
		)
		(polygon
			(pts
				(arc
					(start 37.545264 -247.73255)
					(mid 37.541544 -247.74153)
					(end 37.532564 -247.74525)
				)
				(arc
					(start 36.059364 -247.74525)
					(mid 36.050384 -247.74153)
					(end 36.046664 -247.73255)
				)
				(arc
					(start 36.046664 -247.238012)
					(mid 36.050384 -247.229032)
					(end 36.059364 -247.225312)
				)
				(arc
					(start 37.532564 -247.225312)
					(mid 37.541544 -247.229032)
					(end 37.545264 -247.238012)
				)
			)
		)
	)
	(zone
		(layer "In1.Cu")
		(hatch none 0.5)
		(connect_pads
			(clearance 0)
		)
		(min_thickness 0.25)
		(keepout
			(tracks not_allowed)
			(vias allowed)
			(pads allowed)
			(copperpour not_allowed)
			(footprints allowed)
		)
		(placement
			(enabled no)
			(sheetname "")
		)
		(fill
			(thermal_gap 0.5)
			(thermal_bridge_width 0.5)
			(island_removal_mode 0)
		)
		(polygon
			(pts
				(arc
					(start 318.26073 -394.385292)
					(mid 317.87973 -394.385292)
					(end 318.26073 -394.385292)
				)
			)
		)
	)
	(zone
		(layer "In1.Cu")
		(hatch none 0.5)
		(connect_pads
			(clearance 0)
		)
		(min_thickness 0.25)
		(keepout
			(tracks not_allowed)
			(vias allowed)
			(pads allowed)
			(copperpour not_allowed)
			(footprints allowed)
		)
		(placement
			(enabled no)
			(sheetname "")
		)
		(fill
			(thermal_gap 0.5)
			(thermal_bridge_width 0.5)
			(island_removal_mode 0)
		)
		(polygon
			(pts
				(arc
					(start 285.485332 -208.632298)
					(mid 285.481612 -208.641278)
					(end 285.472632 -208.644998)
				)
				(arc
					(start 283.999432 -208.644998)
					(mid 283.990452 -208.641278)
					(end 283.986732 -208.632298)
				)
				(arc
					(start 283.986732 -208.13776)
					(mid 283.990452 -208.12878)
					(end 283.999432 -208.12506)
				)
				(arc
					(start 285.472632 -208.12506)
					(mid 285.481612 -208.12878)
					(end 285.485332 -208.13776)
				)
			)
		)
	)
	(zone
		(layer "In1.Cu")
		(hatch none 0.5)
		(connect_pads
			(clearance 0)
		)
		(min_thickness 0.25)
		(keepout
			(tracks not_allowed)
			(vias allowed)
			(pads allowed)
			(copperpour not_allowed)
			(footprints allowed)
		)
		(placement
			(enabled no)
			(sheetname "")
		)
		(fill
			(thermal_gap 0.5)
			(thermal_bridge_width 0.5)
			(island_removal_mode 0)
		)
		(polygon
			(pts
				(arc
					(start 195.353432 -213.732364)
					(mid 195.349712 -213.741344)
					(end 195.340732 -213.745064)
				)
				(arc
					(start 193.867532 -213.745064)
					(mid 193.858552 -213.741344)
					(end 193.854832 -213.732364)
				)
				(arc
					(start 193.854832 -213.237826)
					(mid 193.858552 -213.228846)
					(end 193.867532 -213.225126)
				)
				(arc
					(start 195.340732 -213.225126)
					(mid 195.349712 -213.228846)
					(end 195.353432 -213.237826)
				)
			)
		)
	)
	(zone
		(layer "In1.Cu")
		(hatch none 0.5)
		(connect_pads
			(clearance 0)
		)
		(min_thickness 0.25)
		(keepout
			(tracks not_allowed)
			(vias allowed)
			(pads allowed)
			(copperpour not_allowed)
			(footprints allowed)
		)
		(placement
			(enabled no)
			(sheetname "")
		)
		(fill
			(thermal_gap 0.5)
			(thermal_bridge_width 0.5)
			(island_removal_mode 0)
		)
		(polygon
			(pts
				(arc
					(start 51.977544 -17.967198)
					(mid 51.999862 -18.02108)
					(end 52.053744 -18.043398)
				)
				(arc
					(start 52.249324 -18.043398)
					(mid 52.2712 -18.040266)
					(end 52.291234 -18.030952)
				)
				(arc
					(start 52.584858 -17.83842)
					(mid 52.626514 -17.826018)
					(end 52.66817 -17.83842)
				)
				(arc
					(start 52.963064 -18.030952)
					(mid 52.982988 -18.040188)
					(end 53.00472 -18.043398)
				)
				(arc
					(start 53.199284 -18.043398)
					(mid 53.253166 -18.02108)
					(end 53.275484 -17.967198)
				)
				(arc
					(start 53.275484 -17.281398)
					(mid 53.253166 -17.227516)
					(end 53.199284 -17.205198)
				)
				(arc
					(start 53.00472 -17.205198)
					(mid 52.982976 -17.208366)
					(end 52.963064 -17.217644)
				)
				(arc
					(start 52.6669 -17.41043)
					(mid 52.625216 -17.422652)
					(end 52.583588 -17.410176)
				)
				(arc
					(start 52.289964 -17.217644)
					(mid 52.27004 -17.208408)
					(end 52.248308 -17.205198)
				)
				(arc
					(start 52.053744 -17.205198)
					(mid 51.999862 -17.227516)
					(end 51.977544 -17.281398)
				)
			)
		)
	)
	(zone
		(layer "In1.Cu")
		(hatch none 0.5)
		(connect_pads
			(clearance 0)
		)
		(min_thickness 0.25)
		(keepout
			(tracks not_allowed)
			(vias allowed)
			(pads allowed)
			(copperpour not_allowed)
			(footprints allowed)
		)
		(placement
			(enabled no)
			(sheetname "")
		)
		(fill
			(thermal_gap 0.5)
			(thermal_bridge_width 0.5)
			(island_removal_mode 0)
		)
		(polygon
			(pts
				(arc
					(start 447.393568 -220.532198)
					(mid 447.389848 -220.541178)
					(end 447.380868 -220.544898)
				)
				(arc
					(start 445.907668 -220.544898)
					(mid 445.898688 -220.541178)
					(end 445.894968 -220.532198)
				)
				(arc
					(start 445.894968 -220.03766)
					(mid 445.898688 -220.02868)
					(end 445.907668 -220.02496)
				)
				(arc
					(start 447.380868 -220.02496)
					(mid 447.389848 -220.02868)
					(end 447.393568 -220.03766)
				)
			)
		)
	)
	(zone
		(layer "In1.Cu")
		(hatch none 0.5)
		(connect_pads
			(clearance 0)
		)
		(min_thickness 0.25)
		(keepout
			(tracks not_allowed)
			(vias allowed)
			(pads allowed)
			(copperpour not_allowed)
			(footprints allowed)
		)
		(placement
			(enabled no)
			(sheetname "")
		)
		(fill
			(thermal_gap 0.5)
			(thermal_bridge_width 0.5)
			(island_removal_mode 0)
		)
		(polygon
			(pts
				(arc
					(start 435.749446 -273.232118)
					(mid 435.745726 -273.241098)
					(end 435.736746 -273.244818)
				)
				(arc
					(start 434.263546 -273.244818)
					(mid 434.254566 -273.241098)
					(end 434.250846 -273.232118)
				)
				(arc
					(start 434.250846 -272.73758)
					(mid 434.254566 -272.7286)
					(end 434.263546 -272.72488)
				)
				(arc
					(start 435.736746 -272.72488)
					(mid 435.745726 -272.7286)
					(end 435.749446 -272.73758)
				)
			)
		)
	)
	(zone
		(layer "In1.Cu")
		(hatch none 0.5)
		(connect_pads
			(clearance 0)
		)
		(min_thickness 0.25)
		(keepout
			(tracks not_allowed)
			(vias allowed)
			(pads allowed)
			(copperpour not_allowed)
			(footprints allowed)
		)
		(placement
			(enabled no)
			(sheetname "")
		)
		(fill
			(thermal_gap 0.5)
			(thermal_bridge_width 0.5)
			(island_removal_mode 0)
		)
		(polygon
			(pts
				(arc
					(start 195.353432 -204.38237)
					(mid 195.349712 -204.39135)
					(end 195.340732 -204.39507)
				)
				(arc
					(start 193.867532 -204.39507)
					(mid 193.858552 -204.39135)
					(end 193.854832 -204.38237)
				)
				(arc
					(start 193.854832 -203.887832)
					(mid 193.858552 -203.878852)
					(end 193.867532 -203.875132)
				)
				(arc
					(start 195.340732 -203.875132)
					(mid 195.349712 -203.878852)
					(end 195.353432 -203.887832)
				)
			)
		)
	)
	(zone
		(layer "In1.Cu")
		(hatch none 0.5)
		(connect_pads
			(clearance 0)
		)
		(min_thickness 0.25)
		(keepout
			(tracks not_allowed)
			(vias allowed)
			(pads allowed)
			(copperpour not_allowed)
			(footprints allowed)
		)
		(placement
			(enabled no)
			(sheetname "")
		)
		(fill
			(thermal_gap 0.5)
			(thermal_bridge_width 0.5)
			(island_removal_mode 0)
		)
		(polygon
			(pts
				(arc
					(start 270.397478 -197.582282)
					(mid 270.393758 -197.591262)
					(end 270.384778 -197.594982)
				)
				(arc
					(start 268.911578 -197.594982)
					(mid 268.902598 -197.591262)
					(end 268.898878 -197.582282)
				)
				(arc
					(start 268.898878 -197.087744)
					(mid 268.902598 -197.078764)
					(end 268.911578 -197.075044)
				)
				(arc
					(start 270.384778 -197.075044)
					(mid 270.393758 -197.078764)
					(end 270.397478 -197.087744)
				)
			)
		)
	)
	(zone
		(layer "In1.Cu")
		(hatch none 0.5)
		(connect_pads
			(clearance 0)
		)
		(min_thickness 0.25)
		(keepout
			(tracks not_allowed)
			(vias allowed)
			(pads allowed)
			(copperpour not_allowed)
			(footprints allowed)
		)
		(placement
			(enabled no)
			(sheetname "")
		)
		(fill
			(thermal_gap 0.5)
			(thermal_bridge_width 0.5)
			(island_removal_mode 0)
		)
		(polygon
			(pts
				(arc
					(start 199.4535 -274.08251)
					(mid 199.44978 -274.09149)
					(end 199.4408 -274.09521)
				)
				(arc
					(start 197.9676 -274.09521)
					(mid 197.95862 -274.09149)
					(end 197.9549 -274.08251)
				)
				(arc
					(start 197.9549 -273.587972)
					(mid 197.95862 -273.578992)
					(end 197.9676 -273.575272)
				)
				(arc
					(start 199.4408 -273.575272)
					(mid 199.44978 -273.578992)
					(end 199.4535 -273.587972)
				)
			)
		)
	)
	(zone
		(layer "In1.Cu")
		(hatch none 0.5)
		(connect_pads
			(clearance 0)
		)
		(min_thickness 0.25)
		(keepout
			(tracks not_allowed)
			(vias allowed)
			(pads allowed)
			(copperpour not_allowed)
			(footprints allowed)
		)
		(placement
			(enabled no)
			(sheetname "")
		)
		(fill
			(thermal_gap 0.5)
			(thermal_bridge_width 0.5)
			(island_removal_mode 0)
		)
		(polygon
			(pts
				(arc
					(start 25.901396 -267.282422)
					(mid 25.897676 -267.291402)
					(end 25.888696 -267.295122)
				)
				(arc
					(start 24.415496 -267.295122)
					(mid 24.406516 -267.291402)
					(end 24.402796 -267.282422)
				)
				(arc
					(start 24.402796 -266.787884)
					(mid 24.406516 -266.778904)
					(end 24.415496 -266.775184)
				)
				(arc
					(start 25.888696 -266.775184)
					(mid 25.897676 -266.778904)
					(end 25.901396 -266.787884)
				)
			)
		)
	)
	(zone
		(layer "In1.Cu")
		(hatch none 0.5)
		(connect_pads
			(clearance 0)
		)
		(min_thickness 0.25)
		(keepout
			(tracks not_allowed)
			(vias allowed)
			(pads allowed)
			(copperpour not_allowed)
			(footprints allowed)
		)
		(placement
			(enabled no)
			(sheetname "")
		)
		(fill
			(thermal_gap 0.5)
			(thermal_bridge_width 0.5)
			(island_removal_mode 0)
		)
		(polygon
			(pts
				(arc
					(start 432.30546 -205.232254)
					(mid 432.30174 -205.241234)
					(end 432.29276 -205.244954)
				)
				(arc
					(start 430.81956 -205.244954)
					(mid 430.81058 -205.241234)
					(end 430.80686 -205.232254)
				)
				(arc
					(start 430.80686 -204.737716)
					(mid 430.81058 -204.728736)
					(end 430.81956 -204.725016)
				)
				(arc
					(start 432.29276 -204.725016)
					(mid 432.30174 -204.728736)
					(end 432.30546 -204.737716)
				)
			)
		)
	)
	(zone
		(layer "In1.Cu")
		(hatch none 0.5)
		(connect_pads
			(clearance 0)
		)
		(min_thickness 0.25)
		(keepout
			(tracks not_allowed)
			(vias allowed)
			(pads allowed)
			(copperpour not_allowed)
			(footprints allowed)
		)
		(placement
			(enabled no)
			(sheetname "")
		)
		(fill
			(thermal_gap 0.5)
			(thermal_bridge_width 0.5)
			(island_removal_mode 0)
		)
		(polygon
			(pts
				(arc
					(start 169.277284 -300.43247)
					(mid 169.273564 -300.44145)
					(end 169.264584 -300.44517)
				)
				(arc
					(start 167.791384 -300.44517)
					(mid 167.782404 -300.44145)
					(end 167.778684 -300.43247)
				)
				(arc
					(start 167.778684 -299.937932)
					(mid 167.782404 -299.928952)
					(end 167.791384 -299.925232)
				)
				(arc
					(start 169.264584 -299.925232)
					(mid 169.273564 -299.928952)
					(end 169.277284 -299.937932)
				)
			)
		)
	)
	(zone
		(layer "In1.Cu")
		(hatch none 0.5)
		(connect_pads
			(clearance 0)
		)
		(min_thickness 0.25)
		(keepout
			(tracks not_allowed)
			(vias allowed)
			(pads allowed)
			(copperpour not_allowed)
			(footprints allowed)
		)
		(placement
			(enabled no)
			(sheetname "")
		)
		(fill
			(thermal_gap 0.5)
			(thermal_bridge_width 0.5)
			(island_removal_mode 0)
		)
		(polygon
			(pts
				(arc
					(start 300.57344 -212.882226)
					(mid 300.56972 -212.891206)
					(end 300.56074 -212.894926)
				)
				(arc
					(start 299.08754 -212.894926)
					(mid 299.07856 -212.891206)
					(end 299.07484 -212.882226)
				)
				(arc
					(start 299.07484 -212.387688)
					(mid 299.07856 -212.378708)
					(end 299.08754 -212.374988)
				)
				(arc
					(start 300.56074 -212.374988)
					(mid 300.56972 -212.378708)
					(end 300.57344 -212.387688)
				)
			)
		)
	)
	(zone
		(layer "In1.Cu")
		(hatch none 0.5)
		(connect_pads
			(clearance 0)
		)
		(min_thickness 0.25)
		(keepout
			(tracks not_allowed)
			(vias allowed)
			(pads allowed)
			(copperpour not_allowed)
			(footprints allowed)
		)
		(placement
			(enabled no)
			(sheetname "")
		)
		(fill
			(thermal_gap 0.5)
			(thermal_bridge_width 0.5)
			(island_removal_mode 0)
		)
		(polygon
			(pts
				(arc
					(start 206.5782 -210.935316)
					(mid 205.9178 -210.935316)
					(end 206.5782 -210.935316)
				)
			)
		)
	)
	(zone
		(layer "In1.Cu")
		(hatch none 0.5)
		(connect_pads
			(clearance 0)
		)
		(min_thickness 0.25)
		(keepout
			(tracks not_allowed)
			(vias allowed)
			(pads allowed)
			(copperpour not_allowed)
			(footprints allowed)
		)
		(placement
			(enabled no)
			(sheetname "")
		)
		(fill
			(thermal_gap 0.5)
			(thermal_bridge_width 0.5)
			(island_removal_mode 0)
		)
		(polygon
			(pts
				(arc
					(start 33.445196 -286.832548)
					(mid 33.441476 -286.841528)
					(end 33.432496 -286.845248)
				)
				(arc
					(start 31.959296 -286.845248)
					(mid 31.950316 -286.841528)
					(end 31.946596 -286.832548)
				)
				(arc
					(start 31.946596 -286.33801)
					(mid 31.950316 -286.32903)
					(end 31.959296 -286.32531)
				)
				(arc
					(start 33.432496 -286.32531)
					(mid 33.441476 -286.32903)
					(end 33.445196 -286.33801)
				)
			)
		)
	)
	(zone
		(layer "In1.Cu")
		(hatch none 0.5)
		(connect_pads
			(clearance 0)
		)
		(min_thickness 0.25)
		(keepout
			(tracks not_allowed)
			(vias allowed)
			(pads allowed)
			(copperpour not_allowed)
			(footprints allowed)
		)
		(placement
			(enabled no)
			(sheetname "")
		)
		(fill
			(thermal_gap 0.5)
			(thermal_bridge_width 0.5)
			(island_removal_mode 0)
		)
		(polygon
			(pts
				(arc
					(start 266.29741 -209.482182)
					(mid 266.29369 -209.491162)
					(end 266.28471 -209.494882)
				)
				(arc
					(start 264.81151 -209.494882)
					(mid 264.80253 -209.491162)
					(end 264.79881 -209.482182)
				)
				(arc
					(start 264.79881 -208.987644)
					(mid 264.80253 -208.978664)
					(end 264.81151 -208.974944)
				)
				(arc
					(start 266.28471 -208.974944)
					(mid 266.29369 -208.978664)
					(end 266.29741 -208.987644)
				)
			)
		)
	)
	(zone
		(layer "In1.Cu")
		(hatch none 0.5)
		(connect_pads
			(clearance 0)
		)
		(min_thickness 0.25)
		(keepout
			(tracks not_allowed)
			(vias allowed)
			(pads allowed)
			(copperpour not_allowed)
			(footprints allowed)
		)
		(placement
			(enabled no)
			(sheetname "")
		)
		(fill
			(thermal_gap 0.5)
			(thermal_bridge_width 0.5)
			(island_removal_mode 0)
		)
		(polygon
			(pts
				(arc
					(start 33.445196 -297.882564)
					(mid 33.441476 -297.891544)
					(end 33.432496 -297.895264)
				)
				(arc
					(start 31.959296 -297.895264)
					(mid 31.950316 -297.891544)
					(end 31.946596 -297.882564)
				)
				(arc
					(start 31.946596 -297.388026)
					(mid 31.950316 -297.379046)
					(end 31.959296 -297.375326)
				)
				(arc
					(start 33.432496 -297.375326)
					(mid 33.441476 -297.379046)
					(end 33.445196 -297.388026)
				)
			)
		)
	)
	(zone
		(layer "In1.Cu")
		(hatch none 0.5)
		(connect_pads
			(clearance 0)
		)
		(min_thickness 0.25)
		(keepout
			(tracks not_allowed)
			(vias allowed)
			(pads allowed)
			(copperpour not_allowed)
			(footprints allowed)
		)
		(placement
			(enabled no)
			(sheetname "")
		)
		(fill
			(thermal_gap 0.5)
			(thermal_bridge_width 0.5)
			(island_removal_mode 0)
		)
		(polygon
			(pts
				(arc
					(start 160.398206 -390.761474)
					(mid 160.093406 -390.761474)
					(end 160.398206 -390.761474)
				)
			)
		)
	)
	(zone
		(layer "In1.Cu")
		(hatch none 0.5)
		(connect_pads
			(clearance 0)
		)
		(min_thickness 0.25)
		(keepout
			(tracks not_allowed)
			(vias allowed)
			(pads allowed)
			(copperpour not_allowed)
			(footprints allowed)
		)
		(placement
			(enabled no)
			(sheetname "")
		)
		(fill
			(thermal_gap 0.5)
			(thermal_bridge_width 0.5)
			(island_removal_mode 0)
		)
		(polygon
			(pts
				(arc
					(start 172.72127 -246.882412)
					(mid 172.71755 -246.891392)
					(end 172.70857 -246.895112)
				)
				(arc
					(start 171.23537 -246.895112)
					(mid 171.22639 -246.891392)
					(end 171.22267 -246.882412)
				)
				(arc
					(start 171.22267 -246.387874)
					(mid 171.22639 -246.378894)
					(end 171.23537 -246.375174)
				)
				(arc
					(start 172.70857 -246.375174)
					(mid 172.71755 -246.378894)
					(end 172.72127 -246.387874)
				)
			)
		)
	)
	(zone
		(layer "In1.Cu")
		(hatch none 0.5)
		(connect_pads
			(clearance 0)
		)
		(min_thickness 0.25)
		(keepout
			(tracks not_allowed)
			(vias allowed)
			(pads allowed)
			(copperpour not_allowed)
			(footprints allowed)
		)
		(placement
			(enabled no)
			(sheetname "")
		)
		(fill
			(thermal_gap 0.5)
			(thermal_bridge_width 0.5)
			(island_removal_mode 0)
		)
		(polygon
			(pts
				(arc
					(start 432.30546 -208.632298)
					(mid 432.30174 -208.641278)
					(end 432.29276 -208.644998)
				)
				(arc
					(start 430.81956 -208.644998)
					(mid 430.81058 -208.641278)
					(end 430.80686 -208.632298)
				)
				(arc
					(start 430.80686 -208.13776)
					(mid 430.81058 -208.12878)
					(end 430.81956 -208.12506)
				)
				(arc
					(start 432.29276 -208.12506)
					(mid 432.30174 -208.12878)
					(end 432.30546 -208.13776)
				)
			)
		)
	)
	(zone
		(layer "In1.Cu")
		(hatch none 0.5)
		(connect_pads
			(clearance 0)
		)
		(min_thickness 0.25)
		(keepout
			(tracks not_allowed)
			(vias allowed)
			(pads allowed)
			(copperpour not_allowed)
			(footprints allowed)
		)
		(placement
			(enabled no)
			(sheetname "")
		)
		(fill
			(thermal_gap 0.5)
			(thermal_bridge_width 0.5)
			(island_removal_mode 0)
		)
		(polygon
			(pts
				(arc
					(start 420.661338 -302.982122)
					(mid 420.657618 -302.991102)
					(end 420.648638 -302.994822)
				)
				(arc
					(start 419.175438 -302.994822)
					(mid 419.166458 -302.991102)
					(end 419.162738 -302.982122)
				)
				(arc
					(start 419.162738 -302.487584)
					(mid 419.166458 -302.478604)
					(end 419.175438 -302.474884)
				)
				(arc
					(start 420.648638 -302.474884)
					(mid 420.657618 -302.478604)
					(end 420.661338 -302.487584)
				)
			)
		)
	)
	(zone
		(layer "In1.Cu")
		(hatch none 0.5)
		(connect_pads
			(clearance 0)
		)
		(min_thickness 0.25)
		(keepout
			(tracks not_allowed)
			(vias allowed)
			(pads allowed)
			(copperpour not_allowed)
			(footprints allowed)
		)
		(placement
			(enabled no)
			(sheetname "")
		)
		(fill
			(thermal_gap 0.5)
			(thermal_bridge_width 0.5)
			(island_removal_mode 0)
		)
		(polygon
			(pts
				(arc
					(start 443.2935 -207.78216)
					(mid 443.28978 -207.79114)
					(end 443.2808 -207.79486)
				)
				(arc
					(start 441.8076 -207.79486)
					(mid 441.79862 -207.79114)
					(end 441.7949 -207.78216)
				)
				(arc
					(start 441.7949 -207.287622)
					(mid 441.79862 -207.278642)
					(end 441.8076 -207.274922)
				)
				(arc
					(start 443.2808 -207.274922)
					(mid 443.28978 -207.278642)
					(end 443.2935 -207.287622)
				)
			)
		)
	)
	(zone
		(layer "In1.Cu")
		(hatch none 0.5)
		(connect_pads
			(clearance 0)
		)
		(min_thickness 0.25)
		(keepout
			(tracks not_allowed)
			(vias allowed)
			(pads allowed)
			(copperpour not_allowed)
			(footprints allowed)
		)
		(placement
			(enabled no)
			(sheetname "")
		)
		(fill
			(thermal_gap 0.5)
			(thermal_bridge_width 0.5)
			(island_removal_mode 0)
		)
		(polygon
			(pts
				(arc
					(start 266.29741 -240.082324)
					(mid 266.29369 -240.091304)
					(end 266.28471 -240.095024)
				)
				(arc
					(start 264.81151 -240.095024)
					(mid 264.80253 -240.091304)
					(end 264.79881 -240.082324)
				)
				(arc
					(start 264.79881 -239.587786)
					(mid 264.80253 -239.578806)
					(end 264.81151 -239.575086)
				)
				(arc
					(start 266.28471 -239.575086)
					(mid 266.29369 -239.578806)
					(end 266.29741 -239.587786)
				)
			)
		)
	)
	(zone
		(layer "In1.Cu")
		(hatch none 0.5)
		(connect_pads
			(clearance 0)
		)
		(min_thickness 0.25)
		(keepout
			(tracks not_allowed)
			(vias allowed)
			(pads allowed)
			(copperpour not_allowed)
			(footprints allowed)
		)
		(placement
			(enabled no)
			(sheetname "")
		)
		(fill
			(thermal_gap 0.5)
			(thermal_bridge_width 0.5)
			(island_removal_mode 0)
		)
		(polygon
			(pts
				(arc
					(start 378.161042 -397.849344)
					(mid 377.780042 -397.849344)
					(end 378.161042 -397.849344)
				)
			)
		)
	)
	(zone
		(layer "In1.Cu")
		(hatch none 0.5)
		(connect_pads
			(clearance 0)
		)
		(min_thickness 0.25)
		(keepout
			(tracks not_allowed)
			(vias allowed)
			(pads allowed)
			(copperpour not_allowed)
			(footprints allowed)
		)
		(placement
			(enabled no)
			(sheetname "")
		)
		(fill
			(thermal_gap 0.5)
			(thermal_bridge_width 0.5)
			(island_removal_mode 0)
		)
		(polygon
			(pts
				(arc
					(start 273.841464 -308.932326)
					(mid 273.837744 -308.941306)
					(end 273.828764 -308.945026)
				)
				(arc
					(start 272.355564 -308.945026)
					(mid 272.346584 -308.941306)
					(end 272.342864 -308.932326)
				)
				(arc
					(start 272.342864 -308.437788)
					(mid 272.346584 -308.428808)
					(end 272.355564 -308.425088)
				)
				(arc
					(start 273.828764 -308.425088)
					(mid 273.837744 -308.428808)
					(end 273.841464 -308.437788)
				)
			)
		)
	)
	(zone
		(layer "In1.Cu")
		(hatch none 0.5)
		(connect_pads
			(clearance 0)
		)
		(min_thickness 0.25)
		(keepout
			(tracks not_allowed)
			(vias allowed)
			(pads allowed)
			(copperpour not_allowed)
			(footprints allowed)
		)
		(placement
			(enabled no)
			(sheetname "")
		)
		(fill
			(thermal_gap 0.5)
			(thermal_bridge_width 0.5)
			(island_removal_mode 0)
		)
		(polygon
			(pts
				(arc
					(start 432.30546 -231.582214)
					(mid 432.30174 -231.591194)
					(end 432.29276 -231.594914)
				)
				(arc
					(start 430.81956 -231.594914)
					(mid 430.81058 -231.591194)
					(end 430.80686 -231.582214)
				)
				(arc
					(start 430.80686 -231.087676)
					(mid 430.81058 -231.078696)
					(end 430.81956 -231.074976)
				)
				(arc
					(start 432.29276 -231.074976)
					(mid 432.30174 -231.078696)
					(end 432.30546 -231.087676)
				)
			)
		)
	)
	(zone
		(layer "In1.Cu")
		(hatch none 0.5)
		(connect_pads
			(clearance 0)
		)
		(min_thickness 0.25)
		(keepout
			(tracks not_allowed)
			(vias allowed)
			(pads allowed)
			(copperpour not_allowed)
			(footprints allowed)
		)
		(placement
			(enabled no)
			(sheetname "")
		)
		(fill
			(thermal_gap 0.5)
			(thermal_bridge_width 0.5)
			(island_removal_mode 0)
		)
		(polygon
			(pts
				(arc
					(start 195.353432 -251.982478)
					(mid 195.349712 -251.991458)
					(end 195.340732 -251.995178)
				)
				(arc
					(start 193.867532 -251.995178)
					(mid 193.858552 -251.991458)
					(end 193.854832 -251.982478)
				)
				(arc
					(start 193.854832 -251.48794)
					(mid 193.858552 -251.47896)
					(end 193.867532 -251.47524)
				)
				(arc
					(start 195.340732 -251.47524)
					(mid 195.349712 -251.47896)
					(end 195.353432 -251.48794)
				)
			)
		)
	)
	(zone
		(layer "In1.Cu")
		(hatch none 0.5)
		(connect_pads
			(clearance 0)
		)
		(min_thickness 0.25)
		(keepout
			(tracks not_allowed)
			(vias allowed)
			(pads allowed)
			(copperpour not_allowed)
			(footprints allowed)
		)
		(placement
			(enabled no)
			(sheetname "")
		)
		(fill
			(thermal_gap 0.5)
			(thermal_bridge_width 0.5)
			(island_removal_mode 0)
		)
		(polygon
			(pts
				(arc
					(start 347.98889 -393.69238)
					(mid 347.60789 -393.69238)
					(end 347.98889 -393.69238)
				)
			)
		)
	)
	(zone
		(layer "In1.Cu")
		(hatch none 0.5)
		(connect_pads
			(clearance 0)
		)
		(min_thickness 0.25)
		(keepout
			(tracks not_allowed)
			(vias allowed)
			(pads allowed)
			(copperpour not_allowed)
			(footprints allowed)
		)
		(placement
			(enabled no)
			(sheetname "")
		)
		(fill
			(thermal_gap 0.5)
			(thermal_bridge_width 0.5)
			(island_removal_mode 0)
		)
		(polygon
			(pts
				(arc
					(start 30.001464 -266.432538)
					(mid 29.997744 -266.441518)
					(end 29.988764 -266.445238)
				)
				(arc
					(start 28.515564 -266.445238)
					(mid 28.506584 -266.441518)
					(end 28.502864 -266.432538)
				)
				(arc
					(start 28.502864 -265.938)
					(mid 28.506584 -265.92902)
					(end 28.515564 -265.9253)
				)
				(arc
					(start 29.988764 -265.9253)
					(mid 29.997744 -265.92902)
					(end 30.001464 -265.938)
				)
			)
		)
	)
	(zone
		(layer "In1.Cu")
		(hatch none 0.5)
		(connect_pads
			(clearance 0)
		)
		(min_thickness 0.25)
		(keepout
			(tracks not_allowed)
			(vias allowed)
			(pads allowed)
			(copperpour not_allowed)
			(footprints allowed)
		)
		(placement
			(enabled no)
			(sheetname "")
		)
		(fill
			(thermal_gap 0.5)
			(thermal_bridge_width 0.5)
			(island_removal_mode 0)
		)
		(polygon
			(pts
				(arc
					(start 349.588582 -397.849344)
					(mid 349.207582 -397.849344)
					(end 349.588582 -397.849344)
				)
			)
		)
	)
	(zone
		(layer "In1.Cu")
		(hatch none 0.5)
		(connect_pads
			(clearance 0)
		)
		(min_thickness 0.25)
		(keepout
			(tracks not_allowed)
			(vias allowed)
			(pads allowed)
			(copperpour not_allowed)
			(footprints allowed)
		)
		(placement
			(enabled no)
			(sheetname "")
		)
		(fill
			(thermal_gap 0.5)
			(thermal_bridge_width 0.5)
			(island_removal_mode 0)
		)
		(polygon
			(pts
				(arc
					(start 172.72127 -276.632416)
					(mid 172.71755 -276.641396)
					(end 172.70857 -276.645116)
				)
				(arc
					(start 171.23537 -276.645116)
					(mid 171.22639 -276.641396)
					(end 171.22267 -276.632416)
				)
				(arc
					(start 171.22267 -276.137878)
					(mid 171.22639 -276.128898)
					(end 171.23537 -276.125178)
				)
				(arc
					(start 172.70857 -276.125178)
					(mid 172.71755 -276.128898)
					(end 172.72127 -276.137878)
				)
			)
		)
	)
	(zone
		(layer "In1.Cu")
		(hatch none 0.5)
		(connect_pads
			(clearance 0)
		)
		(min_thickness 0.25)
		(keepout
			(tracks not_allowed)
			(vias allowed)
			(pads allowed)
			(copperpour not_allowed)
			(footprints allowed)
		)
		(placement
			(enabled no)
			(sheetname "")
		)
		(fill
			(thermal_gap 0.5)
			(thermal_bridge_width 0.5)
			(island_removal_mode 0)
		)
		(polygon
			(pts
				(arc
					(start 52.633372 -229.882446)
					(mid 52.629652 -229.891426)
					(end 52.620672 -229.895146)
				)
				(arc
					(start 51.147472 -229.895146)
					(mid 51.138492 -229.891426)
					(end 51.134772 -229.882446)
				)
				(arc
					(start 51.134772 -229.387908)
					(mid 51.138492 -229.378928)
					(end 51.147472 -229.375208)
				)
				(arc
					(start 52.620672 -229.375208)
					(mid 52.629652 -229.378928)
					(end 52.633372 -229.387908)
				)
			)
		)
	)
	(zone
		(layer "In1.Cu")
		(hatch none 0.5)
		(connect_pads
			(clearance 0)
		)
		(min_thickness 0.25)
		(keepout
			(tracks not_allowed)
			(vias allowed)
			(pads allowed)
			(copperpour not_allowed)
			(footprints allowed)
		)
		(placement
			(enabled no)
			(sheetname "")
		)
		(fill
			(thermal_gap 0.5)
			(thermal_bridge_width 0.5)
			(island_removal_mode 0)
		)
		(polygon
			(pts
				(arc
					(start 206.5782 -306.135278)
					(mid 205.9178 -306.135278)
					(end 206.5782 -306.135278)
				)
			)
		)
	)
	(zone
		(layer "In1.Cu")
		(hatch none 0.5)
		(connect_pads
			(clearance 0)
		)
		(min_thickness 0.25)
		(keepout
			(tracks not_allowed)
			(vias allowed)
			(pads allowed)
			(copperpour not_allowed)
			(footprints allowed)
		)
		(placement
			(enabled no)
			(sheetname "")
		)
		(fill
			(thermal_gap 0.5)
			(thermal_bridge_width 0.5)
			(island_removal_mode 0)
		)
		(polygon
			(pts
				(arc
					(start 353.188524 -397.849344)
					(mid 352.807524 -397.849344)
					(end 353.188524 -397.849344)
				)
			)
		)
	)
	(zone
		(layer "In1.Cu")
		(hatch none 0.5)
		(connect_pads
			(clearance 0)
		)
		(min_thickness 0.25)
		(keepout
			(tracks not_allowed)
			(vias allowed)
			(pads allowed)
			(copperpour not_allowed)
			(footprints allowed)
		)
		(placement
			(enabled no)
			(sheetname "")
		)
		(fill
			(thermal_gap 0.5)
			(thermal_bridge_width 0.5)
			(island_removal_mode 0)
		)
		(polygon
			(pts
				(arc
					(start 117.070378 -390.761474)
					(mid 116.765578 -390.761474)
					(end 117.070378 -390.761474)
				)
			)
		)
	)
	(zone
		(layer "In1.Cu")
		(hatch none 0.5)
		(connect_pads
			(clearance 0)
		)
		(min_thickness 0.25)
		(keepout
			(tracks not_allowed)
			(vias allowed)
			(pads allowed)
			(copperpour not_allowed)
			(footprints allowed)
		)
		(placement
			(enabled no)
			(sheetname "")
		)
		(fill
			(thermal_gap 0.5)
			(thermal_bridge_width 0.5)
			(island_removal_mode 0)
		)
		(polygon
			(pts
				(arc
					(start 265.87831 -308.685184)
					(mid 265.21791 -308.685184)
					(end 265.87831 -308.685184)
				)
			)
		)
	)
	(zone
		(layer "In1.Cu")
		(hatch none 0.5)
		(connect_pads
			(clearance 0)
		)
		(min_thickness 0.25)
		(keepout
			(tracks not_allowed)
			(vias allowed)
			(pads allowed)
			(copperpour not_allowed)
			(footprints allowed)
		)
		(placement
			(enabled no)
			(sheetname "")
		)
		(fill
			(thermal_gap 0.5)
			(thermal_bridge_width 0.5)
			(island_removal_mode 0)
		)
		(polygon
			(pts
				(arc
					(start 439.849514 -214.582248)
					(mid 439.845794 -214.591228)
					(end 439.836814 -214.594948)
				)
				(arc
					(start 438.363614 -214.594948)
					(mid 438.354634 -214.591228)
					(end 438.350914 -214.582248)
				)
				(arc
					(start 438.350914 -214.08771)
					(mid 438.354634 -214.07873)
					(end 438.363614 -214.07501)
				)
				(arc
					(start 439.836814 -214.07501)
					(mid 439.845794 -214.07873)
					(end 439.849514 -214.08771)
				)
			)
		)
	)
	(zone
		(layer "In1.Cu")
		(hatch none 0.5)
		(connect_pads
			(clearance 0)
		)
		(min_thickness 0.25)
		(keepout
			(tracks not_allowed)
			(vias allowed)
			(pads allowed)
			(copperpour not_allowed)
			(footprints allowed)
		)
		(placement
			(enabled no)
			(sheetname "")
		)
		(fill
			(thermal_gap 0.5)
			(thermal_bridge_width 0.5)
			(island_removal_mode 0)
		)
		(polygon
			(pts
				(arc
					(start 443.2935 -290.232338)
					(mid 443.28978 -290.241318)
					(end 443.2808 -290.245038)
				)
				(arc
					(start 441.8076 -290.245038)
					(mid 441.79862 -290.241318)
					(end 441.7949 -290.232338)
				)
				(arc
					(start 441.7949 -289.7378)
					(mid 441.79862 -289.72882)
					(end 441.8076 -289.7251)
				)
				(arc
					(start 443.2808 -289.7251)
					(mid 443.28978 -289.72882)
					(end 443.2935 -289.7378)
				)
			)
		)
	)
	(zone
		(layer "In1.Cu")
		(hatch none 0.5)
		(connect_pads
			(clearance 0)
		)
		(min_thickness 0.25)
		(keepout
			(tracks not_allowed)
			(vias allowed)
			(pads allowed)
			(copperpour not_allowed)
			(footprints allowed)
		)
		(placement
			(enabled no)
			(sheetname "")
		)
		(fill
			(thermal_gap 0.5)
			(thermal_bridge_width 0.5)
			(island_removal_mode 0)
		)
		(polygon
			(pts
				(arc
					(start 60.177426 -302.132492)
					(mid 60.173706 -302.141472)
					(end 60.164726 -302.145192)
				)
				(arc
					(start 58.691526 -302.145192)
					(mid 58.682546 -302.141472)
					(end 58.678826 -302.132492)
				)
				(arc
					(start 58.678826 -301.637954)
					(mid 58.682546 -301.628974)
					(end 58.691526 -301.625254)
				)
				(arc
					(start 60.164726 -301.625254)
					(mid 60.173706 -301.628974)
					(end 60.177426 -301.637954)
				)
			)
		)
	)
	(zone
		(layer "In1.Cu")
		(hatch none 0.5)
		(connect_pads
			(clearance 0)
		)
		(min_thickness 0.25)
		(keepout
			(tracks not_allowed)
			(vias allowed)
			(pads allowed)
			(copperpour not_allowed)
			(footprints allowed)
		)
		(placement
			(enabled no)
			(sheetname "")
		)
		(fill
			(thermal_gap 0.5)
			(thermal_bridge_width 0.5)
			(island_removal_mode 0)
		)
		(polygon
			(pts
				(arc
					(start 417.217352 -289.3822)
					(mid 417.213632 -289.39118)
					(end 417.204652 -289.3949)
				)
				(arc
					(start 415.731452 -289.3949)
					(mid 415.722472 -289.39118)
					(end 415.718752 -289.3822)
				)
				(arc
					(start 415.718752 -288.887662)
					(mid 415.722472 -288.878682)
					(end 415.731452 -288.874962)
				)
				(arc
					(start 417.204652 -288.874962)
					(mid 417.213632 -288.878682)
					(end 417.217352 -288.887662)
				)
			)
		)
	)
	(zone
		(layer "In1.Cu")
		(hatch none 0.5)
		(connect_pads
			(clearance 0)
		)
		(min_thickness 0.25)
		(keepout
			(tracks not_allowed)
			(vias allowed)
			(pads allowed)
			(copperpour not_allowed)
			(footprints allowed)
		)
		(placement
			(enabled no)
			(sheetname "")
		)
		(fill
			(thermal_gap 0.5)
			(thermal_bridge_width 0.5)
			(island_removal_mode 0)
		)
		(polygon
			(pts
				(arc
					(start 342.097868 -392.30427)
					(mid 341.793068 -392.30427)
					(end 342.097868 -392.30427)
				)
			)
		)
	)
	(zone
		(layer "In1.Cu")
		(hatch none 0.5)
		(connect_pads
			(clearance 0)
		)
		(min_thickness 0.25)
		(keepout
			(tracks not_allowed)
			(vias allowed)
			(pads allowed)
			(copperpour not_allowed)
			(footprints allowed)
		)
		(placement
			(enabled no)
			(sheetname "")
		)
		(fill
			(thermal_gap 0.5)
			(thermal_bridge_width 0.5)
			(island_removal_mode 0)
		)
		(polygon
			(pts
				(arc
					(start 206.5782 -301.88535)
					(mid 205.9178 -301.88535)
					(end 206.5782 -301.88535)
				)
			)
		)
	)
	(zone
		(layer "In1.Cu")
		(hatch none 0.5)
		(connect_pads
			(clearance 0)
		)
		(min_thickness 0.25)
		(keepout
			(tracks not_allowed)
			(vias allowed)
			(pads allowed)
			(copperpour not_allowed)
			(footprints allowed)
		)
		(placement
			(enabled no)
			(sheetname "")
		)
		(fill
			(thermal_gap 0.5)
			(thermal_bridge_width 0.5)
			(island_removal_mode 0)
		)
		(polygon
			(pts
				(arc
					(start 155.01874 -391.319258)
					(mid 155.14574 -391.446258)
					(end 155.27274 -391.319258)
				)
				(arc
					(start 155.27274 -391.243058)
					(mid 155.14574 -391.116058)
					(end 155.01874 -391.243058)
				)
			)
		)
	)
	(zone
		(layer "In1.Cu")
		(hatch none 0.5)
		(connect_pads
			(clearance 0)
		)
		(min_thickness 0.25)
		(keepout
			(tracks not_allowed)
			(vias allowed)
			(pads allowed)
			(copperpour not_allowed)
			(footprints allowed)
		)
		(placement
			(enabled no)
			(sheetname "")
		)
		(fill
			(thermal_gap 0.5)
			(thermal_bridge_width 0.5)
			(island_removal_mode 0)
		)
		(polygon
			(pts
				(arc
					(start 33.445196 -217.132408)
					(mid 33.441476 -217.141388)
					(end 33.432496 -217.145108)
				)
				(arc
					(start 31.959296 -217.145108)
					(mid 31.950316 -217.141388)
					(end 31.946596 -217.132408)
				)
				(arc
					(start 31.946596 -216.63787)
					(mid 31.950316 -216.62889)
					(end 31.959296 -216.62517)
				)
				(arc
					(start 33.432496 -216.62517)
					(mid 33.441476 -216.62889)
					(end 33.445196 -216.63787)
				)
			)
		)
	)
	(zone
		(layer "In1.Cu")
		(hatch none 0.5)
		(connect_pads
			(clearance 0)
		)
		(min_thickness 0.25)
		(keepout
			(tracks not_allowed)
			(vias allowed)
			(pads allowed)
			(copperpour not_allowed)
			(footprints allowed)
		)
		(placement
			(enabled no)
			(sheetname "")
		)
		(fill
			(thermal_gap 0.5)
			(thermal_bridge_width 0.5)
			(island_removal_mode 0)
		)
		(polygon
			(pts
				(arc
					(start 22.45741 -212.88248)
					(mid 22.45369 -212.89146)
					(end 22.44471 -212.89518)
				)
				(arc
					(start 20.97151 -212.89518)
					(mid 20.96253 -212.89146)
					(end 20.95881 -212.88248)
				)
				(arc
					(start 20.95881 -212.387942)
					(mid 20.96253 -212.378962)
					(end 20.97151 -212.375242)
				)
				(arc
					(start 22.44471 -212.375242)
					(mid 22.45369 -212.378962)
					(end 22.45741 -212.387942)
				)
			)
		)
	)
	(zone
		(layer "In1.Cu")
		(hatch none 0.5)
		(connect_pads
			(clearance 0)
		)
		(min_thickness 0.25)
		(keepout
			(tracks not_allowed)
			(vias allowed)
			(pads allowed)
			(copperpour not_allowed)
			(footprints allowed)
		)
		(placement
			(enabled no)
			(sheetname "")
		)
		(fill
			(thermal_gap 0.5)
			(thermal_bridge_width 0.5)
			(island_removal_mode 0)
		)
		(polygon
			(pts
				(arc
					(start 428.205392 -250.282202)
					(mid 428.201672 -250.291182)
					(end 428.192692 -250.294902)
				)
				(arc
					(start 426.719492 -250.294902)
					(mid 426.710512 -250.291182)
					(end 426.706792 -250.282202)
				)
				(arc
					(start 426.706792 -249.787664)
					(mid 426.710512 -249.778684)
					(end 426.719492 -249.774964)
				)
				(arc
					(start 428.192692 -249.774964)
					(mid 428.201672 -249.778684)
					(end 428.205392 -249.787664)
				)
			)
		)
	)
	(zone
		(layer "In1.Cu")
		(hatch none 0.5)
		(connect_pads
			(clearance 0)
		)
		(min_thickness 0.25)
		(keepout
			(tracks not_allowed)
			(vias allowed)
			(pads allowed)
			(copperpour not_allowed)
			(footprints allowed)
		)
		(placement
			(enabled no)
			(sheetname "")
		)
		(fill
			(thermal_gap 0.5)
			(thermal_bridge_width 0.5)
			(island_removal_mode 0)
		)
		(polygon
			(pts
				(arc
					(start 270.397478 -231.582214)
					(mid 270.393758 -231.591194)
					(end 270.384778 -231.594914)
				)
				(arc
					(start 268.911578 -231.594914)
					(mid 268.902598 -231.591194)
					(end 268.898878 -231.582214)
				)
				(arc
					(start 268.898878 -231.087676)
					(mid 268.902598 -231.078696)
					(end 268.911578 -231.074976)
				)
				(arc
					(start 270.384778 -231.074976)
					(mid 270.393758 -231.078696)
					(end 270.397478 -231.087676)
				)
			)
		)
	)
	(zone
		(layer "In1.Cu")
		(hatch none 0.5)
		(connect_pads
			(clearance 0)
		)
		(min_thickness 0.25)
		(keepout
			(tracks not_allowed)
			(vias allowed)
			(pads allowed)
			(copperpour not_allowed)
			(footprints allowed)
		)
		(placement
			(enabled no)
			(sheetname "")
		)
		(fill
			(thermal_gap 0.5)
			(thermal_bridge_width 0.5)
			(island_removal_mode 0)
		)
		(polygon
			(pts
				(arc
					(start 18.357342 -198.43242)
					(mid 18.353622 -198.4414)
					(end 18.344642 -198.44512)
				)
				(arc
					(start 16.871442 -198.44512)
					(mid 16.862462 -198.4414)
					(end 16.858742 -198.43242)
				)
				(arc
					(start 16.858742 -197.937882)
					(mid 16.862462 -197.928902)
					(end 16.871442 -197.925182)
				)
				(arc
					(start 18.344642 -197.925182)
					(mid 18.353622 -197.928902)
					(end 18.357342 -197.937882)
				)
			)
		)
	)
	(zone
		(layer "In1.Cu")
		(hatch none 0.5)
		(connect_pads
			(clearance 0)
		)
		(min_thickness 0.25)
		(keepout
			(tracks not_allowed)
			(vias allowed)
			(pads allowed)
			(copperpour not_allowed)
			(footprints allowed)
		)
		(placement
			(enabled no)
			(sheetname "")
		)
		(fill
			(thermal_gap 0.5)
			(thermal_bridge_width 0.5)
			(island_removal_mode 0)
		)
		(polygon
			(pts
				(arc
					(start 443.2935 -220.532198)
					(mid 443.28978 -220.541178)
					(end 443.2808 -220.544898)
				)
				(arc
					(start 441.8076 -220.544898)
					(mid 441.79862 -220.541178)
					(end 441.7949 -220.532198)
				)
				(arc
					(start 441.7949 -220.03766)
					(mid 441.79862 -220.02868)
					(end 441.8076 -220.02496)
				)
				(arc
					(start 443.2808 -220.02496)
					(mid 443.28978 -220.02868)
					(end 443.2935 -220.03766)
				)
			)
		)
	)
	(zone
		(layer "In1.Cu")
		(hatch none 0.5)
		(connect_pads
			(clearance 0)
		)
		(min_thickness 0.25)
		(keepout
			(tracks not_allowed)
			(vias allowed)
			(pads allowed)
			(copperpour not_allowed)
			(footprints allowed)
		)
		(placement
			(enabled no)
			(sheetname "")
		)
		(fill
			(thermal_gap 0.5)
			(thermal_bridge_width 0.5)
			(island_removal_mode 0)
		)
		(polygon
			(pts
				(arc
					(start 22.45741 -205.232508)
					(mid 22.45369 -205.241488)
					(end 22.44471 -205.245208)
				)
				(arc
					(start 20.97151 -205.245208)
					(mid 20.96253 -205.241488)
					(end 20.95881 -205.232508)
				)
				(arc
					(start 20.95881 -204.73797)
					(mid 20.96253 -204.72899)
					(end 20.97151 -204.72527)
				)
				(arc
					(start 22.44471 -204.72527)
					(mid 22.45369 -204.72899)
					(end 22.45741 -204.73797)
				)
			)
		)
	)
	(zone
		(layer "In1.Cu")
		(hatch none 0.5)
		(connect_pads
			(clearance 0)
		)
		(min_thickness 0.25)
		(keepout
			(tracks not_allowed)
			(vias allowed)
			(pads allowed)
			(copperpour not_allowed)
			(footprints allowed)
		)
		(placement
			(enabled no)
			(sheetname "")
		)
		(fill
			(thermal_gap 0.5)
			(thermal_bridge_width 0.5)
			(island_removal_mode 0)
		)
		(polygon
			(pts
				(arc
					(start 413.117284 -207.78216)
					(mid 413.113564 -207.79114)
					(end 413.104584 -207.79486)
				)
				(arc
					(start 411.631384 -207.79486)
					(mid 411.622404 -207.79114)
					(end 411.618684 -207.78216)
				)
				(arc
					(start 411.618684 -207.287622)
					(mid 411.622404 -207.278642)
					(end 411.631384 -207.274922)
				)
				(arc
					(start 413.104584 -207.274922)
					(mid 413.113564 -207.278642)
					(end 413.117284 -207.287622)
				)
			)
		)
	)
	(zone
		(layer "In1.Cu")
		(hatch none 0.5)
		(connect_pads
			(clearance 0)
		)
		(min_thickness 0.25)
		(keepout
			(tracks not_allowed)
			(vias allowed)
			(pads allowed)
			(copperpour not_allowed)
			(footprints allowed)
		)
		(placement
			(enabled no)
			(sheetname "")
		)
		(fill
			(thermal_gap 0.5)
			(thermal_bridge_width 0.5)
			(island_removal_mode 0)
		)
		(polygon
			(pts
				(arc
					(start 270.397478 -200.982326)
					(mid 270.393758 -200.991306)
					(end 270.384778 -200.995026)
				)
				(arc
					(start 268.911578 -200.995026)
					(mid 268.902598 -200.991306)
					(end 268.898878 -200.982326)
				)
				(arc
					(start 268.898878 -200.487788)
					(mid 268.902598 -200.478808)
					(end 268.911578 -200.475088)
				)
				(arc
					(start 270.384778 -200.475088)
					(mid 270.393758 -200.478808)
					(end 270.397478 -200.487788)
				)
			)
		)
	)
	(zone
		(layer "In1.Cu")
		(hatch none 0.5)
		(connect_pads
			(clearance 0)
		)
		(min_thickness 0.25)
		(keepout
			(tracks not_allowed)
			(vias allowed)
			(pads allowed)
			(copperpour not_allowed)
			(footprints allowed)
		)
		(placement
			(enabled no)
			(sheetname "")
		)
		(fill
			(thermal_gap 0.5)
			(thermal_bridge_width 0.5)
			(island_removal_mode 0)
		)
		(polygon
			(pts
				(arc
					(start 365.939578 -5.628386)
					(mid 365.91726 -5.682268)
					(end 365.863378 -5.704586)
				)
				(arc
					(start 365.251238 -5.704586)
					(mid 365.197356 -5.682268)
					(end 365.175038 -5.628386)
				)
				(arc
					(start 365.175038 -4.531106)
					(mid 365.197356 -4.477224)
					(end 365.251238 -4.454906)
				)
				(arc
					(start 365.863378 -4.454906)
					(mid 365.91726 -4.477224)
					(end 365.939578 -4.531106)
				)
			)
		)
	)
	(zone
		(layer "In1.Cu")
		(hatch none 0.5)
		(connect_pads
			(clearance 0)
		)
		(min_thickness 0.25)
		(keepout
			(tracks not_allowed)
			(vias allowed)
			(pads allowed)
			(copperpour not_allowed)
			(footprints allowed)
		)
		(placement
			(enabled no)
			(sheetname "")
		)
		(fill
			(thermal_gap 0.5)
			(thermal_bridge_width 0.5)
			(island_removal_mode 0)
		)
		(polygon
			(pts
				(arc
					(start 447.393568 -269.832328)
					(mid 447.389848 -269.841308)
					(end 447.380868 -269.845028)
				)
				(arc
					(start 445.907668 -269.845028)
					(mid 445.898688 -269.841308)
					(end 445.894968 -269.832328)
				)
				(arc
					(start 445.894968 -269.33779)
					(mid 445.898688 -269.32881)
					(end 445.907668 -269.32509)
				)
				(arc
					(start 447.380868 -269.32509)
					(mid 447.389848 -269.32881)
					(end 447.393568 -269.33779)
				)
			)
		)
	)
	(zone
		(layer "In1.Cu")
		(hatch none 0.5)
		(connect_pads
			(clearance 0)
		)
		(min_thickness 0.25)
		(keepout
			(tracks not_allowed)
			(vias allowed)
			(pads allowed)
			(copperpour not_allowed)
			(footprints allowed)
		)
		(placement
			(enabled no)
			(sheetname "")
		)
		(fill
			(thermal_gap 0.5)
			(thermal_bridge_width 0.5)
			(island_removal_mode 0)
		)
		(polygon
			(pts
				(arc
					(start 169.277284 -280.03246)
					(mid 169.273564 -280.04144)
					(end 169.264584 -280.04516)
				)
				(arc
					(start 167.791384 -280.04516)
					(mid 167.782404 -280.04144)
					(end 167.778684 -280.03246)
				)
				(arc
					(start 167.778684 -279.537922)
					(mid 167.782404 -279.528942)
					(end 167.791384 -279.525222)
				)
				(arc
					(start 169.264584 -279.525222)
					(mid 169.273564 -279.528942)
					(end 169.277284 -279.537922)
				)
			)
		)
	)
	(zone
		(layer "In1.Cu")
		(hatch none 0.5)
		(connect_pads
			(clearance 0)
		)
		(min_thickness 0.25)
		(keepout
			(tracks not_allowed)
			(vias allowed)
			(pads allowed)
			(copperpour not_allowed)
			(footprints allowed)
		)
		(placement
			(enabled no)
			(sheetname "")
		)
		(fill
			(thermal_gap 0.5)
			(thermal_bridge_width 0.5)
			(island_removal_mode 0)
		)
		(polygon
			(pts
				(arc
					(start 432.30546 -275.782278)
					(mid 432.30174 -275.791258)
					(end 432.29276 -275.794978)
				)
				(arc
					(start 430.81956 -275.794978)
					(mid 430.81058 -275.791258)
					(end 430.80686 -275.782278)
				)
				(arc
					(start 430.80686 -275.28774)
					(mid 430.81058 -275.27876)
					(end 430.81956 -275.27504)
				)
				(arc
					(start 432.29276 -275.27504)
					(mid 432.30174 -275.27876)
					(end 432.30546 -275.28774)
				)
			)
		)
	)
	(zone
		(layer "In1.Cu")
		(hatch none 0.5)
		(connect_pads
			(clearance 0)
		)
		(min_thickness 0.25)
		(keepout
			(tracks not_allowed)
			(vias allowed)
			(pads allowed)
			(copperpour not_allowed)
			(footprints allowed)
		)
		(placement
			(enabled no)
			(sheetname "")
		)
		(fill
			(thermal_gap 0.5)
			(thermal_bridge_width 0.5)
			(island_removal_mode 0)
		)
		(polygon
			(pts
				(arc
					(start 185.513726 5.512054)
					(mid 185.491408 5.458172)
					(end 185.437526 5.435854)
				)
				(arc
					(start 184.825386 5.435854)
					(mid 184.771504 5.458172)
					(end 184.749186 5.512054)
				)
				(arc
					(start 184.749186 6.609334)
					(mid 184.771504 6.663216)
					(end 184.825386 6.685534)
				)
				(arc
					(start 185.437526 6.685534)
					(mid 185.491408 6.663216)
					(end 185.513726 6.609334)
				)
			)
		)
	)
	(zone
		(layer "In1.Cu")
		(hatch none 0.5)
		(connect_pads
			(clearance 0)
		)
		(min_thickness 0.25)
		(keepout
			(tracks not_allowed)
			(vias allowed)
			(pads allowed)
			(copperpour not_allowed)
			(footprints allowed)
		)
		(placement
			(enabled no)
			(sheetname "")
		)
		(fill
			(thermal_gap 0.5)
			(thermal_bridge_width 0.5)
			(island_removal_mode 0)
		)
		(polygon
			(pts
				(arc
					(start 418.797994 -399.143474)
					(mid 418.493194 -399.143474)
					(end 418.797994 -399.143474)
				)
			)
		)
	)
	(zone
		(layer "In1.Cu")
		(hatch none 0.5)
		(connect_pads
			(clearance 0)
		)
		(min_thickness 0.25)
		(keepout
			(tracks not_allowed)
			(vias allowed)
			(pads allowed)
			(copperpour not_allowed)
			(footprints allowed)
		)
		(placement
			(enabled no)
			(sheetname "")
		)
		(fill
			(thermal_gap 0.5)
			(thermal_bridge_width 0.5)
			(island_removal_mode 0)
		)
		(polygon
			(pts
				(arc
					(start 435.749446 -250.282202)
					(mid 435.745726 -250.291182)
					(end 435.736746 -250.294902)
				)
				(arc
					(start 434.263546 -250.294902)
					(mid 434.254566 -250.291182)
					(end 434.250846 -250.282202)
				)
				(arc
					(start 434.250846 -249.787664)
					(mid 434.254566 -249.778684)
					(end 434.263546 -249.774964)
				)
				(arc
					(start 435.736746 -249.774964)
					(mid 435.745726 -249.778684)
					(end 435.749446 -249.787664)
				)
			)
		)
	)
	(zone
		(layer "In1.Cu")
		(hatch none 0.5)
		(connect_pads
			(clearance 0)
		)
		(min_thickness 0.25)
		(keepout
			(tracks not_allowed)
			(vias allowed)
			(pads allowed)
			(copperpour not_allowed)
			(footprints allowed)
		)
		(placement
			(enabled no)
			(sheetname "")
		)
		(fill
			(thermal_gap 0.5)
			(thermal_bridge_width 0.5)
			(island_removal_mode 0)
		)
		(polygon
			(pts
				(arc
					(start 351.118424 -399.701258)
					(mid 351.245424 -399.828258)
					(end 351.372424 -399.701258)
				)
				(arc
					(start 351.372424 -399.625058)
					(mid 351.245424 -399.498058)
					(end 351.118424 -399.625058)
				)
			)
		)
	)
	(zone
		(layer "In1.Cu")
		(hatch none 0.5)
		(connect_pads
			(clearance 0)
		)
		(min_thickness 0.25)
		(keepout
			(tracks not_allowed)
			(vias allowed)
			(pads allowed)
			(copperpour not_allowed)
			(footprints allowed)
		)
		(placement
			(enabled no)
			(sheetname "")
		)
		(fill
			(thermal_gap 0.5)
			(thermal_bridge_width 0.5)
			(island_removal_mode 0)
		)
		(polygon
			(pts
				(arc
					(start 151.418798 -391.319258)
					(mid 151.545798 -391.446258)
					(end 151.672798 -391.319258)
				)
				(arc
					(start 151.672798 -391.243058)
					(mid 151.545798 -391.116058)
					(end 151.418798 -391.243058)
				)
			)
		)
	)
	(zone
		(layer "In1.Cu")
		(hatch none 0.5)
		(connect_pads
			(clearance 0)
		)
		(min_thickness 0.25)
		(keepout
			(tracks not_allowed)
			(vias allowed)
			(pads allowed)
			(copperpour not_allowed)
			(footprints allowed)
		)
		(placement
			(enabled no)
			(sheetname "")
		)
		(fill
			(thermal_gap 0.5)
			(thermal_bridge_width 0.5)
			(island_removal_mode 0)
		)
		(polygon
			(pts
				(arc
					(start 293.029386 -287.682178)
					(mid 293.025666 -287.691158)
					(end 293.016686 -287.694878)
				)
				(arc
					(start 291.543486 -287.694878)
					(mid 291.534506 -287.691158)
					(end 291.530786 -287.682178)
				)
				(arc
					(start 291.530786 -287.18764)
					(mid 291.534506 -287.17866)
					(end 291.543486 -287.17494)
				)
				(arc
					(start 293.016686 -287.17494)
					(mid 293.025666 -287.17866)
					(end 293.029386 -287.18764)
				)
			)
		)
	)
	(zone
		(layer "In1.Cu")
		(hatch none 0.5)
		(connect_pads
			(clearance 0)
		)
		(min_thickness 0.25)
		(keepout
			(tracks not_allowed)
			(vias allowed)
			(pads allowed)
			(copperpour not_allowed)
			(footprints allowed)
		)
		(placement
			(enabled no)
			(sheetname "")
		)
		(fill
			(thermal_gap 0.5)
			(thermal_bridge_width 0.5)
			(island_removal_mode 0)
		)
		(polygon
			(pts
				(arc
					(start 184.365392 -238.382556)
					(mid 184.361672 -238.391536)
					(end 184.352692 -238.395256)
				)
				(arc
					(start 182.879492 -238.395256)
					(mid 182.870512 -238.391536)
					(end 182.866792 -238.382556)
				)
				(arc
					(start 182.866792 -237.888018)
					(mid 182.870512 -237.879038)
					(end 182.879492 -237.875318)
				)
				(arc
					(start 184.352692 -237.875318)
					(mid 184.361672 -237.879038)
					(end 184.365392 -237.888018)
				)
			)
		)
	)
	(zone
		(layer "In1.Cu")
		(hatch none 0.5)
		(connect_pads
			(clearance 0)
		)
		(min_thickness 0.25)
		(keepout
			(tracks not_allowed)
			(vias allowed)
			(pads allowed)
			(copperpour not_allowed)
			(footprints allowed)
		)
		(placement
			(enabled no)
			(sheetname "")
		)
		(fill
			(thermal_gap 0.5)
			(thermal_bridge_width 0.5)
			(island_removal_mode 0)
		)
		(polygon
			(pts
				(arc
					(start 421.19804 -392.30427)
					(mid 420.89324 -392.30427)
					(end 421.19804 -392.30427)
				)
			)
		)
	)
	(zone
		(layer "In1.Cu")
		(hatch none 0.5)
		(connect_pads
			(clearance 0)
		)
		(min_thickness 0.25)
		(keepout
			(tracks not_allowed)
			(vias allowed)
			(pads allowed)
			(copperpour not_allowed)
			(footprints allowed)
		)
		(placement
			(enabled no)
			(sheetname "")
		)
		(fill
			(thermal_gap 0.5)
			(thermal_bridge_width 0.5)
			(island_removal_mode 0)
		)
		(polygon
			(pts
				(arc
					(start 293.029386 -289.3822)
					(mid 293.025666 -289.39118)
					(end 293.016686 -289.3949)
				)
				(arc
					(start 291.543486 -289.3949)
					(mid 291.534506 -289.39118)
					(end 291.530786 -289.3822)
				)
				(arc
					(start 291.530786 -288.887662)
					(mid 291.534506 -288.878682)
					(end 291.543486 -288.874962)
				)
				(arc
					(start 293.016686 -288.874962)
					(mid 293.025666 -288.878682)
					(end 293.029386 -288.887662)
				)
			)
		)
	)
	(zone
		(layer "In1.Cu")
		(hatch none 0.5)
		(connect_pads
			(clearance 0)
		)
		(min_thickness 0.25)
		(keepout
			(tracks not_allowed)
			(vias allowed)
			(pads allowed)
			(copperpour not_allowed)
			(footprints allowed)
		)
		(placement
			(enabled no)
			(sheetname "")
		)
		(fill
			(thermal_gap 0.5)
			(thermal_bridge_width 0.5)
			(island_removal_mode 0)
		)
		(polygon
			(pts
				(arc
					(start 348.388686 -394.385292)
					(mid 348.007686 -394.385292)
					(end 348.388686 -394.385292)
				)
			)
		)
	)
	(zone
		(layer "In1.Cu")
		(hatch none 0.5)
		(connect_pads
			(clearance 0)
		)
		(min_thickness 0.25)
		(keepout
			(tracks not_allowed)
			(vias allowed)
			(pads allowed)
			(copperpour not_allowed)
			(footprints allowed)
		)
		(placement
			(enabled no)
			(sheetname "")
		)
		(fill
			(thermal_gap 0.5)
			(thermal_bridge_width 0.5)
			(island_removal_mode 0)
		)
		(polygon
			(pts
				(arc
					(start 30.001464 -219.682568)
					(mid 29.997744 -219.691548)
					(end 29.988764 -219.695268)
				)
				(arc
					(start 28.515564 -219.695268)
					(mid 28.506584 -219.691548)
					(end 28.502864 -219.682568)
				)
				(arc
					(start 28.502864 -219.18803)
					(mid 28.506584 -219.17905)
					(end 28.515564 -219.17533)
				)
				(arc
					(start 29.988764 -219.17533)
					(mid 29.997744 -219.17905)
					(end 30.001464 -219.18803)
				)
			)
		)
	)
	(zone
		(layer "In1.Cu")
		(hatch none 0.5)
		(connect_pads
			(clearance 0)
		)
		(min_thickness 0.25)
		(keepout
			(tracks not_allowed)
			(vias allowed)
			(pads allowed)
			(copperpour not_allowed)
			(footprints allowed)
		)
		(placement
			(enabled no)
			(sheetname "")
		)
		(fill
			(thermal_gap 0.5)
			(thermal_bridge_width 0.5)
			(island_removal_mode 0)
		)
		(polygon
			(pts
				(arc
					(start 315.461142 -393.69238)
					(mid 315.080142 -393.69238)
					(end 315.461142 -393.69238)
				)
			)
		)
	)
	(zone
		(layer "In1.Cu")
		(hatch none 0.5)
		(connect_pads
			(clearance 0)
		)
		(min_thickness 0.25)
		(keepout
			(tracks not_allowed)
			(vias allowed)
			(pads allowed)
			(copperpour not_allowed)
			(footprints allowed)
		)
		(placement
			(enabled no)
			(sheetname "")
		)
		(fill
			(thermal_gap 0.5)
			(thermal_bridge_width 0.5)
			(island_removal_mode 0)
		)
		(polygon
			(pts
				(arc
					(start 130.27025 -383.92227)
					(mid 129.96545 -383.92227)
					(end 130.27025 -383.92227)
				)
			)
		)
	)
	(zone
		(layer "In1.Cu")
		(hatch none 0.5)
		(connect_pads
			(clearance 0)
		)
		(min_thickness 0.25)
		(keepout
			(tracks not_allowed)
			(vias allowed)
			(pads allowed)
			(copperpour not_allowed)
			(footprints allowed)
		)
		(placement
			(enabled no)
			(sheetname "")
		)
		(fill
			(thermal_gap 0.5)
			(thermal_bridge_width 0.5)
			(island_removal_mode 0)
		)
		(polygon
			(pts
				(arc
					(start 265.87831 -310.384952)
					(mid 265.21791 -310.384952)
					(end 265.87831 -310.384952)
				)
			)
		)
	)
	(zone
		(layer "In1.Cu")
		(hatch none 0.5)
		(connect_pads
			(clearance 0)
		)
		(min_thickness 0.25)
		(keepout
			(tracks not_allowed)
			(vias allowed)
			(pads allowed)
			(copperpour not_allowed)
			(footprints allowed)
		)
		(placement
			(enabled no)
			(sheetname "")
		)
		(fill
			(thermal_gap 0.5)
			(thermal_bridge_width 0.5)
			(island_removal_mode 0)
		)
		(polygon
			(pts
				(arc
					(start 305.970178 -399.143474)
					(mid 305.665378 -399.143474)
					(end 305.970178 -399.143474)
				)
			)
		)
	)
	(zone
		(layer "In1.Cu")
		(hatch none 0.5)
		(connect_pads
			(clearance 0)
		)
		(min_thickness 0.25)
		(keepout
			(tracks not_allowed)
			(vias allowed)
			(pads allowed)
			(copperpour not_allowed)
			(footprints allowed)
		)
		(placement
			(enabled no)
			(sheetname "")
		)
		(fill
			(thermal_gap 0.5)
			(thermal_bridge_width 0.5)
			(island_removal_mode 0)
		)
		(polygon
			(pts
				(arc
					(start 83.118706 -391.319258)
					(mid 83.245706 -391.446258)
					(end 83.372706 -391.319258)
				)
				(arc
					(start 83.372706 -391.243058)
					(mid 83.245706 -391.116058)
					(end 83.118706 -391.243058)
				)
			)
		)
	)
	(zone
		(layer "In1.Cu")
		(hatch none 0.5)
		(connect_pads
			(clearance 0)
		)
		(min_thickness 0.25)
		(keepout
			(tracks not_allowed)
			(vias allowed)
			(pads allowed)
			(copperpour not_allowed)
			(footprints allowed)
		)
		(placement
			(enabled no)
			(sheetname "")
		)
		(fill
			(thermal_gap 0.5)
			(thermal_bridge_width 0.5)
			(island_removal_mode 0)
		)
		(polygon
			(pts
				(arc
					(start 266.29741 -211.182204)
					(mid 266.29369 -211.191184)
					(end 266.28471 -211.194904)
				)
				(arc
					(start 264.81151 -211.194904)
					(mid 264.80253 -211.191184)
					(end 264.79881 -211.182204)
				)
				(arc
					(start 264.79881 -210.687666)
					(mid 264.80253 -210.678686)
					(end 264.81151 -210.674966)
				)
				(arc
					(start 266.28471 -210.674966)
					(mid 266.29369 -210.678686)
					(end 266.29741 -210.687666)
				)
			)
		)
	)
	(zone
		(layer "In1.Cu")
		(hatch none 0.5)
		(connect_pads
			(clearance 0)
		)
		(min_thickness 0.25)
		(keepout
			(tracks not_allowed)
			(vias allowed)
			(pads allowed)
			(copperpour not_allowed)
			(footprints allowed)
		)
		(placement
			(enabled no)
			(sheetname "")
		)
		(fill
			(thermal_gap 0.5)
			(thermal_bridge_width 0.5)
			(island_removal_mode 0)
		)
		(polygon
			(pts
				(arc
					(start 25.901396 -296.182542)
					(mid 25.897676 -296.191522)
					(end 25.888696 -296.195242)
				)
				(arc
					(start 24.415496 -296.195242)
					(mid 24.406516 -296.191522)
					(end 24.402796 -296.182542)
				)
				(arc
					(start 24.402796 -295.688004)
					(mid 24.406516 -295.679024)
					(end 24.415496 -295.675304)
				)
				(arc
					(start 25.888696 -295.675304)
					(mid 25.897676 -295.679024)
					(end 25.901396 -295.688004)
				)
			)
		)
	)
	(zone
		(layer "In1.Cu")
		(hatch none 0.5)
		(connect_pads
			(clearance 0)
		)
		(min_thickness 0.25)
		(keepout
			(tracks not_allowed)
			(vias allowed)
			(pads allowed)
			(copperpour not_allowed)
			(footprints allowed)
		)
		(placement
			(enabled no)
			(sheetname "")
		)
		(fill
			(thermal_gap 0.5)
			(thermal_bridge_width 0.5)
			(island_removal_mode 0)
		)
		(polygon
			(pts
				(arc
					(start 413.117284 -228.18217)
					(mid 413.113564 -228.19115)
					(end 413.104584 -228.19487)
				)
				(arc
					(start 411.631384 -228.19487)
					(mid 411.622404 -228.19115)
					(end 411.618684 -228.18217)
				)
				(arc
					(start 411.618684 -227.687632)
					(mid 411.622404 -227.678652)
					(end 411.631384 -227.674932)
				)
				(arc
					(start 413.104584 -227.674932)
					(mid 413.113564 -227.678652)
					(end 413.117284 -227.687632)
				)
			)
		)
	)
	(zone
		(layer "In1.Cu")
		(hatch none 0.5)
		(connect_pads
			(clearance 0)
		)
		(min_thickness 0.25)
		(keepout
			(tracks not_allowed)
			(vias allowed)
			(pads allowed)
			(copperpour not_allowed)
			(footprints allowed)
		)
		(placement
			(enabled no)
			(sheetname "")
		)
		(fill
			(thermal_gap 0.5)
			(thermal_bridge_width 0.5)
			(island_removal_mode 0)
		)
		(polygon
			(pts
				(arc
					(start 288.929318 -280.88209)
					(mid 288.925598 -280.89107)
					(end 288.916618 -280.89479)
				)
				(arc
					(start 287.443418 -280.89479)
					(mid 287.434438 -280.89107)
					(end 287.430718 -280.88209)
				)
				(arc
					(start 287.430718 -280.387552)
					(mid 287.434438 -280.378572)
					(end 287.443418 -280.374852)
				)
				(arc
					(start 288.916618 -280.374852)
					(mid 288.925598 -280.378572)
					(end 288.929318 -280.387552)
				)
			)
		)
	)
	(zone
		(layer "In1.Cu")
		(hatch none 0.5)
		(connect_pads
			(clearance 0)
		)
		(min_thickness 0.25)
		(keepout
			(tracks not_allowed)
			(vias allowed)
			(pads allowed)
			(copperpour not_allowed)
			(footprints allowed)
		)
		(placement
			(enabled no)
			(sheetname "")
		)
		(fill
			(thermal_gap 0.5)
			(thermal_bridge_width 0.5)
			(island_removal_mode 0)
		)
		(polygon
			(pts
				(arc
					(start 346.89796 -399.143474)
					(mid 346.59316 -399.143474)
					(end 346.89796 -399.143474)
				)
			)
		)
	)
	(zone
		(layer "In1.Cu")
		(hatch none 0.5)
		(connect_pads
			(clearance 0)
		)
		(min_thickness 0.25)
		(keepout
			(tracks not_allowed)
			(vias allowed)
			(pads allowed)
			(copperpour not_allowed)
			(footprints allowed)
		)
		(placement
			(enabled no)
			(sheetname "")
		)
		(fill
			(thermal_gap 0.5)
			(thermal_bridge_width 0.5)
			(island_removal_mode 0)
		)
		(polygon
			(pts
				(arc
					(start 130.161284 -388.774432)
					(mid 129.780284 -388.774432)
					(end 130.161284 -388.774432)
				)
			)
		)
	)
	(zone
		(layer "In1.Cu")
		(hatch none 0.5)
		(connect_pads
			(clearance 0)
		)
		(min_thickness 0.25)
		(keepout
			(tracks not_allowed)
			(vias allowed)
			(pads allowed)
			(copperpour not_allowed)
			(footprints allowed)
		)
		(placement
			(enabled no)
			(sheetname "")
		)
		(fill
			(thermal_gap 0.5)
			(thermal_bridge_width 0.5)
			(island_removal_mode 0)
		)
		(polygon
			(pts
				(arc
					(start 172.72127 -314.88253)
					(mid 172.71755 -314.89151)
					(end 172.70857 -314.89523)
				)
				(arc
					(start 171.23537 -314.89523)
					(mid 171.22639 -314.89151)
					(end 171.22267 -314.88253)
				)
				(arc
					(start 171.22267 -314.387992)
					(mid 171.22639 -314.379012)
					(end 171.23537 -314.375292)
				)
				(arc
					(start 172.70857 -314.375292)
					(mid 172.71755 -314.379012)
					(end 172.72127 -314.387992)
				)
			)
		)
	)
	(zone
		(layer "In1.Cu")
		(hatch none 0.5)
		(connect_pads
			(clearance 0)
		)
		(min_thickness 0.25)
		(keepout
			(tracks not_allowed)
			(vias allowed)
			(pads allowed)
			(copperpour not_allowed)
			(footprints allowed)
		)
		(placement
			(enabled no)
			(sheetname "")
		)
		(fill
			(thermal_gap 0.5)
			(thermal_bridge_width 0.5)
			(island_removal_mode 0)
		)
		(polygon
			(pts
				(arc
					(start 432.30546 -278.332184)
					(mid 432.30174 -278.341164)
					(end 432.29276 -278.344884)
				)
				(arc
					(start 430.81956 -278.344884)
					(mid 430.81058 -278.341164)
					(end 430.80686 -278.332184)
				)
				(arc
					(start 430.80686 -277.837646)
					(mid 430.81058 -277.828666)
					(end 430.81956 -277.824946)
				)
				(arc
					(start 432.29276 -277.824946)
					(mid 432.30174 -277.828666)
					(end 432.30546 -277.837646)
				)
			)
		)
	)
	(zone
		(layer "In1.Cu")
		(hatch none 0.5)
		(connect_pads
			(clearance 0)
		)
		(min_thickness 0.25)
		(keepout
			(tracks not_allowed)
			(vias allowed)
			(pads allowed)
			(copperpour not_allowed)
			(footprints allowed)
		)
		(placement
			(enabled no)
			(sheetname "")
		)
		(fill
			(thermal_gap 0.5)
			(thermal_bridge_width 0.5)
			(island_removal_mode 0)
		)
		(polygon
			(pts
				(arc
					(start 296.473372 -232.432098)
					(mid 296.469652 -232.441078)
					(end 296.460672 -232.444798)
				)
				(arc
					(start 294.987472 -232.444798)
					(mid 294.978492 -232.441078)
					(end 294.974772 -232.432098)
				)
				(arc
					(start 294.974772 -231.93756)
					(mid 294.978492 -231.92858)
					(end 294.987472 -231.92486)
				)
				(arc
					(start 296.460672 -231.92486)
					(mid 296.469652 -231.92858)
					(end 296.473372 -231.93756)
				)
			)
		)
	)
	(zone
		(layer "In1.Cu")
		(hatch none 0.5)
		(connect_pads
			(clearance 0)
		)
		(min_thickness 0.25)
		(keepout
			(tracks not_allowed)
			(vias allowed)
			(pads allowed)
			(copperpour not_allowed)
			(footprints allowed)
		)
		(placement
			(enabled no)
			(sheetname "")
		)
		(fill
			(thermal_gap 0.5)
			(thermal_bridge_width 0.5)
			(island_removal_mode 0)
		)
		(polygon
			(pts
				(arc
					(start 149.598126 -383.92227)
					(mid 149.293326 -383.92227)
					(end 149.598126 -383.92227)
				)
			)
		)
	)
	(zone
		(layer "In1.Cu")
		(hatch none 0.5)
		(connect_pads
			(clearance 0)
		)
		(min_thickness 0.25)
		(keepout
			(tracks not_allowed)
			(vias allowed)
			(pads allowed)
			(copperpour not_allowed)
			(footprints allowed)
		)
		(placement
			(enabled no)
			(sheetname "")
		)
		(fill
			(thermal_gap 0.5)
			(thermal_bridge_width 0.5)
			(island_removal_mode 0)
		)
		(polygon
			(pts
				(arc
					(start 206.9973 -227.33254)
					(mid 206.99358 -227.34152)
					(end 206.9846 -227.34524)
				)
				(arc
					(start 205.5114 -227.34524)
					(mid 205.50242 -227.34152)
					(end 205.4987 -227.33254)
				)
				(arc
					(start 205.4987 -226.838002)
					(mid 205.50242 -226.829022)
					(end 205.5114 -226.825302)
				)
				(arc
					(start 206.9846 -226.825302)
					(mid 206.99358 -226.829022)
					(end 206.9973 -226.838002)
				)
			)
		)
	)
	(zone
		(layer "In1.Cu")
		(hatch none 0.5)
		(connect_pads
			(clearance 0)
		)
		(min_thickness 0.25)
		(keepout
			(tracks not_allowed)
			(vias allowed)
			(pads allowed)
			(copperpour not_allowed)
			(footprints allowed)
		)
		(placement
			(enabled no)
			(sheetname "")
		)
		(fill
			(thermal_gap 0.5)
			(thermal_bridge_width 0.5)
			(island_removal_mode 0)
		)
		(polygon
			(pts
				(arc
					(start 93.918786 -391.319258)
					(mid 94.045786 -391.446258)
					(end 94.172786 -391.319258)
				)
				(arc
					(start 94.172786 -391.243058)
					(mid 94.045786 -391.116058)
					(end 93.918786 -391.243058)
				)
			)
		)
	)
	(zone
		(layer "In1.Cu")
		(hatch none 0.5)
		(connect_pads
			(clearance 0)
		)
		(min_thickness 0.25)
		(keepout
			(tracks not_allowed)
			(vias allowed)
			(pads allowed)
			(copperpour not_allowed)
			(footprints allowed)
		)
		(placement
			(enabled no)
			(sheetname "")
		)
		(fill
			(thermal_gap 0.5)
			(thermal_bridge_width 0.5)
			(island_removal_mode 0)
		)
		(polygon
			(pts
				(arc
					(start 454.937368 -200.982326)
					(mid 454.933648 -200.991306)
					(end 454.924668 -200.995026)
				)
				(arc
					(start 453.451468 -200.995026)
					(mid 453.442488 -200.991306)
					(end 453.438768 -200.982326)
				)
				(arc
					(start 453.438768 -200.487788)
					(mid 453.442488 -200.478808)
					(end 453.451468 -200.475088)
				)
				(arc
					(start 454.924668 -200.475088)
					(mid 454.933648 -200.478808)
					(end 454.937368 -200.487788)
				)
			)
		)
	)
	(zone
		(layer "In1.Cu")
		(hatch none 0.5)
		(connect_pads
			(clearance 0)
		)
		(min_thickness 0.25)
		(keepout
			(tracks not_allowed)
			(vias allowed)
			(pads allowed)
			(copperpour not_allowed)
			(footprints allowed)
		)
		(placement
			(enabled no)
			(sheetname "")
		)
		(fill
			(thermal_gap 0.5)
			(thermal_bridge_width 0.5)
			(island_removal_mode 0)
		)
		(polygon
			(pts
				(arc
					(start 125.470412 -383.92227)
					(mid 125.165612 -383.92227)
					(end 125.470412 -383.92227)
				)
			)
		)
	)
	(zone
		(layer "In1.Cu")
		(hatch none 0.5)
		(connect_pads
			(clearance 0)
		)
		(min_thickness 0.25)
		(keepout
			(tracks not_allowed)
			(vias allowed)
			(pads allowed)
			(copperpour not_allowed)
			(footprints allowed)
		)
		(placement
			(enabled no)
			(sheetname "")
		)
		(fill
			(thermal_gap 0.5)
			(thermal_bridge_width 0.5)
			(island_removal_mode 0)
		)
		(polygon
			(pts
				(arc
					(start 40.98925 -209.482436)
					(mid 40.98553 -209.491416)
					(end 40.97655 -209.495136)
				)
				(arc
					(start 39.50335 -209.495136)
					(mid 39.49437 -209.491416)
					(end 39.49065 -209.482436)
				)
				(arc
					(start 39.49065 -208.987898)
					(mid 39.49437 -208.978918)
					(end 39.50335 -208.975198)
				)
				(arc
					(start 40.97655 -208.975198)
					(mid 40.98553 -208.978918)
					(end 40.98925 -208.987898)
				)
			)
		)
	)
	(zone
		(layer "In1.Cu")
		(hatch none 0.5)
		(connect_pads
			(clearance 0)
		)
		(min_thickness 0.25)
		(keepout
			(tracks not_allowed)
			(vias allowed)
			(pads allowed)
			(copperpour not_allowed)
			(footprints allowed)
		)
		(placement
			(enabled no)
			(sheetname "")
		)
		(fill
			(thermal_gap 0.5)
			(thermal_bridge_width 0.5)
			(island_removal_mode 0)
		)
		(polygon
			(pts
				(arc
					(start 202.897232 -218.83243)
					(mid 202.893512 -218.84141)
					(end 202.884532 -218.84513)
				)
				(arc
					(start 201.411332 -218.84513)
					(mid 201.402352 -218.84141)
					(end 201.398632 -218.83243)
				)
				(arc
					(start 201.398632 -218.337892)
					(mid 201.402352 -218.328912)
					(end 201.411332 -218.325192)
				)
				(arc
					(start 202.884532 -218.325192)
					(mid 202.893512 -218.328912)
					(end 202.897232 -218.337892)
				)
			)
		)
	)
	(zone
		(layer "In1.Cu")
		(hatch none 0.5)
		(connect_pads
			(clearance 0)
		)
		(min_thickness 0.25)
		(keepout
			(tracks not_allowed)
			(vias allowed)
			(pads allowed)
			(copperpour not_allowed)
			(footprints allowed)
		)
		(placement
			(enabled no)
			(sheetname "")
		)
		(fill
			(thermal_gap 0.5)
			(thermal_bridge_width 0.5)
			(island_removal_mode 0)
		)
		(polygon
			(pts
				(arc
					(start 131.36118 -385.31038)
					(mid 130.98018 -385.31038)
					(end 131.36118 -385.31038)
				)
			)
		)
	)
	(zone
		(layer "In1.Cu")
		(hatch none 0.5)
		(connect_pads
			(clearance 0)
		)
		(min_thickness 0.25)
		(keepout
			(tracks not_allowed)
			(vias allowed)
			(pads allowed)
			(copperpour not_allowed)
			(footprints allowed)
		)
		(placement
			(enabled no)
			(sheetname "")
		)
		(fill
			(thermal_gap 0.5)
			(thermal_bridge_width 0.5)
			(island_removal_mode 0)
		)
		(polygon
			(pts
				(arc
					(start 40.98925 -221.382336)
					(mid 40.98553 -221.391316)
					(end 40.97655 -221.395036)
				)
				(arc
					(start 39.50335 -221.395036)
					(mid 39.49437 -221.391316)
					(end 39.49065 -221.382336)
				)
				(arc
					(start 39.49065 -220.887798)
					(mid 39.49437 -220.878818)
					(end 39.50335 -220.875098)
				)
				(arc
					(start 40.97655 -220.875098)
					(mid 40.98553 -220.878818)
					(end 40.98925 -220.887798)
				)
			)
		)
	)
	(zone
		(layer "In1.Cu")
		(hatch none 0.5)
		(connect_pads
			(clearance 0)
		)
		(min_thickness 0.25)
		(keepout
			(tracks not_allowed)
			(vias allowed)
			(pads allowed)
			(copperpour not_allowed)
			(footprints allowed)
		)
		(placement
			(enabled no)
			(sheetname "")
		)
		(fill
			(thermal_gap 0.5)
			(thermal_bridge_width 0.5)
			(island_removal_mode 0)
		)
		(polygon
			(pts
				(arc
					(start 266.29741 -308.932326)
					(mid 266.29369 -308.941306)
					(end 266.28471 -308.945026)
				)
				(arc
					(start 264.81151 -308.945026)
					(mid 264.80253 -308.941306)
					(end 264.79881 -308.932326)
				)
				(arc
					(start 264.79881 -308.437788)
					(mid 264.80253 -308.428808)
					(end 264.81151 -308.425088)
				)
				(arc
					(start 266.28471 -308.425088)
					(mid 266.29369 -308.428808)
					(end 266.29741 -308.437788)
				)
			)
		)
	)
	(zone
		(layer "In1.Cu")
		(hatch none 0.5)
		(connect_pads
			(clearance 0)
		)
		(min_thickness 0.25)
		(keepout
			(tracks not_allowed)
			(vias allowed)
			(pads allowed)
			(copperpour not_allowed)
			(footprints allowed)
		)
		(placement
			(enabled no)
			(sheetname "")
		)
		(fill
			(thermal_gap 0.5)
			(thermal_bridge_width 0.5)
			(island_removal_mode 0)
		)
		(polygon
			(pts
				(arc
					(start 169.277284 -285.98241)
					(mid 169.273564 -285.99139)
					(end 169.264584 -285.99511)
				)
				(arc
					(start 167.791384 -285.99511)
					(mid 167.782404 -285.99139)
					(end 167.778684 -285.98241)
				)
				(arc
					(start 167.778684 -285.487872)
					(mid 167.782404 -285.478892)
					(end 167.791384 -285.475172)
				)
				(arc
					(start 169.264584 -285.475172)
					(mid 169.273564 -285.478892)
					(end 169.277284 -285.487872)
				)
			)
		)
	)
	(zone
		(layer "In1.Cu")
		(hatch none 0.5)
		(connect_pads
			(clearance 0)
		)
		(min_thickness 0.25)
		(keepout
			(tracks not_allowed)
			(vias allowed)
			(pads allowed)
			(copperpour not_allowed)
			(footprints allowed)
		)
		(placement
			(enabled no)
			(sheetname "")
		)
		(fill
			(thermal_gap 0.5)
			(thermal_bridge_width 0.5)
			(island_removal_mode 0)
		)
		(polygon
			(pts
				(arc
					(start 37.545264 -313.182508)
					(mid 37.541544 -313.191488)
					(end 37.532564 -313.195208)
				)
				(arc
					(start 36.059364 -313.195208)
					(mid 36.050384 -313.191488)
					(end 36.046664 -313.182508)
				)
				(arc
					(start 36.046664 -312.68797)
					(mid 36.050384 -312.67899)
					(end 36.059364 -312.67527)
				)
				(arc
					(start 37.532564 -312.67527)
					(mid 37.541544 -312.67899)
					(end 37.545264 -312.68797)
				)
			)
		)
	)
	(zone
		(layer "In1.Cu")
		(hatch none 0.5)
		(connect_pads
			(clearance 0)
		)
		(min_thickness 0.25)
		(keepout
			(tracks not_allowed)
			(vias allowed)
			(pads allowed)
			(copperpour not_allowed)
			(footprints allowed)
		)
		(placement
			(enabled no)
			(sheetname "")
		)
		(fill
			(thermal_gap 0.5)
			(thermal_bridge_width 0.5)
			(island_removal_mode 0)
		)
		(polygon
			(pts
				(arc
					(start 126.090934 -383.440686)
					(mid 126.217934 -383.567686)
					(end 126.344934 -383.440686)
				)
				(arc
					(start 126.344934 -383.364486)
					(mid 126.217934 -383.237486)
					(end 126.090934 -383.364486)
				)
			)
		)
	)
	(zone
		(layer "In1.Cu")
		(hatch none 0.5)
		(connect_pads
			(clearance 0)
		)
		(min_thickness 0.25)
		(keepout
			(tracks not_allowed)
			(vias allowed)
			(pads allowed)
			(copperpour not_allowed)
			(footprints allowed)
		)
		(placement
			(enabled no)
			(sheetname "")
		)
		(fill
			(thermal_gap 0.5)
			(thermal_bridge_width 0.5)
			(island_removal_mode 0)
		)
		(polygon
			(pts
				(arc
					(start 18.357342 -201.832464)
					(mid 18.353622 -201.841444)
					(end 18.344642 -201.845164)
				)
				(arc
					(start 16.871442 -201.845164)
					(mid 16.862462 -201.841444)
					(end 16.858742 -201.832464)
				)
				(arc
					(start 16.858742 -201.337926)
					(mid 16.862462 -201.328946)
					(end 16.871442 -201.325226)
				)
				(arc
					(start 18.344642 -201.325226)
					(mid 18.353622 -201.328946)
					(end 18.357342 -201.337926)
				)
			)
		)
	)
	(zone
		(layer "In1.Cu")
		(hatch none 0.5)
		(connect_pads
			(clearance 0)
		)
		(min_thickness 0.25)
		(keepout
			(tracks not_allowed)
			(vias allowed)
			(pads allowed)
			(copperpour not_allowed)
			(footprints allowed)
		)
		(placement
			(enabled no)
			(sheetname "")
		)
		(fill
			(thermal_gap 0.5)
			(thermal_bridge_width 0.5)
			(island_removal_mode 0)
		)
		(polygon
			(pts
				(arc
					(start 420.661338 -206.082138)
					(mid 420.657618 -206.091118)
					(end 420.648638 -206.094838)
				)
				(arc
					(start 419.175438 -206.094838)
					(mid 419.166458 -206.091118)
					(end 419.162738 -206.082138)
				)
				(arc
					(start 419.162738 -205.5876)
					(mid 419.166458 -205.57862)
					(end 419.175438 -205.5749)
				)
				(arc
					(start 420.648638 -205.5749)
					(mid 420.657618 -205.57862)
					(end 420.661338 -205.5876)
				)
			)
		)
	)
	(zone
		(layer "In1.Cu")
		(hatch none 0.5)
		(connect_pads
			(clearance 0)
		)
		(min_thickness 0.25)
		(keepout
			(tracks not_allowed)
			(vias allowed)
			(pads allowed)
			(copperpour not_allowed)
			(footprints allowed)
		)
		(placement
			(enabled no)
			(sheetname "")
		)
		(fill
			(thermal_gap 0.5)
			(thermal_bridge_width 0.5)
			(island_removal_mode 0)
		)
		(polygon
			(pts
				(arc
					(start 285.485332 -285.982156)
					(mid 285.481612 -285.991136)
					(end 285.472632 -285.994856)
				)
				(arc
					(start 283.999432 -285.994856)
					(mid 283.990452 -285.991136)
					(end 283.986732 -285.982156)
				)
				(arc
					(start 283.986732 -285.487618)
					(mid 283.990452 -285.478638)
					(end 283.999432 -285.474918)
				)
				(arc
					(start 285.472632 -285.474918)
					(mid 285.481612 -285.478638)
					(end 285.485332 -285.487618)
				)
			)
		)
	)
	(zone
		(layer "In1.Cu")
		(hatch none 0.5)
		(connect_pads
			(clearance 0)
		)
		(min_thickness 0.25)
		(keepout
			(tracks not_allowed)
			(vias allowed)
			(pads allowed)
			(copperpour not_allowed)
			(footprints allowed)
		)
		(placement
			(enabled no)
			(sheetname "")
		)
		(fill
			(thermal_gap 0.5)
			(thermal_bridge_width 0.5)
			(island_removal_mode 0)
		)
		(polygon
			(pts
				(arc
					(start 37.545264 -315.732414)
					(mid 37.541544 -315.741394)
					(end 37.532564 -315.745114)
				)
				(arc
					(start 36.059364 -315.745114)
					(mid 36.050384 -315.741394)
					(end 36.046664 -315.732414)
				)
				(arc
					(start 36.046664 -315.237876)
					(mid 36.050384 -315.228896)
					(end 36.059364 -315.225176)
				)
				(arc
					(start 37.532564 -315.225176)
					(mid 37.541544 -315.228896)
					(end 37.545264 -315.237876)
				)
			)
		)
	)
	(zone
		(layer "In1.Cu")
		(hatch none 0.5)
		(connect_pads
			(clearance 0)
		)
		(min_thickness 0.25)
		(keepout
			(tracks not_allowed)
			(vias allowed)
			(pads allowed)
			(copperpour not_allowed)
			(footprints allowed)
		)
		(placement
			(enabled no)
			(sheetname "")
		)
		(fill
			(thermal_gap 0.5)
			(thermal_bridge_width 0.5)
			(island_removal_mode 0)
		)
		(polygon
			(pts
				(arc
					(start 52.633372 -275.782532)
					(mid 52.629652 -275.791512)
					(end 52.620672 -275.795232)
				)
				(arc
					(start 51.147472 -275.795232)
					(mid 51.138492 -275.791512)
					(end 51.134772 -275.782532)
				)
				(arc
					(start 51.134772 -275.287994)
					(mid 51.138492 -275.279014)
					(end 51.147472 -275.275294)
				)
				(arc
					(start 52.620672 -275.275294)
					(mid 52.629652 -275.279014)
					(end 52.633372 -275.287994)
				)
			)
		)
	)
	(zone
		(layer "In1.Cu")
		(hatch none 0.5)
		(connect_pads
			(clearance 0)
		)
		(min_thickness 0.25)
		(keepout
			(tracks not_allowed)
			(vias allowed)
			(pads allowed)
			(copperpour not_allowed)
			(footprints allowed)
		)
		(placement
			(enabled no)
			(sheetname "")
		)
		(fill
			(thermal_gap 0.5)
			(thermal_bridge_width 0.5)
			(island_removal_mode 0)
		)
		(polygon
			(pts
				(arc
					(start 98.388932 -389.467344)
					(mid 98.007932 -389.467344)
					(end 98.388932 -389.467344)
				)
			)
		)
	)
	(zone
		(layer "In1.Cu")
		(hatch none 0.5)
		(connect_pads
			(clearance 0)
		)
		(min_thickness 0.25)
		(keepout
			(tracks not_allowed)
			(vias allowed)
			(pads allowed)
			(copperpour not_allowed)
			(footprints allowed)
		)
		(placement
			(enabled no)
			(sheetname "")
		)
		(fill
			(thermal_gap 0.5)
			(thermal_bridge_width 0.5)
			(island_removal_mode 0)
		)
		(polygon
			(pts
				(arc
					(start 296.473372 -230.73233)
					(mid 296.469652 -230.74131)
					(end 296.460672 -230.74503)
				)
				(arc
					(start 294.987472 -230.74503)
					(mid 294.978492 -230.74131)
					(end 294.974772 -230.73233)
				)
				(arc
					(start 294.974772 -230.237792)
					(mid 294.978492 -230.228812)
					(end 294.987472 -230.225092)
				)
				(arc
					(start 296.460672 -230.225092)
					(mid 296.469652 -230.228812)
					(end 296.473372 -230.237792)
				)
			)
		)
	)
	(zone
		(layer "In1.Cu")
		(hatch none 0.5)
		(connect_pads
			(clearance 0)
		)
		(min_thickness 0.25)
		(keepout
			(tracks not_allowed)
			(vias allowed)
			(pads allowed)
			(copperpour not_allowed)
			(footprints allowed)
		)
		(placement
			(enabled no)
			(sheetname "")
		)
		(fill
			(thermal_gap 0.5)
			(thermal_bridge_width 0.5)
			(island_removal_mode 0)
		)
		(polygon
			(pts
				(arc
					(start 424.761406 -268.132306)
					(mid 424.757686 -268.141286)
					(end 424.748706 -268.145006)
				)
				(arc
					(start 423.275506 -268.145006)
					(mid 423.266526 -268.141286)
					(end 423.262806 -268.132306)
				)
				(arc
					(start 423.262806 -267.637768)
					(mid 423.266526 -267.628788)
					(end 423.275506 -267.625068)
				)
				(arc
					(start 424.748706 -267.625068)
					(mid 424.757686 -267.628788)
					(end 424.761406 -267.637768)
				)
			)
		)
	)
	(zone
		(layer "In1.Cu")
		(hatch none 0.5)
		(connect_pads
			(clearance 0)
		)
		(min_thickness 0.25)
		(keepout
			(tracks not_allowed)
			(vias allowed)
			(pads allowed)
			(copperpour not_allowed)
			(footprints allowed)
		)
		(placement
			(enabled no)
			(sheetname "")
		)
		(fill
			(thermal_gap 0.5)
			(thermal_bridge_width 0.5)
			(island_removal_mode 0)
		)
		(polygon
			(pts
				(arc
					(start 127.870458 -390.761474)
					(mid 127.565658 -390.761474)
					(end 127.870458 -390.761474)
				)
			)
		)
	)
	(zone
		(layer "In1.Cu")
		(hatch none 0.5)
		(connect_pads
			(clearance 0)
		)
		(min_thickness 0.25)
		(keepout
			(tracks not_allowed)
			(vias allowed)
			(pads allowed)
			(copperpour not_allowed)
			(footprints allowed)
		)
		(placement
			(enabled no)
			(sheetname "")
		)
		(fill
			(thermal_gap 0.5)
			(thermal_bridge_width 0.5)
			(island_removal_mode 0)
		)
		(polygon
			(pts
				(arc
					(start 184.365392 -298.732448)
					(mid 184.361672 -298.741428)
					(end 184.352692 -298.745148)
				)
				(arc
					(start 182.879492 -298.745148)
					(mid 182.870512 -298.741428)
					(end 182.866792 -298.732448)
				)
				(arc
					(start 182.866792 -298.23791)
					(mid 182.870512 -298.22893)
					(end 182.879492 -298.22521)
				)
				(arc
					(start 184.352692 -298.22521)
					(mid 184.361672 -298.22893)
					(end 184.365392 -298.23791)
				)
			)
		)
	)
	(zone
		(layer "In1.Cu")
		(hatch none 0.5)
		(connect_pads
			(clearance 0)
		)
		(min_thickness 0.25)
		(keepout
			(tracks not_allowed)
			(vias allowed)
			(pads allowed)
			(copperpour not_allowed)
			(footprints allowed)
		)
		(placement
			(enabled no)
			(sheetname "")
		)
		(fill
			(thermal_gap 0.5)
			(thermal_bridge_width 0.5)
			(island_removal_mode 0)
		)
		(polygon
			(pts
				(arc
					(start 56.077358 -234.132374)
					(mid 56.073638 -234.141354)
					(end 56.064658 -234.145074)
				)
				(arc
					(start 54.591458 -234.145074)
					(mid 54.582478 -234.141354)
					(end 54.578758 -234.132374)
				)
				(arc
					(start 54.578758 -233.637836)
					(mid 54.582478 -233.628856)
					(end 54.591458 -233.625136)
				)
				(arc
					(start 56.064658 -233.625136)
					(mid 56.073638 -233.628856)
					(end 56.077358 -233.637836)
				)
			)
		)
	)
	(zone
		(layer "In1.Cu")
		(hatch none 0.5)
		(connect_pads
			(clearance 0)
		)
		(min_thickness 0.25)
		(keepout
			(tracks not_allowed)
			(vias allowed)
			(pads allowed)
			(copperpour not_allowed)
			(footprints allowed)
		)
		(placement
			(enabled no)
			(sheetname "")
		)
		(fill
			(thermal_gap 0.5)
			(thermal_bridge_width 0.5)
			(island_removal_mode 0)
		)
		(polygon
			(pts
				(arc
					(start 202.897232 -234.132374)
					(mid 202.893512 -234.141354)
					(end 202.884532 -234.145074)
				)
				(arc
					(start 201.411332 -234.145074)
					(mid 201.402352 -234.141354)
					(end 201.398632 -234.132374)
				)
				(arc
					(start 201.398632 -233.637836)
					(mid 201.402352 -233.628856)
					(end 201.411332 -233.625136)
				)
				(arc
					(start 202.884532 -233.625136)
					(mid 202.893512 -233.628856)
					(end 202.897232 -233.637836)
				)
			)
		)
	)
	(zone
		(layer "In1.Cu")
		(hatch none 0.5)
		(connect_pads
			(clearance 0)
		)
		(min_thickness 0.25)
		(keepout
			(tracks not_allowed)
			(vias allowed)
			(pads allowed)
			(copperpour not_allowed)
			(footprints allowed)
		)
		(placement
			(enabled no)
			(sheetname "")
		)
		(fill
			(thermal_gap 0.5)
			(thermal_bridge_width 0.5)
			(island_removal_mode 0)
		)
		(polygon
			(pts
				(arc
					(start 180.265324 -239.23244)
					(mid 180.261604 -239.24142)
					(end 180.252624 -239.24514)
				)
				(arc
					(start 178.779424 -239.24514)
					(mid 178.770444 -239.24142)
					(end 178.766724 -239.23244)
				)
				(arc
					(start 178.766724 -238.737902)
					(mid 178.770444 -238.728922)
					(end 178.779424 -238.725202)
				)
				(arc
					(start 180.252624 -238.725202)
					(mid 180.261604 -238.728922)
					(end 180.265324 -238.737902)
				)
			)
		)
	)
	(zone
		(layer "In1.Cu")
		(hatch none 0.5)
		(connect_pads
			(clearance 0)
		)
		(min_thickness 0.25)
		(keepout
			(tracks not_allowed)
			(vias allowed)
			(pads allowed)
			(copperpour not_allowed)
			(footprints allowed)
		)
		(placement
			(enabled no)
			(sheetname "")
		)
		(fill
			(thermal_gap 0.5)
			(thermal_bridge_width 0.5)
			(island_removal_mode 0)
		)
		(polygon
			(pts
				(arc
					(start 169.277284 -229.882446)
					(mid 169.273564 -229.891426)
					(end 169.264584 -229.895146)
				)
				(arc
					(start 167.791384 -229.895146)
					(mid 167.782404 -229.891426)
					(end 167.778684 -229.882446)
				)
				(arc
					(start 167.778684 -229.387908)
					(mid 167.782404 -229.378928)
					(end 167.791384 -229.375208)
				)
				(arc
					(start 169.264584 -229.375208)
					(mid 169.273564 -229.378928)
					(end 169.277284 -229.387908)
				)
			)
		)
	)
	(zone
		(layer "In1.Cu")
		(hatch none 0.5)
		(connect_pads
			(clearance 0)
		)
		(min_thickness 0.25)
		(keepout
			(tracks not_allowed)
			(vias allowed)
			(pads allowed)
			(copperpour not_allowed)
			(footprints allowed)
		)
		(placement
			(enabled no)
			(sheetname "")
		)
		(fill
			(thermal_gap 0.5)
			(thermal_bridge_width 0.5)
			(island_removal_mode 0)
		)
		(polygon
			(pts
				(arc
					(start 454.937368 -220.532198)
					(mid 454.933648 -220.541178)
					(end 454.924668 -220.544898)
				)
				(arc
					(start 453.451468 -220.544898)
					(mid 453.442488 -220.541178)
					(end 453.438768 -220.532198)
				)
				(arc
					(start 453.438768 -220.03766)
					(mid 453.442488 -220.02868)
					(end 453.451468 -220.02496)
				)
				(arc
					(start 454.924668 -220.02496)
					(mid 454.933648 -220.02868)
					(end 454.937368 -220.03766)
				)
			)
		)
	)
	(zone
		(layer "In1.Cu")
		(hatch none 0.5)
		(connect_pads
			(clearance 0)
		)
		(min_thickness 0.25)
		(keepout
			(tracks not_allowed)
			(vias allowed)
			(pads allowed)
			(copperpour not_allowed)
			(footprints allowed)
		)
		(placement
			(enabled no)
			(sheetname "")
		)
		(fill
			(thermal_gap 0.5)
			(thermal_bridge_width 0.5)
			(island_removal_mode 0)
		)
		(polygon
			(pts
				(arc
					(start 432.30546 -240.932208)
					(mid 432.30174 -240.941188)
					(end 432.29276 -240.944908)
				)
				(arc
					(start 430.81956 -240.944908)
					(mid 430.81058 -240.941188)
					(end 430.80686 -240.932208)
				)
				(arc
					(start 430.80686 -240.43767)
					(mid 430.81058 -240.42869)
					(end 430.81956 -240.42497)
				)
				(arc
					(start 432.29276 -240.42497)
					(mid 432.30174 -240.42869)
					(end 432.30546 -240.43767)
				)
			)
		)
	)
	(zone
		(layer "In1.Cu")
		(hatch none 0.5)
		(connect_pads
			(clearance 0)
		)
		(min_thickness 0.25)
		(keepout
			(tracks not_allowed)
			(vias allowed)
			(pads allowed)
			(copperpour not_allowed)
			(footprints allowed)
		)
		(placement
			(enabled no)
			(sheetname "")
		)
		(fill
			(thermal_gap 0.5)
			(thermal_bridge_width 0.5)
			(island_removal_mode 0)
		)
		(polygon
			(pts
				(arc
					(start 165.088824 -385.31038)
					(mid 164.707824 -385.31038)
					(end 165.088824 -385.31038)
				)
			)
		)
	)
	(zone
		(layer "In1.Cu")
		(hatch none 0.5)
		(connect_pads
			(clearance 0)
		)
		(min_thickness 0.25)
		(keepout
			(tracks not_allowed)
			(vias allowed)
			(pads allowed)
			(copperpour not_allowed)
			(footprints allowed)
		)
		(placement
			(enabled no)
			(sheetname "")
		)
		(fill
			(thermal_gap 0.5)
			(thermal_bridge_width 0.5)
			(island_removal_mode 0)
		)
		(polygon
			(pts
				(arc
					(start 405.341582 -11.91768)
					(mid 405.319264 -11.971562)
					(end 405.265382 -11.99388)
				)
				(arc
					(start 404.228808 -11.99388)
					(mid 404.174926 -11.971562)
					(end 404.152608 -11.91768)
				)
				(arc
					(start 404.152608 -10.51814)
					(mid 404.174926 -10.464258)
					(end 404.228808 -10.44194)
				)
				(arc
					(start 405.265382 -10.44194)
					(mid 405.319264 -10.464258)
					(end 405.341582 -10.51814)
				)
			)
		)
	)
	(zone
		(layer "In1.Cu")
		(hatch none 0.5)
		(connect_pads
			(clearance 0)
		)
		(min_thickness 0.25)
		(keepout
			(tracks not_allowed)
			(vias allowed)
			(pads allowed)
			(copperpour not_allowed)
			(footprints allowed)
		)
		(placement
			(enabled no)
			(sheetname "")
		)
		(fill
			(thermal_gap 0.5)
			(thermal_bridge_width 0.5)
			(island_removal_mode 0)
		)
		(polygon
			(pts
				(arc
					(start 37.545264 -234.982512)
					(mid 37.541544 -234.991492)
					(end 37.532564 -234.995212)
				)
				(arc
					(start 36.059364 -234.995212)
					(mid 36.050384 -234.991492)
					(end 36.046664 -234.982512)
				)
				(arc
					(start 36.046664 -234.487974)
					(mid 36.050384 -234.478994)
					(end 36.059364 -234.475274)
				)
				(arc
					(start 37.532564 -234.475274)
					(mid 37.541544 -234.478994)
					(end 37.545264 -234.487974)
				)
			)
		)
	)
	(zone
		(layer "In1.Cu")
		(hatch none 0.5)
		(connect_pads
			(clearance 0)
		)
		(min_thickness 0.25)
		(keepout
			(tracks not_allowed)
			(vias allowed)
			(pads allowed)
			(copperpour not_allowed)
			(footprints allowed)
		)
		(placement
			(enabled no)
			(sheetname "")
		)
		(fill
			(thermal_gap 0.5)
			(thermal_bridge_width 0.5)
			(island_removal_mode 0)
		)
		(polygon
			(pts
				(arc
					(start 304.017426 -223.082104)
					(mid 304.013706 -223.091084)
					(end 304.004726 -223.094804)
				)
				(arc
					(start 302.531526 -223.094804)
					(mid 302.522546 -223.091084)
					(end 302.518826 -223.082104)
				)
				(arc
					(start 302.518826 -222.587566)
					(mid 302.522546 -222.578586)
					(end 302.531526 -222.574866)
				)
				(arc
					(start 304.004726 -222.574866)
					(mid 304.013706 -222.578586)
					(end 304.017426 -222.587566)
				)
			)
		)
	)
	(zone
		(layer "In1.Cu")
		(hatch none 0.5)
		(connect_pads
			(clearance 0)
		)
		(min_thickness 0.25)
		(keepout
			(tracks not_allowed)
			(vias allowed)
			(pads allowed)
			(copperpour not_allowed)
			(footprints allowed)
		)
		(placement
			(enabled no)
			(sheetname "")
		)
		(fill
			(thermal_gap 0.5)
			(thermal_bridge_width 0.5)
			(island_removal_mode 0)
		)
		(polygon
			(pts
				(arc
					(start 447.393568 -208.632298)
					(mid 447.389848 -208.641278)
					(end 447.380868 -208.644998)
				)
				(arc
					(start 445.907668 -208.644998)
					(mid 445.898688 -208.641278)
					(end 445.894968 -208.632298)
				)
				(arc
					(start 445.894968 -208.13776)
					(mid 445.898688 -208.12878)
					(end 445.907668 -208.12506)
				)
				(arc
					(start 447.380868 -208.12506)
					(mid 447.389848 -208.12878)
					(end 447.393568 -208.13776)
				)
			)
		)
	)
	(zone
		(layer "In1.Cu")
		(hatch none 0.5)
		(connect_pads
			(clearance 0)
		)
		(min_thickness 0.25)
		(keepout
			(tracks not_allowed)
			(vias allowed)
			(pads allowed)
			(copperpour not_allowed)
			(footprints allowed)
		)
		(placement
			(enabled no)
			(sheetname "")
		)
		(fill
			(thermal_gap 0.5)
			(thermal_bridge_width 0.5)
			(island_removal_mode 0)
		)
		(polygon
			(pts
				(arc
					(start 184.365392 -229.882446)
					(mid 184.361672 -229.891426)
					(end 184.352692 -229.895146)
				)
				(arc
					(start 182.879492 -229.895146)
					(mid 182.870512 -229.891426)
					(end 182.866792 -229.882446)
				)
				(arc
					(start 182.866792 -229.387908)
					(mid 182.870512 -229.378928)
					(end 182.879492 -229.375208)
				)
				(arc
					(start 184.352692 -229.375208)
					(mid 184.361672 -229.378928)
					(end 184.365392 -229.387908)
				)
			)
		)
	)
	(zone
		(layer "In1.Cu")
		(hatch none 0.5)
		(connect_pads
			(clearance 0)
		)
		(min_thickness 0.25)
		(keepout
			(tracks not_allowed)
			(vias allowed)
			(pads allowed)
			(copperpour not_allowed)
			(footprints allowed)
		)
		(placement
			(enabled no)
			(sheetname "")
		)
		(fill
			(thermal_gap 0.5)
			(thermal_bridge_width 0.5)
			(island_removal_mode 0)
		)
		(polygon
			(pts
				(arc
					(start 48.533304 -299.582586)
					(mid 48.529584 -299.591566)
					(end 48.520604 -299.595286)
				)
				(arc
					(start 47.047404 -299.595286)
					(mid 47.038424 -299.591566)
					(end 47.034704 -299.582586)
				)
				(arc
					(start 47.034704 -299.088048)
					(mid 47.038424 -299.079068)
					(end 47.047404 -299.075348)
				)
				(arc
					(start 48.520604 -299.075348)
					(mid 48.529584 -299.079068)
					(end 48.533304 -299.088048)
				)
			)
		)
	)
	(zone
		(layer "In1.Cu")
		(hatch none 0.5)
		(connect_pads
			(clearance 0)
		)
		(min_thickness 0.25)
		(keepout
			(tracks not_allowed)
			(vias allowed)
			(pads allowed)
			(copperpour not_allowed)
			(footprints allowed)
		)
		(placement
			(enabled no)
			(sheetname "")
		)
		(fill
			(thermal_gap 0.5)
			(thermal_bridge_width 0.5)
			(island_removal_mode 0)
		)
		(polygon
			(pts
				(arc
					(start 428.205392 -310.632094)
					(mid 428.201672 -310.641074)
					(end 428.192692 -310.644794)
				)
				(arc
					(start 426.719492 -310.644794)
					(mid 426.710512 -310.641074)
					(end 426.706792 -310.632094)
				)
				(arc
					(start 426.706792 -310.137556)
					(mid 426.710512 -310.128576)
					(end 426.719492 -310.124856)
				)
				(arc
					(start 428.192692 -310.124856)
					(mid 428.201672 -310.128576)
					(end 428.205392 -310.137556)
				)
			)
		)
	)
	(zone
		(layer "In1.Cu")
		(hatch none 0.5)
		(connect_pads
			(clearance 0)
		)
		(min_thickness 0.25)
		(keepout
			(tracks not_allowed)
			(vias allowed)
			(pads allowed)
			(copperpour not_allowed)
			(footprints allowed)
		)
		(placement
			(enabled no)
			(sheetname "")
		)
		(fill
			(thermal_gap 0.5)
			(thermal_bridge_width 0.5)
			(island_removal_mode 0)
		)
		(polygon
			(pts
				(arc
					(start 184.365392 -306.38242)
					(mid 184.361672 -306.3914)
					(end 184.352692 -306.39512)
				)
				(arc
					(start 182.879492 -306.39512)
					(mid 182.870512 -306.3914)
					(end 182.866792 -306.38242)
				)
				(arc
					(start 182.866792 -305.887882)
					(mid 182.870512 -305.878902)
					(end 182.879492 -305.875182)
				)
				(arc
					(start 184.352692 -305.875182)
					(mid 184.361672 -305.878902)
					(end 184.365392 -305.887882)
				)
			)
		)
	)
	(zone
		(layer "In1.Cu")
		(hatch none 0.5)
		(connect_pads
			(clearance 0)
		)
		(min_thickness 0.25)
		(keepout
			(tracks not_allowed)
			(vias allowed)
			(pads allowed)
			(copperpour not_allowed)
			(footprints allowed)
		)
		(placement
			(enabled no)
			(sheetname "")
		)
		(fill
			(thermal_gap 0.5)
			(thermal_bridge_width 0.5)
			(island_removal_mode 0)
		)
		(polygon
			(pts
				(arc
					(start 413.117284 -296.182288)
					(mid 413.113564 -296.191268)
					(end 413.104584 -296.194988)
				)
				(arc
					(start 411.631384 -296.194988)
					(mid 411.622404 -296.191268)
					(end 411.618684 -296.182288)
				)
				(arc
					(start 411.618684 -295.68775)
					(mid 411.622404 -295.67877)
					(end 411.631384 -295.67505)
				)
				(arc
					(start 413.104584 -295.67505)
					(mid 413.113564 -295.67877)
					(end 413.117284 -295.68775)
				)
			)
		)
	)
	(zone
		(layer "In1.Cu")
		(hatch none 0.5)
		(connect_pads
			(clearance 0)
		)
		(min_thickness 0.25)
		(keepout
			(tracks not_allowed)
			(vias allowed)
			(pads allowed)
			(copperpour not_allowed)
			(footprints allowed)
		)
		(placement
			(enabled no)
			(sheetname "")
		)
		(fill
			(thermal_gap 0.5)
			(thermal_bridge_width 0.5)
			(island_removal_mode 0)
		)
		(polygon
			(pts
				(arc
					(start 304.017426 -314.882276)
					(mid 304.013706 -314.891256)
					(end 304.004726 -314.894976)
				)
				(arc
					(start 302.531526 -314.894976)
					(mid 302.522546 -314.891256)
					(end 302.518826 -314.882276)
				)
				(arc
					(start 302.518826 -314.387738)
					(mid 302.522546 -314.378758)
					(end 302.531526 -314.375038)
				)
				(arc
					(start 304.004726 -314.375038)
					(mid 304.013706 -314.378758)
					(end 304.017426 -314.387738)
				)
			)
		)
	)
	(zone
		(layer "In1.Cu")
		(hatch none 0.5)
		(connect_pads
			(clearance 0)
		)
		(min_thickness 0.25)
		(keepout
			(tracks not_allowed)
			(vias allowed)
			(pads allowed)
			(copperpour not_allowed)
			(footprints allowed)
		)
		(placement
			(enabled no)
			(sheetname "")
		)
		(fill
			(thermal_gap 0.5)
			(thermal_bridge_width 0.5)
			(island_removal_mode 0)
		)
		(polygon
			(pts
				(arc
					(start 90.898218 -390.761474)
					(mid 90.593418 -390.761474)
					(end 90.898218 -390.761474)
				)
			)
		)
	)
	(zone
		(layer "In1.Cu")
		(hatch none 0.5)
		(connect_pads
			(clearance 0)
		)
		(min_thickness 0.25)
		(keepout
			(tracks not_allowed)
			(vias allowed)
			(pads allowed)
			(copperpour not_allowed)
			(footprints allowed)
		)
		(placement
			(enabled no)
			(sheetname "")
		)
		(fill
			(thermal_gap 0.5)
			(thermal_bridge_width 0.5)
			(island_removal_mode 0)
		)
		(polygon
			(pts
				(arc
					(start 157.88894 -385.31038)
					(mid 157.50794 -385.31038)
					(end 157.88894 -385.31038)
				)
			)
		)
	)
	(zone
		(layer "In1.Cu")
		(hatch none 0.5)
		(connect_pads
			(clearance 0)
		)
		(min_thickness 0.25)
		(keepout
			(tracks not_allowed)
			(vias allowed)
			(pads allowed)
			(copperpour not_allowed)
			(footprints allowed)
		)
		(placement
			(enabled no)
			(sheetname "")
		)
		(fill
			(thermal_gap 0.5)
			(thermal_bridge_width 0.5)
			(island_removal_mode 0)
		)
		(polygon
			(pts
				(arc
					(start 199.4535 -269.832582)
					(mid 199.44978 -269.841562)
					(end 199.4408 -269.845282)
				)
				(arc
					(start 197.9676 -269.845282)
					(mid 197.95862 -269.841562)
					(end 197.9549 -269.832582)
				)
				(arc
					(start 197.9549 -269.338044)
					(mid 197.95862 -269.329064)
					(end 197.9676 -269.325344)
				)
				(arc
					(start 199.4408 -269.325344)
					(mid 199.44978 -269.329064)
					(end 199.4535 -269.338044)
				)
			)
		)
	)
	(zone
		(layer "In1.Cu")
		(hatch none 0.5)
		(connect_pads
			(clearance 0)
		)
		(min_thickness 0.25)
		(keepout
			(tracks not_allowed)
			(vias allowed)
			(pads allowed)
			(copperpour not_allowed)
			(footprints allowed)
		)
		(placement
			(enabled no)
			(sheetname "")
		)
		(fill
			(thermal_gap 0.5)
			(thermal_bridge_width 0.5)
			(island_removal_mode 0)
		)
		(polygon
			(pts
				(arc
					(start 184.365392 -197.582536)
					(mid 184.361672 -197.591516)
					(end 184.352692 -197.595236)
				)
				(arc
					(start 182.879492 -197.595236)
					(mid 182.870512 -197.591516)
					(end 182.866792 -197.582536)
				)
				(arc
					(start 182.866792 -197.087998)
					(mid 182.870512 -197.079018)
					(end 182.879492 -197.075298)
				)
				(arc
					(start 184.352692 -197.075298)
					(mid 184.361672 -197.079018)
					(end 184.365392 -197.087998)
				)
			)
		)
	)
	(zone
		(layer "In1.Cu")
		(hatch none 0.5)
		(connect_pads
			(clearance 0)
		)
		(min_thickness 0.25)
		(keepout
			(tracks not_allowed)
			(vias allowed)
			(pads allowed)
			(copperpour not_allowed)
			(footprints allowed)
		)
		(placement
			(enabled no)
			(sheetname "")
		)
		(fill
			(thermal_gap 0.5)
			(thermal_bridge_width 0.5)
			(island_removal_mode 0)
		)
		(polygon
			(pts
				(arc
					(start 169.277284 -234.982512)
					(mid 169.273564 -234.991492)
					(end 169.264584 -234.995212)
				)
				(arc
					(start 167.791384 -234.995212)
					(mid 167.782404 -234.991492)
					(end 167.778684 -234.982512)
				)
				(arc
					(start 167.778684 -234.487974)
					(mid 167.782404 -234.478994)
					(end 167.791384 -234.475274)
				)
				(arc
					(start 169.264584 -234.475274)
					(mid 169.273564 -234.478994)
					(end 169.277284 -234.487974)
				)
			)
		)
	)
	(zone
		(layer "In1.Cu")
		(hatch none 0.5)
		(connect_pads
			(clearance 0)
		)
		(min_thickness 0.25)
		(keepout
			(tracks not_allowed)
			(vias allowed)
			(pads allowed)
			(copperpour not_allowed)
			(footprints allowed)
		)
		(placement
			(enabled no)
			(sheetname "")
		)
		(fill
			(thermal_gap 0.5)
			(thermal_bridge_width 0.5)
			(island_removal_mode 0)
		)
		(polygon
			(pts
				(arc
					(start 176.821338 -236.682534)
					(mid 176.817618 -236.691514)
					(end 176.808638 -236.695234)
				)
				(arc
					(start 175.335438 -236.695234)
					(mid 175.326458 -236.691514)
					(end 175.322738 -236.682534)
				)
				(arc
					(start 175.322738 -236.187996)
					(mid 175.326458 -236.179016)
					(end 175.335438 -236.175296)
				)
				(arc
					(start 176.808638 -236.175296)
					(mid 176.817618 -236.179016)
					(end 176.821338 -236.187996)
				)
			)
		)
	)
	(zone
		(layer "In1.Cu")
		(hatch none 0.5)
		(connect_pads
			(clearance 0)
		)
		(min_thickness 0.25)
		(keepout
			(tracks not_allowed)
			(vias allowed)
			(pads allowed)
			(copperpour not_allowed)
			(footprints allowed)
		)
		(placement
			(enabled no)
			(sheetname "")
		)
		(fill
			(thermal_gap 0.5)
			(thermal_bridge_width 0.5)
			(island_removal_mode 0)
		)
		(polygon
			(pts
				(arc
					(start 381.361188 -393.69238)
					(mid 380.980188 -393.69238)
					(end 381.361188 -393.69238)
				)
			)
		)
	)
	(zone
		(layer "In1.Cu")
		(hatch none 0.5)
		(connect_pads
			(clearance 0)
		)
		(min_thickness 0.25)
		(keepout
			(tracks not_allowed)
			(vias allowed)
			(pads allowed)
			(copperpour not_allowed)
			(footprints allowed)
		)
		(placement
			(enabled no)
			(sheetname "")
		)
		(fill
			(thermal_gap 0.5)
			(thermal_bridge_width 0.5)
			(island_removal_mode 0)
		)
		(polygon
			(pts
				(arc
					(start 18.357342 -230.732584)
					(mid 18.353622 -230.741564)
					(end 18.344642 -230.745284)
				)
				(arc
					(start 16.871442 -230.745284)
					(mid 16.862462 -230.741564)
					(end 16.858742 -230.732584)
				)
				(arc
					(start 16.858742 -230.238046)
					(mid 16.862462 -230.229066)
					(end 16.871442 -230.225346)
				)
				(arc
					(start 18.344642 -230.225346)
					(mid 18.353622 -230.229066)
					(end 18.357342 -230.238046)
				)
			)
		)
	)
	(zone
		(layer "In1.Cu")
		(hatch none 0.5)
		(connect_pads
			(clearance 0)
		)
		(min_thickness 0.25)
		(keepout
			(tracks not_allowed)
			(vias allowed)
			(pads allowed)
			(copperpour not_allowed)
			(footprints allowed)
		)
		(placement
			(enabled no)
			(sheetname "")
		)
		(fill
			(thermal_gap 0.5)
			(thermal_bridge_width 0.5)
			(island_removal_mode 0)
		)
		(polygon
			(pts
				(arc
					(start 18.357342 -206.082392)
					(mid 18.353622 -206.091372)
					(end 18.344642 -206.095092)
				)
				(arc
					(start 16.871442 -206.095092)
					(mid 16.862462 -206.091372)
					(end 16.858742 -206.082392)
				)
				(arc
					(start 16.858742 -205.587854)
					(mid 16.862462 -205.578874)
					(end 16.871442 -205.575154)
				)
				(arc
					(start 18.344642 -205.575154)
					(mid 18.353622 -205.578874)
					(end 18.357342 -205.587854)
				)
			)
		)
	)
	(zone
		(layer "In1.Cu")
		(hatch none 0.5)
		(connect_pads
			(clearance 0)
		)
		(min_thickness 0.25)
		(keepout
			(tracks not_allowed)
			(vias allowed)
			(pads allowed)
			(copperpour not_allowed)
			(footprints allowed)
		)
		(placement
			(enabled no)
			(sheetname "")
		)
		(fill
			(thermal_gap 0.5)
			(thermal_bridge_width 0.5)
			(island_removal_mode 0)
		)
		(polygon
			(pts
				(arc
					(start 176.821338 -216.282524)
					(mid 176.817618 -216.291504)
					(end 176.808638 -216.295224)
				)
				(arc
					(start 175.335438 -216.295224)
					(mid 175.326458 -216.291504)
					(end 175.322738 -216.282524)
				)
				(arc
					(start 175.322738 -215.787986)
					(mid 175.326458 -215.779006)
					(end 175.335438 -215.775286)
				)
				(arc
					(start 176.808638 -215.775286)
					(mid 176.817618 -215.779006)
					(end 176.821338 -215.787986)
				)
			)
		)
	)
	(zone
		(layer "In1.Cu")
		(hatch none 0.5)
		(connect_pads
			(clearance 0)
		)
		(min_thickness 0.25)
		(keepout
			(tracks not_allowed)
			(vias allowed)
			(pads allowed)
			(copperpour not_allowed)
			(footprints allowed)
		)
		(placement
			(enabled no)
			(sheetname "")
		)
		(fill
			(thermal_gap 0.5)
			(thermal_bridge_width 0.5)
			(island_removal_mode 0)
		)
		(polygon
			(pts
				(arc
					(start 317.970154 -392.30427)
					(mid 317.665354 -392.30427)
					(end 317.970154 -392.30427)
				)
			)
		)
	)
	(zone
		(layer "In1.Cu")
		(hatch none 0.5)
		(connect_pads
			(clearance 0)
		)
		(min_thickness 0.25)
		(keepout
			(tracks not_allowed)
			(vias allowed)
			(pads allowed)
			(copperpour not_allowed)
			(footprints allowed)
		)
		(placement
			(enabled no)
			(sheetname "")
		)
		(fill
			(thermal_gap 0.5)
			(thermal_bridge_width 0.5)
			(island_removal_mode 0)
		)
		(polygon
			(pts
				(arc
					(start 60.177426 -249.432572)
					(mid 60.173706 -249.441552)
					(end 60.164726 -249.445272)
				)
				(arc
					(start 58.691526 -249.445272)
					(mid 58.682546 -249.441552)
					(end 58.678826 -249.432572)
				)
				(arc
					(start 58.678826 -248.938034)
					(mid 58.682546 -248.929054)
					(end 58.691526 -248.925334)
				)
				(arc
					(start 60.164726 -248.925334)
					(mid 60.173706 -248.929054)
					(end 60.177426 -248.938034)
				)
			)
		)
	)
	(zone
		(layer "In1.Cu")
		(hatch none 0.5)
		(connect_pads
			(clearance 0)
		)
		(min_thickness 0.25)
		(keepout
			(tracks not_allowed)
			(vias allowed)
			(pads allowed)
			(copperpour not_allowed)
			(footprints allowed)
		)
		(placement
			(enabled no)
			(sheetname "")
		)
		(fill
			(thermal_gap 0.5)
			(thermal_bridge_width 0.5)
			(island_removal_mode 0)
		)
		(polygon
			(pts
				(arc
					(start 409.089098 -393.69238)
					(mid 408.708098 -393.69238)
					(end 409.089098 -393.69238)
				)
			)
		)
	)
	(zone
		(layer "In1.Cu")
		(hatch none 0.5)
		(connect_pads
			(clearance 0)
		)
		(min_thickness 0.25)
		(keepout
			(tracks not_allowed)
			(vias allowed)
			(pads allowed)
			(copperpour not_allowed)
			(footprints allowed)
		)
		(placement
			(enabled no)
			(sheetname "")
		)
		(fill
			(thermal_gap 0.5)
			(thermal_bridge_width 0.5)
			(island_removal_mode 0)
		)
		(polygon
			(pts
				(arc
					(start 22.45741 -270.682466)
					(mid 22.45369 -270.691446)
					(end 22.44471 -270.695166)
				)
				(arc
					(start 20.97151 -270.695166)
					(mid 20.96253 -270.691446)
					(end 20.95881 -270.682466)
				)
				(arc
					(start 20.95881 -270.187928)
					(mid 20.96253 -270.178948)
					(end 20.97151 -270.175228)
				)
				(arc
					(start 22.44471 -270.175228)
					(mid 22.45369 -270.178948)
					(end 22.45741 -270.187928)
				)
			)
		)
	)
	(zone
		(layer "In1.Cu")
		(hatch none 0.5)
		(connect_pads
			(clearance 0)
		)
		(min_thickness 0.25)
		(keepout
			(tracks not_allowed)
			(vias allowed)
			(pads allowed)
			(copperpour not_allowed)
			(footprints allowed)
		)
		(placement
			(enabled no)
			(sheetname "")
		)
		(fill
			(thermal_gap 0.5)
			(thermal_bridge_width 0.5)
			(island_removal_mode 0)
		)
		(polygon
			(pts
				(arc
					(start 45.089318 -311.482486)
					(mid 45.085598 -311.491466)
					(end 45.076618 -311.495186)
				)
				(arc
					(start 43.603418 -311.495186)
					(mid 43.594438 -311.491466)
					(end 43.590718 -311.482486)
				)
				(arc
					(start 43.590718 -310.987948)
					(mid 43.594438 -310.978968)
					(end 43.603418 -310.975248)
				)
				(arc
					(start 45.076618 -310.975248)
					(mid 45.085598 -310.978968)
					(end 45.089318 -310.987948)
				)
			)
		)
	)
	(zone
		(layer "In1.Cu")
		(hatch none 0.5)
		(connect_pads
			(clearance 0)
		)
		(min_thickness 0.25)
		(keepout
			(tracks not_allowed)
			(vias allowed)
			(pads allowed)
			(copperpour not_allowed)
			(footprints allowed)
		)
		(placement
			(enabled no)
			(sheetname "")
		)
		(fill
			(thermal_gap 0.5)
			(thermal_bridge_width 0.5)
			(island_removal_mode 0)
		)
		(polygon
			(pts
				(arc
					(start 60.177426 -197.582536)
					(mid 60.173706 -197.591516)
					(end 60.164726 -197.595236)
				)
				(arc
					(start 58.691526 -197.595236)
					(mid 58.682546 -197.591516)
					(end 58.678826 -197.582536)
				)
				(arc
					(start 58.678826 -197.087998)
					(mid 58.682546 -197.079018)
					(end 58.691526 -197.075298)
				)
				(arc
					(start 60.164726 -197.075298)
					(mid 60.173706 -197.079018)
					(end 60.177426 -197.087998)
				)
			)
		)
	)
	(zone
		(layer "In1.Cu")
		(hatch none 0.5)
		(connect_pads
			(clearance 0)
		)
		(min_thickness 0.25)
		(keepout
			(tracks not_allowed)
			(vias allowed)
			(pads allowed)
			(copperpour not_allowed)
			(footprints allowed)
		)
		(placement
			(enabled no)
			(sheetname "")
		)
		(fill
			(thermal_gap 0.5)
			(thermal_bridge_width 0.5)
			(island_removal_mode 0)
		)
		(polygon
			(pts
				(arc
					(start 191.909446 -275.782532)
					(mid 191.905726 -275.791512)
					(end 191.896746 -275.795232)
				)
				(arc
					(start 190.423546 -275.795232)
					(mid 190.414566 -275.791512)
					(end 190.410846 -275.782532)
				)
				(arc
					(start 190.410846 -275.287994)
					(mid 190.414566 -275.279014)
					(end 190.423546 -275.275294)
				)
				(arc
					(start 191.896746 -275.275294)
					(mid 191.905726 -275.279014)
					(end 191.909446 -275.287994)
				)
			)
		)
	)
	(zone
		(layer "In1.Cu")
		(hatch none 0.5)
		(connect_pads
			(clearance 0)
		)
		(min_thickness 0.25)
		(keepout
			(tracks not_allowed)
			(vias allowed)
			(pads allowed)
			(copperpour not_allowed)
			(footprints allowed)
		)
		(placement
			(enabled no)
			(sheetname "")
		)
		(fill
			(thermal_gap 0.5)
			(thermal_bridge_width 0.5)
			(island_removal_mode 0)
		)
		(polygon
			(pts
				(arc
					(start 435.749446 -293.632128)
					(mid 435.745726 -293.641108)
					(end 435.736746 -293.644828)
				)
				(arc
					(start 434.263546 -293.644828)
					(mid 434.254566 -293.641108)
					(end 434.250846 -293.632128)
				)
				(arc
					(start 434.250846 -293.13759)
					(mid 434.254566 -293.12861)
					(end 434.263546 -293.12489)
				)
				(arc
					(start 435.736746 -293.12489)
					(mid 435.745726 -293.12861)
					(end 435.749446 -293.13759)
				)
			)
		)
	)
	(zone
		(layer "In1.Cu")
		(hatch none 0.5)
		(connect_pads
			(clearance 0)
		)
		(min_thickness 0.25)
		(keepout
			(tracks not_allowed)
			(vias allowed)
			(pads allowed)
			(copperpour not_allowed)
			(footprints allowed)
		)
		(placement
			(enabled no)
			(sheetname "")
		)
		(fill
			(thermal_gap 0.5)
			(thermal_bridge_width 0.5)
			(island_removal_mode 0)
		)
		(polygon
			(pts
				(arc
					(start 305.970178 -392.30427)
					(mid 305.665378 -392.30427)
					(end 305.970178 -392.30427)
				)
			)
		)
	)
	(zone
		(layer "In1.Cu")
		(hatch none 0.5)
		(connect_pads
			(clearance 0)
		)
		(min_thickness 0.25)
		(keepout
			(tracks not_allowed)
			(vias allowed)
			(pads allowed)
			(copperpour not_allowed)
			(footprints allowed)
		)
		(placement
			(enabled no)
			(sheetname "")
		)
		(fill
			(thermal_gap 0.5)
			(thermal_bridge_width 0.5)
			(island_removal_mode 0)
		)
		(polygon
			(pts
				(arc
					(start 48.533304 -250.282456)
					(mid 48.529584 -250.291436)
					(end 48.520604 -250.295156)
				)
				(arc
					(start 47.047404 -250.295156)
					(mid 47.038424 -250.291436)
					(end 47.034704 -250.282456)
				)
				(arc
					(start 47.034704 -249.787918)
					(mid 47.038424 -249.778938)
					(end 47.047404 -249.775218)
				)
				(arc
					(start 48.520604 -249.775218)
					(mid 48.529584 -249.778938)
					(end 48.533304 -249.787918)
				)
			)
		)
	)
	(zone
		(layer "In1.Cu")
		(hatch none 0.5)
		(connect_pads
			(clearance 0)
		)
		(min_thickness 0.25)
		(keepout
			(tracks not_allowed)
			(vias allowed)
			(pads allowed)
			(copperpour not_allowed)
			(footprints allowed)
		)
		(placement
			(enabled no)
			(sheetname "")
		)
		(fill
			(thermal_gap 0.5)
			(thermal_bridge_width 0.5)
			(island_removal_mode 0)
		)
		(polygon
			(pts
				(arc
					(start 443.2935 -304.682144)
					(mid 443.28978 -304.691124)
					(end 443.2808 -304.694844)
				)
				(arc
					(start 441.8076 -304.694844)
					(mid 441.79862 -304.691124)
					(end 441.7949 -304.682144)
				)
				(arc
					(start 441.7949 -304.187606)
					(mid 441.79862 -304.178626)
					(end 441.8076 -304.174906)
				)
				(arc
					(start 443.2808 -304.174906)
					(mid 443.28978 -304.178626)
					(end 443.2935 -304.187606)
				)
			)
		)
	)
	(zone
		(layer "In1.Cu")
		(hatch none 0.5)
		(connect_pads
			(clearance 0)
		)
		(min_thickness 0.25)
		(keepout
			(tracks not_allowed)
			(vias allowed)
			(pads allowed)
			(copperpour not_allowed)
			(footprints allowed)
		)
		(placement
			(enabled no)
			(sheetname "")
		)
		(fill
			(thermal_gap 0.5)
			(thermal_bridge_width 0.5)
			(island_removal_mode 0)
		)
		(polygon
			(pts
				(arc
					(start 417.217352 -233.282236)
					(mid 417.213632 -233.291216)
					(end 417.204652 -233.294936)
				)
				(arc
					(start 415.731452 -233.294936)
					(mid 415.722472 -233.291216)
					(end 415.718752 -233.282236)
				)
				(arc
					(start 415.718752 -232.787698)
					(mid 415.722472 -232.778718)
					(end 415.731452 -232.774998)
				)
				(arc
					(start 417.204652 -232.774998)
					(mid 417.213632 -232.778718)
					(end 417.217352 -232.787698)
				)
			)
		)
	)
	(zone
		(layer "In1.Cu")
		(hatch none 0.5)
		(connect_pads
			(clearance 0)
		)
		(min_thickness 0.25)
		(keepout
			(tracks not_allowed)
			(vias allowed)
			(pads allowed)
			(copperpour not_allowed)
			(footprints allowed)
		)
		(placement
			(enabled no)
			(sheetname "")
		)
		(fill
			(thermal_gap 0.5)
			(thermal_bridge_width 0.5)
			(island_removal_mode 0)
		)
		(polygon
			(pts
				(arc
					(start 281.385264 -217.132154)
					(mid 281.381544 -217.141134)
					(end 281.372564 -217.144854)
				)
				(arc
					(start 279.899364 -217.144854)
					(mid 279.890384 -217.141134)
					(end 279.886664 -217.132154)
				)
				(arc
					(start 279.886664 -216.637616)
					(mid 279.890384 -216.628636)
					(end 279.899364 -216.624916)
				)
				(arc
					(start 281.372564 -216.624916)
					(mid 281.381544 -216.628636)
					(end 281.385264 -216.637616)
				)
			)
		)
	)
	(zone
		(layer "In1.Cu")
		(hatch none 0.5)
		(connect_pads
			(clearance 0)
		)
		(min_thickness 0.25)
		(keepout
			(tracks not_allowed)
			(vias allowed)
			(pads allowed)
			(copperpour not_allowed)
			(footprints allowed)
		)
		(placement
			(enabled no)
			(sheetname "")
		)
		(fill
			(thermal_gap 0.5)
			(thermal_bridge_width 0.5)
			(island_removal_mode 0)
		)
		(polygon
			(pts
				(arc
					(start 413.117284 -223.082104)
					(mid 413.113564 -223.091084)
					(end 413.104584 -223.094804)
				)
				(arc
					(start 411.631384 -223.094804)
					(mid 411.622404 -223.091084)
					(end 411.618684 -223.082104)
				)
				(arc
					(start 411.618684 -222.587566)
					(mid 411.622404 -222.578586)
					(end 411.631384 -222.574866)
				)
				(arc
					(start 413.104584 -222.574866)
					(mid 413.113564 -222.578586)
					(end 413.117284 -222.587566)
				)
			)
		)
	)
	(zone
		(layer "In1.Cu")
		(hatch none 0.5)
		(connect_pads
			(clearance 0)
		)
		(min_thickness 0.25)
		(keepout
			(tracks not_allowed)
			(vias allowed)
			(pads allowed)
			(copperpour not_allowed)
			(footprints allowed)
		)
		(placement
			(enabled no)
			(sheetname "")
		)
		(fill
			(thermal_gap 0.5)
			(thermal_bridge_width 0.5)
			(island_removal_mode 0)
		)
		(polygon
			(pts
				(arc
					(start 206.9973 -264.732516)
					(mid 206.99358 -264.741496)
					(end 206.9846 -264.745216)
				)
				(arc
					(start 205.5114 -264.745216)
					(mid 205.50242 -264.741496)
					(end 205.4987 -264.732516)
				)
				(arc
					(start 205.4987 -264.237978)
					(mid 205.50242 -264.228998)
					(end 205.5114 -264.225278)
				)
				(arc
					(start 206.9846 -264.225278)
					(mid 206.99358 -264.228998)
					(end 206.9973 -264.237978)
				)
			)
		)
	)
	(zone
		(layer "In1.Cu")
		(hatch none 0.5)
		(connect_pads
			(clearance 0)
		)
		(min_thickness 0.25)
		(keepout
			(tracks not_allowed)
			(vias allowed)
			(pads allowed)
			(copperpour not_allowed)
			(footprints allowed)
		)
		(placement
			(enabled no)
			(sheetname "")
		)
		(fill
			(thermal_gap 0.5)
			(thermal_bridge_width 0.5)
			(island_removal_mode 0)
		)
		(polygon
			(pts
				(arc
					(start 56.077358 -226.482402)
					(mid 56.073638 -226.491382)
					(end 56.064658 -226.495102)
				)
				(arc
					(start 54.591458 -226.495102)
					(mid 54.582478 -226.491382)
					(end 54.578758 -226.482402)
				)
				(arc
					(start 54.578758 -225.987864)
					(mid 54.582478 -225.978884)
					(end 54.591458 -225.975164)
				)
				(arc
					(start 56.064658 -225.975164)
					(mid 56.073638 -225.978884)
					(end 56.077358 -225.987864)
				)
			)
		)
	)
	(zone
		(layer "In1.Cu")
		(hatch none 0.5)
		(connect_pads
			(clearance 0)
		)
		(min_thickness 0.25)
		(keepout
			(tracks not_allowed)
			(vias allowed)
			(pads allowed)
			(copperpour not_allowed)
			(footprints allowed)
		)
		(placement
			(enabled no)
			(sheetname "")
		)
		(fill
			(thermal_gap 0.5)
			(thermal_bridge_width 0.5)
			(island_removal_mode 0)
		)
		(polygon
			(pts
				(arc
					(start 172.72127 -243.482368)
					(mid 172.71755 -243.491348)
					(end 172.70857 -243.495068)
				)
				(arc
					(start 171.23537 -243.495068)
					(mid 171.22639 -243.491348)
					(end 171.22267 -243.482368)
				)
				(arc
					(start 171.22267 -242.98783)
					(mid 171.22639 -242.97885)
					(end 171.23537 -242.97513)
				)
				(arc
					(start 172.70857 -242.97513)
					(mid 172.71755 -242.97885)
					(end 172.72127 -242.98783)
				)
			)
		)
	)
	(zone
		(layer "In1.Cu")
		(hatch none 0.5)
		(connect_pads
			(clearance 0)
		)
		(min_thickness 0.25)
		(keepout
			(tracks not_allowed)
			(vias allowed)
			(pads allowed)
			(copperpour not_allowed)
			(footprints allowed)
		)
		(placement
			(enabled no)
			(sheetname "")
		)
		(fill
			(thermal_gap 0.5)
			(thermal_bridge_width 0.5)
			(island_removal_mode 0)
		)
		(polygon
			(pts
				(arc
					(start 40.98925 -240.082578)
					(mid 40.98553 -240.091558)
					(end 40.97655 -240.095278)
				)
				(arc
					(start 39.50335 -240.095278)
					(mid 39.49437 -240.091558)
					(end 39.49065 -240.082578)
				)
				(arc
					(start 39.49065 -239.58804)
					(mid 39.49437 -239.57906)
					(end 39.50335 -239.57534)
				)
				(arc
					(start 40.97655 -239.57534)
					(mid 40.98553 -239.57906)
					(end 40.98925 -239.58804)
				)
			)
		)
	)
	(zone
		(layer "In1.Cu")
		(hatch none 0.5)
		(connect_pads
			(clearance 0)
		)
		(min_thickness 0.25)
		(keepout
			(tracks not_allowed)
			(vias allowed)
			(pads allowed)
			(copperpour not_allowed)
			(footprints allowed)
		)
		(placement
			(enabled no)
			(sheetname "")
		)
		(fill
			(thermal_gap 0.5)
			(thermal_bridge_width 0.5)
			(island_removal_mode 0)
		)
		(polygon
			(pts
				(arc
					(start 199.4535 -281.732482)
					(mid 199.44978 -281.741462)
					(end 199.4408 -281.745182)
				)
				(arc
					(start 197.9676 -281.745182)
					(mid 197.95862 -281.741462)
					(end 197.9549 -281.732482)
				)
				(arc
					(start 197.9549 -281.237944)
					(mid 197.95862 -281.228964)
					(end 197.9676 -281.225244)
				)
				(arc
					(start 199.4408 -281.225244)
					(mid 199.44978 -281.228964)
					(end 199.4535 -281.237944)
				)
			)
		)
	)
	(zone
		(layer "In1.Cu")
		(hatch none 0.5)
		(connect_pads
			(clearance 0)
		)
		(min_thickness 0.25)
		(keepout
			(tracks not_allowed)
			(vias allowed)
			(pads allowed)
			(copperpour not_allowed)
			(footprints allowed)
		)
		(placement
			(enabled no)
			(sheetname "")
		)
		(fill
			(thermal_gap 0.5)
			(thermal_bridge_width 0.5)
			(island_removal_mode 0)
		)
		(polygon
			(pts
				(arc
					(start 22.45741 -314.032392)
					(mid 22.45369 -314.041372)
					(end 22.44471 -314.045092)
				)
				(arc
					(start 20.97151 -314.045092)
					(mid 20.96253 -314.041372)
					(end 20.95881 -314.032392)
				)
				(arc
					(start 20.95881 -313.537854)
					(mid 20.96253 -313.528874)
					(end 20.97151 -313.525154)
				)
				(arc
					(start 22.44471 -313.525154)
					(mid 22.45369 -313.528874)
					(end 22.45741 -313.537854)
				)
			)
		)
	)
	(zone
		(layer "In1.Cu")
		(hatch none 0.5)
		(connect_pads
			(clearance 0)
		)
		(min_thickness 0.25)
		(keepout
			(tracks not_allowed)
			(vias allowed)
			(pads allowed)
			(copperpour not_allowed)
			(footprints allowed)
		)
		(placement
			(enabled no)
			(sheetname "")
		)
		(fill
			(thermal_gap 0.5)
			(thermal_bridge_width 0.5)
			(island_removal_mode 0)
		)
		(polygon
			(pts
				(arc
					(start 60.618116 -383.76987)
					(mid 60.618116 -384.07467)
					(end 60.618116 -383.76987)
				)
			)
		)
	)
	(zone
		(layer "In1.Cu")
		(hatch none 0.5)
		(connect_pads
			(clearance 0)
		)
		(min_thickness 0.25)
		(keepout
			(tracks not_allowed)
			(vias allowed)
			(pads allowed)
			(copperpour not_allowed)
			(footprints allowed)
		)
		(placement
			(enabled no)
			(sheetname "")
		)
		(fill
			(thermal_gap 0.5)
			(thermal_bridge_width 0.5)
			(island_removal_mode 0)
		)
		(polygon
			(pts
				(arc
					(start 277.941532 -283.43225)
					(mid 277.937812 -283.44123)
					(end 277.928832 -283.44495)
				)
				(arc
					(start 276.455632 -283.44495)
					(mid 276.446652 -283.44123)
					(end 276.442932 -283.43225)
				)
				(arc
					(start 276.442932 -282.937712)
					(mid 276.446652 -282.928732)
					(end 276.455632 -282.925012)
				)
				(arc
					(start 277.928832 -282.925012)
					(mid 277.937812 -282.928732)
					(end 277.941532 -282.937712)
				)
			)
		)
	)
	(zone
		(layer "In1.Cu")
		(hatch none 0.5)
		(connect_pads
			(clearance 0)
		)
		(min_thickness 0.25)
		(keepout
			(tracks not_allowed)
			(vias allowed)
			(pads allowed)
			(copperpour not_allowed)
			(footprints allowed)
		)
		(placement
			(enabled no)
			(sheetname "")
		)
		(fill
			(thermal_gap 0.5)
			(thermal_bridge_width 0.5)
			(island_removal_mode 0)
		)
		(polygon
			(pts
				(arc
					(start 137.355326 -15.90294)
					(mid 137.377644 -15.849058)
					(end 137.431526 -15.82674)
				)
				(arc
					(start 138.260074 -15.82674)
					(mid 138.313956 -15.849058)
					(end 138.336274 -15.90294)
				)
				(arc
					(start 138.336274 -17.19834)
					(mid 138.313956 -17.252222)
					(end 138.260074 -17.27454)
				)
				(arc
					(start 137.431526 -17.27454)
					(mid 137.377644 -17.252222)
					(end 137.355326 -17.19834)
				)
			)
		)
	)
	(zone
		(layer "In1.Cu")
		(hatch none 0.5)
		(connect_pads
			(clearance 0)
		)
		(min_thickness 0.25)
		(keepout
			(tracks not_allowed)
			(vias allowed)
			(pads allowed)
			(copperpour not_allowed)
			(footprints allowed)
		)
		(placement
			(enabled no)
			(sheetname "")
		)
		(fill
			(thermal_gap 0.5)
			(thermal_bridge_width 0.5)
			(island_removal_mode 0)
		)
		(polygon
			(pts
				(arc
					(start 187.809378 -218.83243)
					(mid 187.805658 -218.84141)
					(end 187.796678 -218.84513)
				)
				(arc
					(start 186.323478 -218.84513)
					(mid 186.314498 -218.84141)
					(end 186.310778 -218.83243)
				)
				(arc
					(start 186.310778 -218.337892)
					(mid 186.314498 -218.328912)
					(end 186.323478 -218.325192)
				)
				(arc
					(start 187.796678 -218.325192)
					(mid 187.805658 -218.328912)
					(end 187.809378 -218.337892)
				)
			)
		)
	)
	(zone
		(layer "In1.Cu")
		(hatch none 0.5)
		(connect_pads
			(clearance 0)
		)
		(min_thickness 0.25)
		(keepout
			(tracks not_allowed)
			(vias allowed)
			(pads allowed)
			(copperpour not_allowed)
			(footprints allowed)
		)
		(placement
			(enabled no)
			(sheetname "")
		)
		(fill
			(thermal_gap 0.5)
			(thermal_bridge_width 0.5)
			(island_removal_mode 0)
		)
		(polygon
			(pts
				(arc
					(start 184.365392 -210.332574)
					(mid 184.361672 -210.341554)
					(end 184.352692 -210.345274)
				)
				(arc
					(start 182.879492 -210.345274)
					(mid 182.870512 -210.341554)
					(end 182.866792 -210.332574)
				)
				(arc
					(start 182.866792 -209.838036)
					(mid 182.870512 -209.829056)
					(end 182.879492 -209.825336)
				)
				(arc
					(start 184.352692 -209.825336)
					(mid 184.361672 -209.829056)
					(end 184.365392 -209.838036)
				)
			)
		)
	)
	(zone
		(layer "In1.Cu")
		(hatch none 0.5)
		(connect_pads
			(clearance 0)
		)
		(min_thickness 0.25)
		(keepout
			(tracks not_allowed)
			(vias allowed)
			(pads allowed)
			(copperpour not_allowed)
			(footprints allowed)
		)
		(placement
			(enabled no)
			(sheetname "")
		)
		(fill
			(thermal_gap 0.5)
			(thermal_bridge_width 0.5)
			(island_removal_mode 0)
		)
		(polygon
			(pts
				(arc
					(start 37.545264 -210.332574)
					(mid 37.541544 -210.341554)
					(end 37.532564 -210.345274)
				)
				(arc
					(start 36.059364 -210.345274)
					(mid 36.050384 -210.341554)
					(end 36.046664 -210.332574)
				)
				(arc
					(start 36.046664 -209.838036)
					(mid 36.050384 -209.829056)
					(end 36.059364 -209.825336)
				)
				(arc
					(start 37.532564 -209.825336)
					(mid 37.541544 -209.829056)
					(end 37.545264 -209.838036)
				)
			)
		)
	)
	(zone
		(layer "In1.Cu")
		(hatch none 0.5)
		(connect_pads
			(clearance 0)
		)
		(min_thickness 0.25)
		(keepout
			(tracks not_allowed)
			(vias allowed)
			(pads allowed)
			(copperpour not_allowed)
			(footprints allowed)
		)
		(placement
			(enabled no)
			(sheetname "")
		)
		(fill
			(thermal_gap 0.5)
			(thermal_bridge_width 0.5)
			(island_removal_mode 0)
		)
		(polygon
			(pts
				(arc
					(start 97.518728 -391.319258)
					(mid 97.645728 -391.446258)
					(end 97.772728 -391.319258)
				)
				(arc
					(start 97.772728 -391.243058)
					(mid 97.645728 -391.116058)
					(end 97.518728 -391.243058)
				)
			)
		)
	)
	(zone
		(layer "In1.Cu")
		(hatch none 0.5)
		(connect_pads
			(clearance 0)
		)
		(min_thickness 0.25)
		(keepout
			(tracks not_allowed)
			(vias allowed)
			(pads allowed)
			(copperpour not_allowed)
			(footprints allowed)
		)
		(placement
			(enabled no)
			(sheetname "")
		)
		(fill
			(thermal_gap 0.5)
			(thermal_bridge_width 0.5)
			(island_removal_mode 0)
		)
		(polygon
			(pts
				(arc
					(start 25.901396 -237.532418)
					(mid 25.897676 -237.541398)
					(end 25.888696 -237.545118)
				)
				(arc
					(start 24.415496 -237.545118)
					(mid 24.406516 -237.541398)
					(end 24.402796 -237.532418)
				)
				(arc
					(start 24.402796 -237.03788)
					(mid 24.406516 -237.0289)
					(end 24.415496 -237.02518)
				)
				(arc
					(start 25.888696 -237.02518)
					(mid 25.897676 -237.0289)
					(end 25.901396 -237.03788)
				)
			)
		)
	)
	(zone
		(layer "In1.Cu")
		(hatch none 0.5)
		(connect_pads
			(clearance 0)
		)
		(min_thickness 0.25)
		(keepout
			(tracks not_allowed)
			(vias allowed)
			(pads allowed)
			(copperpour not_allowed)
			(footprints allowed)
		)
		(placement
			(enabled no)
			(sheetname "")
		)
		(fill
			(thermal_gap 0.5)
			(thermal_bridge_width 0.5)
			(island_removal_mode 0)
		)
		(polygon
			(pts
				(arc
					(start 152.618694 -383.440686)
					(mid 152.745694 -383.567686)
					(end 152.872694 -383.440686)
				)
				(arc
					(start 152.872694 -383.364486)
					(mid 152.745694 -383.237486)
					(end 152.618694 -383.364486)
				)
			)
		)
	)
	(zone
		(layer "In1.Cu")
		(hatch none 0.5)
		(connect_pads
			(clearance 0)
		)
		(min_thickness 0.25)
		(keepout
			(tracks not_allowed)
			(vias allowed)
			(pads allowed)
			(copperpour not_allowed)
			(footprints allowed)
		)
		(placement
			(enabled no)
			(sheetname "")
		)
		(fill
			(thermal_gap 0.5)
			(thermal_bridge_width 0.5)
			(island_removal_mode 0)
		)
		(polygon
			(pts
				(arc
					(start 413.117284 -318.28232)
					(mid 413.113564 -318.2913)
					(end 413.104584 -318.29502)
				)
				(arc
					(start 411.631384 -318.29502)
					(mid 411.622404 -318.2913)
					(end 411.618684 -318.28232)
				)
				(arc
					(start 411.618684 -317.787782)
					(mid 411.622404 -317.778802)
					(end 411.631384 -317.775082)
				)
				(arc
					(start 413.104584 -317.775082)
					(mid 413.113564 -317.778802)
					(end 413.117284 -317.787782)
				)
			)
		)
	)
	(zone
		(layer "In1.Cu")
		(hatch none 0.5)
		(connect_pads
			(clearance 0)
		)
		(min_thickness 0.25)
		(keepout
			(tracks not_allowed)
			(vias allowed)
			(pads allowed)
			(copperpour not_allowed)
			(footprints allowed)
		)
		(placement
			(enabled no)
			(sheetname "")
		)
		(fill
			(thermal_gap 0.5)
			(thermal_bridge_width 0.5)
			(island_removal_mode 0)
		)
		(polygon
			(pts
				(arc
					(start 60.177426 -309.782464)
					(mid 60.173706 -309.791444)
					(end 60.164726 -309.795164)
				)
				(arc
					(start 58.691526 -309.795164)
					(mid 58.682546 -309.791444)
					(end 58.678826 -309.782464)
				)
				(arc
					(start 58.678826 -309.287926)
					(mid 58.682546 -309.278946)
					(end 58.691526 -309.275226)
				)
				(arc
					(start 60.164726 -309.275226)
					(mid 60.173706 -309.278946)
					(end 60.177426 -309.287926)
				)
			)
		)
	)
	(zone
		(layer "In1.Cu")
		(hatch none 0.5)
		(connect_pads
			(clearance 0)
		)
		(min_thickness 0.25)
		(keepout
			(tracks not_allowed)
			(vias allowed)
			(pads allowed)
			(copperpour not_allowed)
			(footprints allowed)
		)
		(placement
			(enabled no)
			(sheetname "")
		)
		(fill
			(thermal_gap 0.5)
			(thermal_bridge_width 0.5)
			(island_removal_mode 0)
		)
		(polygon
			(pts
				(arc
					(start 288.929318 -310.632094)
					(mid 288.925598 -310.641074)
					(end 288.916618 -310.644794)
				)
				(arc
					(start 287.443418 -310.644794)
					(mid 287.434438 -310.641074)
					(end 287.430718 -310.632094)
				)
				(arc
					(start 287.430718 -310.137556)
					(mid 287.434438 -310.128576)
					(end 287.443418 -310.124856)
				)
				(arc
					(start 288.916618 -310.124856)
					(mid 288.925598 -310.128576)
					(end 288.929318 -310.137556)
				)
			)
		)
	)
	(zone
		(layer "In1.Cu")
		(hatch none 0.5)
		(connect_pads
			(clearance 0)
		)
		(min_thickness 0.25)
		(keepout
			(tracks not_allowed)
			(vias allowed)
			(pads allowed)
			(copperpour not_allowed)
			(footprints allowed)
		)
		(placement
			(enabled no)
			(sheetname "")
		)
		(fill
			(thermal_gap 0.5)
			(thermal_bridge_width 0.5)
			(island_removal_mode 0)
		)
		(polygon
			(pts
				(arc
					(start 12.521692 -16.036036)
					(mid 12.46781 -16.013718)
					(end 12.445492 -15.959836)
				)
				(arc
					(start 12.445492 -14.685518)
					(mid 12.46781 -14.631636)
					(end 12.521692 -14.609318)
				)
				(arc
					(start 13.029946 -14.609318)
					(mid 13.083828 -14.631636)
					(end 13.106146 -14.685518)
				)
				(arc
					(start 13.106146 -15.959836)
					(mid 13.083828 -16.013718)
					(end 13.029946 -16.036036)
				)
			)
		)
	)
	(zone
		(layer "In1.Cu")
		(hatch none 0.5)
		(connect_pads
			(clearance 0)
		)
		(min_thickness 0.25)
		(keepout
			(tracks not_allowed)
			(vias allowed)
			(pads allowed)
			(copperpour not_allowed)
			(footprints allowed)
		)
		(placement
			(enabled no)
			(sheetname "")
		)
		(fill
			(thermal_gap 0.5)
			(thermal_bridge_width 0.5)
			(island_removal_mode 0)
		)
		(polygon
			(pts
				(arc
					(start 57.17032 -383.92227)
					(mid 56.86552 -383.92227)
					(end 57.17032 -383.92227)
				)
			)
		)
	)
	(zone
		(layer "In1.Cu")
		(hatch none 0.5)
		(connect_pads
			(clearance 0)
		)
		(min_thickness 0.25)
		(keepout
			(tracks not_allowed)
			(vias allowed)
			(pads allowed)
			(copperpour not_allowed)
			(footprints allowed)
		)
		(placement
			(enabled no)
			(sheetname "")
		)
		(fill
			(thermal_gap 0.5)
			(thermal_bridge_width 0.5)
			(island_removal_mode 0)
		)
		(polygon
			(pts
				(arc
					(start 288.929318 -307.232304)
					(mid 288.925598 -307.241284)
					(end 288.916618 -307.245004)
				)
				(arc
					(start 287.443418 -307.245004)
					(mid 287.434438 -307.241284)
					(end 287.430718 -307.232304)
				)
				(arc
					(start 287.430718 -306.737766)
					(mid 287.434438 -306.728786)
					(end 287.443418 -306.725066)
				)
				(arc
					(start 288.916618 -306.725066)
					(mid 288.925598 -306.728786)
					(end 288.929318 -306.737766)
				)
			)
		)
	)
	(zone
		(layer "In1.Cu")
		(hatch none 0.5)
		(connect_pads
			(clearance 0)
		)
		(min_thickness 0.25)
		(keepout
			(tracks not_allowed)
			(vias allowed)
			(pads allowed)
			(copperpour not_allowed)
			(footprints allowed)
		)
		(placement
			(enabled no)
			(sheetname "")
		)
		(fill
			(thermal_gap 0.5)
			(thermal_bridge_width 0.5)
			(island_removal_mode 0)
		)
		(polygon
			(pts
				(arc
					(start 315.461142 -397.156432)
					(mid 315.080142 -397.156432)
					(end 315.461142 -397.156432)
				)
			)
		)
	)
	(zone
		(layer "In1.Cu")
		(hatch none 0.5)
		(connect_pads
			(clearance 0)
		)
		(min_thickness 0.25)
		(keepout
			(tracks not_allowed)
			(vias allowed)
			(pads allowed)
			(copperpour not_allowed)
			(footprints allowed)
		)
		(placement
			(enabled no)
			(sheetname "")
		)
		(fill
			(thermal_gap 0.5)
			(thermal_bridge_width 0.5)
			(island_removal_mode 0)
		)
		(polygon
			(pts
				(arc
					(start 304.017426 -282.582112)
					(mid 304.013706 -282.591092)
					(end 304.004726 -282.594812)
				)
				(arc
					(start 302.531526 -282.594812)
					(mid 302.522546 -282.591092)
					(end 302.518826 -282.582112)
				)
				(arc
					(start 302.518826 -282.087574)
					(mid 302.522546 -282.078594)
					(end 302.531526 -282.074874)
				)
				(arc
					(start 304.004726 -282.074874)
					(mid 304.013706 -282.078594)
					(end 304.017426 -282.087574)
				)
			)
		)
	)
	(zone
		(layer "In1.Cu")
		(hatch none 0.5)
		(connect_pads
			(clearance 0)
		)
		(min_thickness 0.25)
		(keepout
			(tracks not_allowed)
			(vias allowed)
			(pads allowed)
			(copperpour not_allowed)
			(footprints allowed)
		)
		(placement
			(enabled no)
			(sheetname "")
		)
		(fill
			(thermal_gap 0.5)
			(thermal_bridge_width 0.5)
			(island_removal_mode 0)
		)
		(polygon
			(pts
				(arc
					(start 340.788752 -397.156432)
					(mid 340.407752 -397.156432)
					(end 340.788752 -397.156432)
				)
			)
		)
	)
	(zone
		(layer "In1.Cu")
		(hatch none 0.5)
		(connect_pads
			(clearance 0)
		)
		(min_thickness 0.25)
		(keepout
			(tracks not_allowed)
			(vias allowed)
			(pads allowed)
			(copperpour not_allowed)
			(footprints allowed)
		)
		(placement
			(enabled no)
			(sheetname "")
		)
		(fill
			(thermal_gap 0.5)
			(thermal_bridge_width 0.5)
			(island_removal_mode 0)
		)
		(polygon
			(pts
				(arc
					(start 48.533304 -295.332404)
					(mid 48.529584 -295.341384)
					(end 48.520604 -295.345104)
				)
				(arc
					(start 47.047404 -295.345104)
					(mid 47.038424 -295.341384)
					(end 47.034704 -295.332404)
				)
				(arc
					(start 47.034704 -294.837866)
					(mid 47.038424 -294.828886)
					(end 47.047404 -294.825166)
				)
				(arc
					(start 48.520604 -294.825166)
					(mid 48.529584 -294.828886)
					(end 48.533304 -294.837866)
				)
			)
		)
	)
	(zone
		(layer "In1.Cu")
		(hatch none 0.5)
		(connect_pads
			(clearance 0)
		)
		(min_thickness 0.25)
		(keepout
			(tracks not_allowed)
			(vias allowed)
			(pads allowed)
			(copperpour not_allowed)
			(footprints allowed)
		)
		(placement
			(enabled no)
			(sheetname "")
		)
		(fill
			(thermal_gap 0.5)
			(thermal_bridge_width 0.5)
			(island_removal_mode 0)
		)
		(polygon
			(pts
				(arc
					(start 339.118448 -381.824484)
					(mid 339.138372 -381.83372)
					(end 339.160104 -381.83693)
				)
				(arc
					(start 339.354668 -381.83693)
					(mid 339.40855 -381.814612)
					(end 339.430868 -381.76073)
				)
				(arc
					(start 339.430868 -381.07493)
					(mid 339.40855 -381.021048)
					(end 339.354668 -380.99873)
				)
				(arc
					(start 339.160104 -380.99873)
					(mid 339.13836 -381.001898)
					(end 339.118448 -381.011176)
				)
				(arc
					(start 338.822284 -381.203962)
					(mid 338.7806 -381.216184)
					(end 338.738972 -381.203708)
				)
				(arc
					(start 338.445348 -381.011176)
					(mid 338.425424 -381.00194)
					(end 338.403692 -380.99873)
				)
				(arc
					(start 338.209128 -380.99873)
					(mid 338.155246 -381.021048)
					(end 338.132928 -381.07493)
				)
				(arc
					(start 338.132928 -381.76073)
					(mid 338.155246 -381.814612)
					(end 338.209128 -381.83693)
				)
				(arc
					(start 338.404962 -381.83693)
					(mid 338.426706 -381.833762)
					(end 338.446618 -381.824484)
				)
				(arc
					(start 338.740242 -381.631952)
					(mid 338.781898 -381.61955)
					(end 338.823554 -381.631952)
				)
			)
		)
	)
	(zone
		(layer "In1.Cu")
		(hatch none 0.5)
		(connect_pads
			(clearance 0)
		)
		(min_thickness 0.25)
		(keepout
			(tracks not_allowed)
			(vias allowed)
			(pads allowed)
			(copperpour not_allowed)
			(footprints allowed)
		)
		(placement
			(enabled no)
			(sheetname "")
		)
		(fill
			(thermal_gap 0.5)
			(thermal_bridge_width 0.5)
			(island_removal_mode 0)
		)
		(polygon
			(pts
				(arc
					(start 160.288986 -388.774432)
					(mid 159.907986 -388.774432)
					(end 160.288986 -388.774432)
				)
			)
		)
	)
	(zone
		(layer "In1.Cu")
		(hatch none 0.5)
		(connect_pads
			(clearance 0)
		)
		(min_thickness 0.25)
		(keepout
			(tracks not_allowed)
			(vias allowed)
			(pads allowed)
			(copperpour not_allowed)
			(footprints allowed)
		)
		(placement
			(enabled no)
			(sheetname "")
		)
		(fill
			(thermal_gap 0.5)
			(thermal_bridge_width 0.5)
			(island_removal_mode 0)
		)
		(polygon
			(pts
				(arc
					(start 187.809378 -254.532384)
					(mid 187.805658 -254.541364)
					(end 187.796678 -254.545084)
				)
				(arc
					(start 186.323478 -254.545084)
					(mid 186.314498 -254.541364)
					(end 186.310778 -254.532384)
				)
				(arc
					(start 186.310778 -254.037846)
					(mid 186.314498 -254.028866)
					(end 186.323478 -254.025146)
				)
				(arc
					(start 187.796678 -254.025146)
					(mid 187.805658 -254.028866)
					(end 187.809378 -254.037846)
				)
			)
		)
	)
	(zone
		(layer "In1.Cu")
		(hatch none 0.5)
		(connect_pads
			(clearance 0)
		)
		(min_thickness 0.25)
		(keepout
			(tracks not_allowed)
			(vias allowed)
			(pads allowed)
			(copperpour not_allowed)
			(footprints allowed)
		)
		(placement
			(enabled no)
			(sheetname "")
		)
		(fill
			(thermal_gap 0.5)
			(thermal_bridge_width 0.5)
			(island_removal_mode 0)
		)
		(polygon
			(pts
				(arc
					(start 270.397478 -274.082256)
					(mid 270.393758 -274.091236)
					(end 270.384778 -274.094956)
				)
				(arc
					(start 268.911578 -274.094956)
					(mid 268.902598 -274.091236)
					(end 268.898878 -274.082256)
				)
				(arc
					(start 268.898878 -273.587718)
					(mid 268.902598 -273.578738)
					(end 268.911578 -273.575018)
				)
				(arc
					(start 270.384778 -273.575018)
					(mid 270.393758 -273.578738)
					(end 270.397478 -273.587718)
				)
			)
		)
	)
	(zone
		(layer "In1.Cu")
		(hatch none 0.5)
		(connect_pads
			(clearance 0)
		)
		(min_thickness 0.25)
		(keepout
			(tracks not_allowed)
			(vias allowed)
			(pads allowed)
			(copperpour not_allowed)
			(footprints allowed)
		)
		(placement
			(enabled no)
			(sheetname "")
		)
		(fill
			(thermal_gap 0.5)
			(thermal_bridge_width 0.5)
			(island_removal_mode 0)
		)
		(polygon
			(pts
				(arc
					(start 435.749446 -220.532198)
					(mid 435.745726 -220.541178)
					(end 435.736746 -220.544898)
				)
				(arc
					(start 434.263546 -220.544898)
					(mid 434.254566 -220.541178)
					(end 434.250846 -220.532198)
				)
				(arc
					(start 434.250846 -220.03766)
					(mid 434.254566 -220.02868)
					(end 434.263546 -220.02496)
				)
				(arc
					(start 435.736746 -220.02496)
					(mid 435.745726 -220.02868)
					(end 435.749446 -220.03766)
				)
			)
		)
	)
	(zone
		(layer "In1.Cu")
		(hatch none 0.5)
		(connect_pads
			(clearance 0)
		)
		(min_thickness 0.25)
		(keepout
			(tracks not_allowed)
			(vias allowed)
			(pads allowed)
			(copperpour not_allowed)
			(footprints allowed)
		)
		(placement
			(enabled no)
			(sheetname "")
		)
		(fill
			(thermal_gap 0.5)
			(thermal_bridge_width 0.5)
			(island_removal_mode 0)
		)
		(polygon
			(pts
				(arc
					(start 413.117284 -273.232118)
					(mid 413.113564 -273.241098)
					(end 413.104584 -273.244818)
				)
				(arc
					(start 411.631384 -273.244818)
					(mid 411.622404 -273.241098)
					(end 411.618684 -273.232118)
				)
				(arc
					(start 411.618684 -272.73758)
					(mid 411.622404 -272.7286)
					(end 411.631384 -272.72488)
				)
				(arc
					(start 413.104584 -272.72488)
					(mid 413.113564 -272.7286)
					(end 413.117284 -272.73758)
				)
			)
		)
	)
	(zone
		(layer "In1.Cu")
		(hatch none 0.5)
		(connect_pads
			(clearance 0)
		)
		(min_thickness 0.25)
		(keepout
			(tracks not_allowed)
			(vias allowed)
			(pads allowed)
			(copperpour not_allowed)
			(footprints allowed)
		)
		(placement
			(enabled no)
			(sheetname "")
		)
		(fill
			(thermal_gap 0.5)
			(thermal_bridge_width 0.5)
			(island_removal_mode 0)
		)
		(polygon
			(pts
				(arc
					(start 308.117494 -287.682178)
					(mid 308.113774 -287.691158)
					(end 308.104794 -287.694878)
				)
				(arc
					(start 306.631594 -287.694878)
					(mid 306.622614 -287.691158)
					(end 306.618894 -287.682178)
				)
				(arc
					(start 306.618894 -287.18764)
					(mid 306.622614 -287.17866)
					(end 306.631594 -287.17494)
				)
				(arc
					(start 308.104794 -287.17494)
					(mid 308.113774 -287.17866)
					(end 308.117494 -287.18764)
				)
			)
		)
	)
	(zone
		(layer "In1.Cu")
		(hatch none 0.5)
		(connect_pads
			(clearance 0)
		)
		(min_thickness 0.25)
		(keepout
			(tracks not_allowed)
			(vias allowed)
			(pads allowed)
			(copperpour not_allowed)
			(footprints allowed)
		)
		(placement
			(enabled no)
			(sheetname "")
		)
		(fill
			(thermal_gap 0.5)
			(thermal_bridge_width 0.5)
			(island_removal_mode 0)
		)
		(polygon
			(pts
				(arc
					(start 202.897232 -237.532418)
					(mid 202.893512 -237.541398)
					(end 202.884532 -237.545118)
				)
				(arc
					(start 201.411332 -237.545118)
					(mid 201.402352 -237.541398)
					(end 201.398632 -237.532418)
				)
				(arc
					(start 201.398632 -237.03788)
					(mid 201.402352 -237.0289)
					(end 201.411332 -237.02518)
				)
				(arc
					(start 202.884532 -237.02518)
					(mid 202.893512 -237.0289)
					(end 202.897232 -237.03788)
				)
			)
		)
	)
	(zone
		(layer "In1.Cu")
		(hatch none 0.5)
		(connect_pads
			(clearance 0)
		)
		(min_thickness 0.25)
		(keepout
			(tracks not_allowed)
			(vias allowed)
			(pads allowed)
			(copperpour not_allowed)
			(footprints allowed)
		)
		(placement
			(enabled no)
			(sheetname "")
		)
		(fill
			(thermal_gap 0.5)
			(thermal_bridge_width 0.5)
			(island_removal_mode 0)
		)
		(polygon
			(pts
				(arc
					(start 40.98925 -245.18239)
					(mid 40.98553 -245.19137)
					(end 40.97655 -245.19509)
				)
				(arc
					(start 39.50335 -245.19509)
					(mid 39.49437 -245.19137)
					(end 39.49065 -245.18239)
				)
				(arc
					(start 39.49065 -244.687852)
					(mid 39.49437 -244.678872)
					(end 39.50335 -244.675152)
				)
				(arc
					(start 40.97655 -244.675152)
					(mid 40.98553 -244.678872)
					(end 40.98925 -244.687852)
				)
			)
		)
	)
	(zone
		(layer "In1.Cu")
		(hatch none 0.5)
		(connect_pads
			(clearance 0)
		)
		(min_thickness 0.25)
		(keepout
			(tracks not_allowed)
			(vias allowed)
			(pads allowed)
			(copperpour not_allowed)
			(footprints allowed)
		)
		(placement
			(enabled no)
			(sheetname "")
		)
		(fill
			(thermal_gap 0.5)
			(thermal_bridge_width 0.5)
			(island_removal_mode 0)
		)
		(polygon
			(pts
				(arc
					(start 345.925648 -381.824484)
					(mid 345.945572 -381.83372)
					(end 345.967304 -381.83693)
				)
				(arc
					(start 346.161868 -381.83693)
					(mid 346.21575 -381.814612)
					(end 346.238068 -381.76073)
				)
				(arc
					(start 346.238068 -381.07493)
					(mid 346.21575 -381.021048)
					(end 346.161868 -380.99873)
				)
				(arc
					(start 345.967304 -380.99873)
					(mid 345.94556 -381.001898)
					(end 345.925648 -381.011176)
				)
				(arc
					(start 345.629484 -381.203962)
					(mid 345.5878 -381.216184)
					(end 345.546172 -381.203708)
				)
				(arc
					(start 345.252548 -381.011176)
					(mid 345.232624 -381.00194)
					(end 345.210892 -380.99873)
				)
				(arc
					(start 345.016328 -380.99873)
					(mid 344.962446 -381.021048)
					(end 344.940128 -381.07493)
				)
				(arc
					(start 344.940128 -381.76073)
					(mid 344.962446 -381.814612)
					(end 345.016328 -381.83693)
				)
				(arc
					(start 345.212162 -381.83693)
					(mid 345.233906 -381.833762)
					(end 345.253818 -381.824484)
				)
				(arc
					(start 345.547442 -381.631952)
					(mid 345.589098 -381.61955)
					(end 345.630754 -381.631952)
				)
			)
		)
	)
	(zone
		(layer "In1.Cu")
		(hatch none 0.5)
		(connect_pads
			(clearance 0)
		)
		(min_thickness 0.25)
		(keepout
			(tracks not_allowed)
			(vias allowed)
			(pads allowed)
			(copperpour not_allowed)
			(footprints allowed)
		)
		(placement
			(enabled no)
			(sheetname "")
		)
		(fill
			(thermal_gap 0.5)
			(thermal_bridge_width 0.5)
			(island_removal_mode 0)
		)
		(polygon
			(pts
				(arc
					(start 293.029386 -285.982156)
					(mid 293.025666 -285.991136)
					(end 293.016686 -285.994856)
				)
				(arc
					(start 291.543486 -285.994856)
					(mid 291.534506 -285.991136)
					(end 291.530786 -285.982156)
				)
				(arc
					(start 291.530786 -285.487618)
					(mid 291.534506 -285.478638)
					(end 291.543486 -285.474918)
				)
				(arc
					(start 293.016686 -285.474918)
					(mid 293.025666 -285.478638)
					(end 293.029386 -285.487618)
				)
			)
		)
	)
	(zone
		(layer "In1.Cu")
		(hatch none 0.5)
		(connect_pads
			(clearance 0)
		)
		(min_thickness 0.25)
		(keepout
			(tracks not_allowed)
			(vias allowed)
			(pads allowed)
			(copperpour not_allowed)
			(footprints allowed)
		)
		(placement
			(enabled no)
			(sheetname "")
		)
		(fill
			(thermal_gap 0.5)
			(thermal_bridge_width 0.5)
			(island_removal_mode 0)
		)
		(polygon
			(pts
				(arc
					(start 40.98925 -276.632416)
					(mid 40.98553 -276.641396)
					(end 40.97655 -276.645116)
				)
				(arc
					(start 39.50335 -276.645116)
					(mid 39.49437 -276.641396)
					(end 39.49065 -276.632416)
				)
				(arc
					(start 39.49065 -276.137878)
					(mid 39.49437 -276.128898)
					(end 39.50335 -276.125178)
				)
				(arc
					(start 40.97655 -276.125178)
					(mid 40.98553 -276.128898)
					(end 40.98925 -276.137878)
				)
			)
		)
	)
	(zone
		(layer "In1.Cu")
		(hatch none 0.5)
		(connect_pads
			(clearance 0)
		)
		(min_thickness 0.25)
		(keepout
			(tracks not_allowed)
			(vias allowed)
			(pads allowed)
			(copperpour not_allowed)
			(footprints allowed)
		)
		(placement
			(enabled no)
			(sheetname "")
		)
		(fill
			(thermal_gap 0.5)
			(thermal_bridge_width 0.5)
			(island_removal_mode 0)
		)
		(polygon
			(pts
				(arc
					(start 128.961134 -388.774432)
					(mid 128.580134 -388.774432)
					(end 128.961134 -388.774432)
				)
			)
		)
	)
	(zone
		(layer "In1.Cu")
		(hatch none 0.5)
		(connect_pads
			(clearance 0)
		)
		(min_thickness 0.25)
		(keepout
			(tracks not_allowed)
			(vias allowed)
			(pads allowed)
			(copperpour not_allowed)
			(footprints allowed)
		)
		(placement
			(enabled no)
			(sheetname "")
		)
		(fill
			(thermal_gap 0.5)
			(thermal_bridge_width 0.5)
			(island_removal_mode 0)
		)
		(polygon
			(pts
				(arc
					(start 202.897232 -246.882412)
					(mid 202.893512 -246.891392)
					(end 202.884532 -246.895112)
				)
				(arc
					(start 201.411332 -246.895112)
					(mid 201.402352 -246.891392)
					(end 201.398632 -246.882412)
				)
				(arc
					(start 201.398632 -246.387874)
					(mid 201.402352 -246.378894)
					(end 201.411332 -246.375174)
				)
				(arc
					(start 202.884532 -246.375174)
					(mid 202.893512 -246.378894)
					(end 202.897232 -246.387874)
				)
			)
		)
	)
	(zone
		(layer "In1.Cu")
		(hatch none 0.5)
		(connect_pads
			(clearance 0)
		)
		(min_thickness 0.25)
		(keepout
			(tracks not_allowed)
			(vias allowed)
			(pads allowed)
			(copperpour not_allowed)
			(footprints allowed)
		)
		(placement
			(enabled no)
			(sheetname "")
		)
		(fill
			(thermal_gap 0.5)
			(thermal_bridge_width 0.5)
			(island_removal_mode 0)
		)
		(polygon
			(pts
				(arc
					(start 18.357342 -239.23244)
					(mid 18.353622 -239.24142)
					(end 18.344642 -239.24514)
				)
				(arc
					(start 16.871442 -239.24514)
					(mid 16.862462 -239.24142)
					(end 16.858742 -239.23244)
				)
				(arc
					(start 16.858742 -238.737902)
					(mid 16.862462 -238.728922)
					(end 16.871442 -238.725202)
				)
				(arc
					(start 18.344642 -238.725202)
					(mid 18.353622 -238.728922)
					(end 18.357342 -238.737902)
				)
			)
		)
	)
	(zone
		(layer "In1.Cu")
		(hatch none 0.5)
		(connect_pads
			(clearance 0)
		)
		(min_thickness 0.25)
		(keepout
			(tracks not_allowed)
			(vias allowed)
			(pads allowed)
			(copperpour not_allowed)
			(footprints allowed)
		)
		(placement
			(enabled no)
			(sheetname "")
		)
		(fill
			(thermal_gap 0.5)
			(thermal_bridge_width 0.5)
			(island_removal_mode 0)
		)
		(polygon
			(pts
				(arc
					(start 403.818598 -391.822686)
					(mid 403.945598 -391.949686)
					(end 404.072598 -391.822686)
				)
				(arc
					(start 404.072598 -391.746486)
					(mid 403.945598 -391.619486)
					(end 403.818598 -391.746486)
				)
			)
		)
	)
	(zone
		(layer "In1.Cu")
		(hatch none 0.5)
		(connect_pads
			(clearance 0)
		)
		(min_thickness 0.25)
		(keepout
			(tracks not_allowed)
			(vias allowed)
			(pads allowed)
			(copperpour not_allowed)
			(footprints allowed)
		)
		(placement
			(enabled no)
			(sheetname "")
		)
		(fill
			(thermal_gap 0.5)
			(thermal_bridge_width 0.5)
			(island_removal_mode 0)
		)
		(polygon
			(pts
				(arc
					(start 199.4535 -217.982546)
					(mid 199.44978 -217.991526)
					(end 199.4408 -217.995246)
				)
				(arc
					(start 197.9676 -217.995246)
					(mid 197.95862 -217.991526)
					(end 197.9549 -217.982546)
				)
				(arc
					(start 197.9549 -217.488008)
					(mid 197.95862 -217.479028)
					(end 197.9676 -217.475308)
				)
				(arc
					(start 199.4408 -217.475308)
					(mid 199.44978 -217.479028)
					(end 199.4535 -217.488008)
				)
			)
		)
	)
	(zone
		(layer "In1.Cu")
		(hatch none 0.5)
		(connect_pads
			(clearance 0)
		)
		(min_thickness 0.25)
		(keepout
			(tracks not_allowed)
			(vias allowed)
			(pads allowed)
			(copperpour not_allowed)
			(footprints allowed)
		)
		(placement
			(enabled no)
			(sheetname "")
		)
		(fill
			(thermal_gap 0.5)
			(thermal_bridge_width 0.5)
			(island_removal_mode 0)
		)
		(polygon
			(pts
				(arc
					(start 79.989172 -385.31038)
					(mid 79.608172 -385.31038)
					(end 79.989172 -385.31038)
				)
			)
		)
	)
	(zone
		(layer "In1.Cu")
		(hatch none 0.5)
		(connect_pads
			(clearance 0)
		)
		(min_thickness 0.25)
		(keepout
			(tracks not_allowed)
			(vias allowed)
			(pads allowed)
			(copperpour not_allowed)
			(footprints allowed)
		)
		(placement
			(enabled no)
			(sheetname "")
		)
		(fill
			(thermal_gap 0.5)
			(thermal_bridge_width 0.5)
			(island_removal_mode 0)
		)
		(polygon
			(pts
				(arc
					(start 206.9973 -317.432436)
					(mid 206.99358 -317.441416)
					(end 206.9846 -317.445136)
				)
				(arc
					(start 205.5114 -317.445136)
					(mid 205.50242 -317.441416)
					(end 205.4987 -317.432436)
				)
				(arc
					(start 205.4987 -316.937898)
					(mid 205.50242 -316.928918)
					(end 205.5114 -316.925198)
				)
				(arc
					(start 206.9846 -316.925198)
					(mid 206.99358 -316.928918)
					(end 206.9973 -316.937898)
				)
			)
		)
	)
	(zone
		(layer "In1.Cu")
		(hatch none 0.5)
		(connect_pads
			(clearance 0)
		)
		(min_thickness 0.25)
		(keepout
			(tracks not_allowed)
			(vias allowed)
			(pads allowed)
			(copperpour not_allowed)
			(footprints allowed)
		)
		(placement
			(enabled no)
			(sheetname "")
		)
		(fill
			(thermal_gap 0.5)
			(thermal_bridge_width 0.5)
			(island_removal_mode 0)
		)
		(polygon
			(pts
				(arc
					(start 285.485332 -205.232254)
					(mid 285.481612 -205.241234)
					(end 285.472632 -205.244954)
				)
				(arc
					(start 283.999432 -205.244954)
					(mid 283.990452 -205.241234)
					(end 283.986732 -205.232254)
				)
				(arc
					(start 283.986732 -204.737716)
					(mid 283.990452 -204.728736)
					(end 283.999432 -204.725016)
				)
				(arc
					(start 285.472632 -204.725016)
					(mid 285.481612 -204.728736)
					(end 285.485332 -204.737716)
				)
			)
		)
	)
	(zone
		(layer "In1.Cu")
		(hatch none 0.5)
		(connect_pads
			(clearance 0)
		)
		(min_thickness 0.25)
		(keepout
			(tracks not_allowed)
			(vias allowed)
			(pads allowed)
			(copperpour not_allowed)
			(footprints allowed)
		)
		(placement
			(enabled no)
			(sheetname "")
		)
		(fill
			(thermal_gap 0.5)
			(thermal_bridge_width 0.5)
			(island_removal_mode 0)
		)
		(polygon
			(pts
				(arc
					(start 52.661058 -389.467344)
					(mid 52.280058 -389.467344)
					(end 52.661058 -389.467344)
				)
			)
		)
	)
	(zone
		(layer "In1.Cu")
		(hatch none 0.5)
		(connect_pads
			(clearance 0)
		)
		(min_thickness 0.25)
		(keepout
			(tracks not_allowed)
			(vias allowed)
			(pads allowed)
			(copperpour not_allowed)
			(footprints allowed)
		)
		(placement
			(enabled no)
			(sheetname "")
		)
		(fill
			(thermal_gap 0.5)
			(thermal_bridge_width 0.5)
			(island_removal_mode 0)
		)
		(polygon
			(pts
				(arc
					(start 296.473372 -318.28232)
					(mid 296.469652 -318.2913)
					(end 296.460672 -318.29502)
				)
				(arc
					(start 294.987472 -318.29502)
					(mid 294.978492 -318.2913)
					(end 294.974772 -318.28232)
				)
				(arc
					(start 294.974772 -317.787782)
					(mid 294.978492 -317.778802)
					(end 294.987472 -317.775082)
				)
				(arc
					(start 296.460672 -317.775082)
					(mid 296.469652 -317.778802)
					(end 296.473372 -317.787782)
				)
			)
		)
	)
	(zone
		(layer "In1.Cu")
		(hatch none 0.5)
		(connect_pads
			(clearance 0)
		)
		(min_thickness 0.25)
		(keepout
			(tracks not_allowed)
			(vias allowed)
			(pads allowed)
			(copperpour not_allowed)
			(footprints allowed)
		)
		(placement
			(enabled no)
			(sheetname "")
		)
		(fill
			(thermal_gap 0.5)
			(thermal_bridge_width 0.5)
			(island_removal_mode 0)
		)
		(polygon
			(pts
				(arc
					(start 25.901396 -284.282388)
					(mid 25.897676 -284.291368)
					(end 25.888696 -284.295088)
				)
				(arc
					(start 24.415496 -284.295088)
					(mid 24.406516 -284.291368)
					(end 24.402796 -284.282388)
				)
				(arc
					(start 24.402796 -283.78785)
					(mid 24.406516 -283.77887)
					(end 24.415496 -283.77515)
				)
				(arc
					(start 25.888696 -283.77515)
					(mid 25.897676 -283.77887)
					(end 25.901396 -283.78785)
				)
			)
		)
	)
	(zone
		(layer "In1.Cu")
		(hatch none 0.5)
		(connect_pads
			(clearance 0)
		)
		(min_thickness 0.25)
		(keepout
			(tracks not_allowed)
			(vias allowed)
			(pads allowed)
			(copperpour not_allowed)
			(footprints allowed)
		)
		(placement
			(enabled no)
			(sheetname "")
		)
		(fill
			(thermal_gap 0.5)
			(thermal_bridge_width 0.5)
			(island_removal_mode 0)
		)
		(polygon
			(pts
				(arc
					(start 176.821338 -304.682398)
					(mid 176.817618 -304.691378)
					(end 176.808638 -304.695098)
				)
				(arc
					(start 175.335438 -304.695098)
					(mid 175.326458 -304.691378)
					(end 175.322738 -304.682398)
				)
				(arc
					(start 175.322738 -304.18786)
					(mid 175.326458 -304.17888)
					(end 175.335438 -304.17516)
				)
				(arc
					(start 176.808638 -304.17516)
					(mid 176.817618 -304.17888)
					(end 176.821338 -304.18786)
				)
			)
		)
	)
	(zone
		(layer "In1.Cu")
		(hatch none 0.5)
		(connect_pads
			(clearance 0)
		)
		(min_thickness 0.25)
		(keepout
			(tracks not_allowed)
			(vias allowed)
			(pads allowed)
			(copperpour not_allowed)
			(footprints allowed)
		)
		(placement
			(enabled no)
			(sheetname "")
		)
		(fill
			(thermal_gap 0.5)
			(thermal_bridge_width 0.5)
			(island_removal_mode 0)
		)
		(polygon
			(pts
				(arc
					(start 30.001464 -304.682398)
					(mid 29.997744 -304.691378)
					(end 29.988764 -304.695098)
				)
				(arc
					(start 28.515564 -304.695098)
					(mid 28.506584 -304.691378)
					(end 28.502864 -304.682398)
				)
				(arc
					(start 28.502864 -304.18786)
					(mid 28.506584 -304.17888)
					(end 28.515564 -304.17516)
				)
				(arc
					(start 29.988764 -304.17516)
					(mid 29.997744 -304.17888)
					(end 30.001464 -304.18786)
				)
			)
		)
	)
	(zone
		(layer "In1.Cu")
		(hatch none 0.5)
		(connect_pads
			(clearance 0)
		)
		(min_thickness 0.25)
		(keepout
			(tracks not_allowed)
			(vias allowed)
			(pads allowed)
			(copperpour not_allowed)
			(footprints allowed)
		)
		(placement
			(enabled no)
			(sheetname "")
		)
		(fill
			(thermal_gap 0.5)
			(thermal_bridge_width 0.5)
			(island_removal_mode 0)
		)
		(polygon
			(pts
				(arc
					(start 176.821338 -240.932462)
					(mid 176.817618 -240.941442)
					(end 176.808638 -240.945162)
				)
				(arc
					(start 175.335438 -240.945162)
					(mid 175.326458 -240.941442)
					(end 175.322738 -240.932462)
				)
				(arc
					(start 175.322738 -240.437924)
					(mid 175.326458 -240.428944)
					(end 175.335438 -240.425224)
				)
				(arc
					(start 176.808638 -240.425224)
					(mid 176.817618 -240.428944)
					(end 176.821338 -240.437924)
				)
			)
		)
	)
	(zone
		(layer "In1.Cu")
		(hatch none 0.5)
		(connect_pads
			(clearance 0)
		)
		(min_thickness 0.25)
		(keepout
			(tracks not_allowed)
			(vias allowed)
			(pads allowed)
			(copperpour not_allowed)
			(footprints allowed)
		)
		(placement
			(enabled no)
			(sheetname "")
		)
		(fill
			(thermal_gap 0.5)
			(thermal_bridge_width 0.5)
			(island_removal_mode 0)
		)
		(polygon
			(pts
				(arc
					(start 277.941532 -197.582282)
					(mid 277.937812 -197.591262)
					(end 277.928832 -197.594982)
				)
				(arc
					(start 276.455632 -197.594982)
					(mid 276.446652 -197.591262)
					(end 276.442932 -197.582282)
				)
				(arc
					(start 276.442932 -197.087744)
					(mid 276.446652 -197.078764)
					(end 276.455632 -197.075044)
				)
				(arc
					(start 277.928832 -197.075044)
					(mid 277.937812 -197.078764)
					(end 277.941532 -197.087744)
				)
			)
		)
	)
	(zone
		(layer "In1.Cu")
		(hatch none 0.5)
		(connect_pads
			(clearance 0)
		)
		(min_thickness 0.25)
		(keepout
			(tracks not_allowed)
			(vias allowed)
			(pads allowed)
			(copperpour not_allowed)
			(footprints allowed)
		)
		(placement
			(enabled no)
			(sheetname "")
		)
		(fill
			(thermal_gap 0.5)
			(thermal_bridge_width 0.5)
			(island_removal_mode 0)
		)
		(polygon
			(pts
				(arc
					(start 413.117284 -213.73211)
					(mid 413.113564 -213.74109)
					(end 413.104584 -213.74481)
				)
				(arc
					(start 411.631384 -213.74481)
					(mid 411.622404 -213.74109)
					(end 411.618684 -213.73211)
				)
				(arc
					(start 411.618684 -213.237572)
					(mid 411.622404 -213.228592)
					(end 411.631384 -213.224872)
				)
				(arc
					(start 413.104584 -213.224872)
					(mid 413.113564 -213.228592)
					(end 413.117284 -213.237572)
				)
			)
		)
	)
	(zone
		(layer "In1.Cu")
		(hatch none 0.5)
		(connect_pads
			(clearance 0)
		)
		(min_thickness 0.25)
		(keepout
			(tracks not_allowed)
			(vias allowed)
			(pads allowed)
			(copperpour not_allowed)
			(footprints allowed)
		)
		(placement
			(enabled no)
			(sheetname "")
		)
		(fill
			(thermal_gap 0.5)
			(thermal_bridge_width 0.5)
			(island_removal_mode 0)
		)
		(polygon
			(pts
				(arc
					(start 308.117494 -208.632298)
					(mid 308.113774 -208.641278)
					(end 308.104794 -208.644998)
				)
				(arc
					(start 306.631594 -208.644998)
					(mid 306.622614 -208.641278)
					(end 306.618894 -208.632298)
				)
				(arc
					(start 306.618894 -208.13776)
					(mid 306.622614 -208.12878)
					(end 306.631594 -208.12506)
				)
				(arc
					(start 308.104794 -208.12506)
					(mid 308.113774 -208.12878)
					(end 308.117494 -208.13776)
				)
			)
		)
	)
	(zone
		(layer "In1.Cu")
		(hatch none 0.5)
		(connect_pads
			(clearance 0)
		)
		(min_thickness 0.25)
		(keepout
			(tracks not_allowed)
			(vias allowed)
			(pads allowed)
			(copperpour not_allowed)
			(footprints allowed)
		)
		(placement
			(enabled no)
			(sheetname "")
		)
		(fill
			(thermal_gap 0.5)
			(thermal_bridge_width 0.5)
			(island_removal_mode 0)
		)
		(polygon
			(pts
				(arc
					(start 265.87831 -265.335004)
					(mid 265.21791 -265.335004)
					(end 265.87831 -265.335004)
				)
			)
		)
	)
	(zone
		(layer "In1.Cu")
		(hatch none 0.5)
		(connect_pads
			(clearance 0)
		)
		(min_thickness 0.25)
		(keepout
			(tracks not_allowed)
			(vias allowed)
			(pads allowed)
			(copperpour not_allowed)
			(footprints allowed)
		)
		(placement
			(enabled no)
			(sheetname "")
		)
		(fill
			(thermal_gap 0.5)
			(thermal_bridge_width 0.5)
			(island_removal_mode 0)
		)
		(polygon
			(pts
				(arc
					(start 443.2935 -302.982122)
					(mid 443.28978 -302.991102)
					(end 443.2808 -302.994822)
				)
				(arc
					(start 441.8076 -302.994822)
					(mid 441.79862 -302.991102)
					(end 441.7949 -302.982122)
				)
				(arc
					(start 441.7949 -302.487584)
					(mid 441.79862 -302.478604)
					(end 441.8076 -302.474884)
				)
				(arc
					(start 443.2808 -302.474884)
					(mid 443.28978 -302.478604)
					(end 443.2935 -302.487584)
				)
			)
		)
	)
	(zone
		(layer "In1.Cu")
		(hatch none 0.5)
		(connect_pads
			(clearance 0)
		)
		(min_thickness 0.25)
		(keepout
			(tracks not_allowed)
			(vias allowed)
			(pads allowed)
			(copperpour not_allowed)
			(footprints allowed)
		)
		(placement
			(enabled no)
			(sheetname "")
		)
		(fill
			(thermal_gap 0.5)
			(thermal_bridge_width 0.5)
			(island_removal_mode 0)
		)
		(polygon
			(pts
				(arc
					(start 202.897232 -310.632348)
					(mid 202.893512 -310.641328)
					(end 202.884532 -310.645048)
				)
				(arc
					(start 201.411332 -310.645048)
					(mid 201.402352 -310.641328)
					(end 201.398632 -310.632348)
				)
				(arc
					(start 201.398632 -310.13781)
					(mid 201.402352 -310.12883)
					(end 201.411332 -310.12511)
				)
				(arc
					(start 202.884532 -310.12511)
					(mid 202.893512 -310.12883)
					(end 202.897232 -310.13781)
				)
			)
		)
	)
	(zone
		(layer "In1.Cu")
		(hatch none 0.5)
		(connect_pads
			(clearance 0)
		)
		(min_thickness 0.25)
		(keepout
			(tracks not_allowed)
			(vias allowed)
			(pads allowed)
			(copperpour not_allowed)
			(footprints allowed)
		)
		(placement
			(enabled no)
			(sheetname "")
		)
		(fill
			(thermal_gap 0.5)
			(thermal_bridge_width 0.5)
			(island_removal_mode 0)
		)
		(polygon
			(pts
				(arc
					(start 447.393568 -210.33232)
					(mid 447.389848 -210.3413)
					(end 447.380868 -210.34502)
				)
				(arc
					(start 445.907668 -210.34502)
					(mid 445.898688 -210.3413)
					(end 445.894968 -210.33232)
				)
				(arc
					(start 445.894968 -209.837782)
					(mid 445.898688 -209.828802)
					(end 445.907668 -209.825082)
				)
				(arc
					(start 447.380868 -209.825082)
					(mid 447.389848 -209.828802)
					(end 447.393568 -209.837782)
				)
			)
		)
	)
	(zone
		(layer "In1.Cu")
		(hatch none 0.5)
		(connect_pads
			(clearance 0)
		)
		(min_thickness 0.25)
		(keepout
			(tracks not_allowed)
			(vias allowed)
			(pads allowed)
			(copperpour not_allowed)
			(footprints allowed)
		)
		(placement
			(enabled no)
			(sheetname "")
		)
		(fill
			(thermal_gap 0.5)
			(thermal_bridge_width 0.5)
			(island_removal_mode 0)
		)
		(polygon
			(pts
				(arc
					(start 199.4535 -210.332574)
					(mid 199.44978 -210.341554)
					(end 199.4408 -210.345274)
				)
				(arc
					(start 197.9676 -210.345274)
					(mid 197.95862 -210.341554)
					(end 197.9549 -210.332574)
				)
				(arc
					(start 197.9549 -209.838036)
					(mid 197.95862 -209.829056)
					(end 197.9676 -209.825336)
				)
				(arc
					(start 199.4408 -209.825336)
					(mid 199.44978 -209.829056)
					(end 199.4535 -209.838036)
				)
			)
		)
	)
	(zone
		(layer "In1.Cu")
		(hatch none 0.5)
		(connect_pads
			(clearance 0)
		)
		(min_thickness 0.25)
		(keepout
			(tracks not_allowed)
			(vias allowed)
			(pads allowed)
			(copperpour not_allowed)
			(footprints allowed)
		)
		(placement
			(enabled no)
			(sheetname "")
		)
		(fill
			(thermal_gap 0.5)
			(thermal_bridge_width 0.5)
			(island_removal_mode 0)
		)
		(polygon
			(pts
				(arc
					(start 454.937368 -295.33215)
					(mid 454.933648 -295.34113)
					(end 454.924668 -295.34485)
				)
				(arc
					(start 453.451468 -295.34485)
					(mid 453.442488 -295.34113)
					(end 453.438768 -295.33215)
				)
				(arc
					(start 453.438768 -294.837612)
					(mid 453.442488 -294.828632)
					(end 453.451468 -294.824912)
				)
				(arc
					(start 454.924668 -294.824912)
					(mid 454.933648 -294.828632)
					(end 454.937368 -294.837612)
				)
			)
		)
	)
	(zone
		(layer "In1.Cu")
		(hatch none 0.5)
		(connect_pads
			(clearance 0)
		)
		(min_thickness 0.25)
		(keepout
			(tracks not_allowed)
			(vias allowed)
			(pads allowed)
			(copperpour not_allowed)
			(footprints allowed)
		)
		(placement
			(enabled no)
			(sheetname "")
		)
		(fill
			(thermal_gap 0.5)
			(thermal_bridge_width 0.5)
			(island_removal_mode 0)
		)
		(polygon
			(pts
				(arc
					(start 413.117284 -279.182322)
					(mid 413.113564 -279.191302)
					(end 413.104584 -279.195022)
				)
				(arc
					(start 411.631384 -279.195022)
					(mid 411.622404 -279.191302)
					(end 411.618684 -279.182322)
				)
				(arc
					(start 411.618684 -278.687784)
					(mid 411.622404 -278.678804)
					(end 411.631384 -278.675084)
				)
				(arc
					(start 413.104584 -278.675084)
					(mid 413.113564 -278.678804)
					(end 413.117284 -278.687784)
				)
			)
		)
	)
	(zone
		(layer "In1.Cu")
		(hatch none 0.5)
		(connect_pads
			(clearance 0)
		)
		(min_thickness 0.25)
		(keepout
			(tracks not_allowed)
			(vias allowed)
			(pads allowed)
			(copperpour not_allowed)
			(footprints allowed)
		)
		(placement
			(enabled no)
			(sheetname "")
		)
		(fill
			(thermal_gap 0.5)
			(thermal_bridge_width 0.5)
			(island_removal_mode 0)
		)
		(polygon
			(pts
				(arc
					(start 159.08909 -385.31038)
					(mid 158.70809 -385.31038)
					(end 159.08909 -385.31038)
				)
			)
		)
	)
	(zone
		(layer "In1.Cu")
		(hatch none 0.5)
		(connect_pads
			(clearance 0)
		)
		(min_thickness 0.25)
		(keepout
			(tracks not_allowed)
			(vias allowed)
			(pads allowed)
			(copperpour not_allowed)
			(footprints allowed)
		)
		(placement
			(enabled no)
			(sheetname "")
		)
		(fill
			(thermal_gap 0.5)
			(thermal_bridge_width 0.5)
			(island_removal_mode 0)
		)
		(polygon
			(pts
				(arc
					(start 435.749446 -301.2821)
					(mid 435.745726 -301.29108)
					(end 435.736746 -301.2948)
				)
				(arc
					(start 434.263546 -301.2948)
					(mid 434.254566 -301.29108)
					(end 434.250846 -301.2821)
				)
				(arc
					(start 434.250846 -300.787562)
					(mid 434.254566 -300.778582)
					(end 434.263546 -300.774862)
				)
				(arc
					(start 435.736746 -300.774862)
					(mid 435.745726 -300.778582)
					(end 435.749446 -300.787562)
				)
			)
		)
	)
	(zone
		(layer "In1.Cu")
		(hatch none 0.5)
		(connect_pads
			(clearance 0)
		)
		(min_thickness 0.25)
		(keepout
			(tracks not_allowed)
			(vias allowed)
			(pads allowed)
			(copperpour not_allowed)
			(footprints allowed)
		)
		(placement
			(enabled no)
			(sheetname "")
		)
		(fill
			(thermal_gap 0.5)
			(thermal_bridge_width 0.5)
			(island_removal_mode 0)
		)
		(polygon
			(pts
				(arc
					(start 51.061366 -388.774432)
					(mid 50.680366 -388.774432)
					(end 51.061366 -388.774432)
				)
			)
		)
	)
	(zone
		(layer "In1.Cu")
		(hatch none 0.5)
		(connect_pads
			(clearance 0)
		)
		(min_thickness 0.25)
		(keepout
			(tracks not_allowed)
			(vias allowed)
			(pads allowed)
			(copperpour not_allowed)
			(footprints allowed)
		)
		(placement
			(enabled no)
			(sheetname "")
		)
		(fill
			(thermal_gap 0.5)
			(thermal_bridge_width 0.5)
			(island_removal_mode 0)
		)
		(polygon
			(pts
				(arc
					(start 56.077358 -284.282388)
					(mid 56.073638 -284.291368)
					(end 56.064658 -284.295088)
				)
				(arc
					(start 54.591458 -284.295088)
					(mid 54.582478 -284.291368)
					(end 54.578758 -284.282388)
				)
				(arc
					(start 54.578758 -283.78785)
					(mid 54.582478 -283.77887)
					(end 54.591458 -283.77515)
				)
				(arc
					(start 56.064658 -283.77515)
					(mid 56.073638 -283.77887)
					(end 56.077358 -283.78785)
				)
			)
		)
	)
	(zone
		(layer "In1.Cu")
		(hatch none 0.5)
		(connect_pads
			(clearance 0)
		)
		(min_thickness 0.25)
		(keepout
			(tracks not_allowed)
			(vias allowed)
			(pads allowed)
			(copperpour not_allowed)
			(footprints allowed)
		)
		(placement
			(enabled no)
			(sheetname "")
		)
		(fill
			(thermal_gap 0.5)
			(thermal_bridge_width 0.5)
			(island_removal_mode 0)
		)
		(polygon
			(pts
				(arc
					(start 120.090946 -391.319258)
					(mid 120.217946 -391.446258)
					(end 120.344946 -391.319258)
				)
				(arc
					(start 120.344946 -391.243058)
					(mid 120.217946 -391.116058)
					(end 120.090946 -391.243058)
				)
			)
		)
	)
	(zone
		(layer "In1.Cu")
		(hatch none 0.5)
		(connect_pads
			(clearance 0)
		)
		(min_thickness 0.25)
		(keepout
			(tracks not_allowed)
			(vias allowed)
			(pads allowed)
			(copperpour not_allowed)
			(footprints allowed)
		)
		(placement
			(enabled no)
			(sheetname "")
		)
		(fill
			(thermal_gap 0.5)
			(thermal_bridge_width 0.5)
			(island_removal_mode 0)
		)
		(polygon
			(pts
				(arc
					(start 176.821338 -210.332574)
					(mid 176.817618 -210.341554)
					(end 176.808638 -210.345274)
				)
				(arc
					(start 175.335438 -210.345274)
					(mid 175.326458 -210.341554)
					(end 175.322738 -210.332574)
				)
				(arc
					(start 175.322738 -209.838036)
					(mid 175.326458 -209.829056)
					(end 175.335438 -209.825336)
				)
				(arc
					(start 176.808638 -209.825336)
					(mid 176.817618 -209.829056)
					(end 176.821338 -209.838036)
				)
			)
		)
	)
	(zone
		(layer "In1.Cu")
		(hatch none 0.5)
		(connect_pads
			(clearance 0)
		)
		(min_thickness 0.25)
		(keepout
			(tracks not_allowed)
			(vias allowed)
			(pads allowed)
			(copperpour not_allowed)
			(footprints allowed)
		)
		(placement
			(enabled no)
			(sheetname "")
		)
		(fill
			(thermal_gap 0.5)
			(thermal_bridge_width 0.5)
			(island_removal_mode 0)
		)
		(polygon
			(pts
				(arc
					(start 37.545264 -252.832362)
					(mid 37.541544 -252.841342)
					(end 37.532564 -252.845062)
				)
				(arc
					(start 36.059364 -252.845062)
					(mid 36.050384 -252.841342)
					(end 36.046664 -252.832362)
				)
				(arc
					(start 36.046664 -252.337824)
					(mid 36.050384 -252.328844)
					(end 36.059364 -252.325124)
				)
				(arc
					(start 37.532564 -252.325124)
					(mid 37.541544 -252.328844)
					(end 37.545264 -252.337824)
				)
			)
		)
	)
	(zone
		(layer "In1.Cu")
		(hatch none 0.5)
		(connect_pads
			(clearance 0)
		)
		(min_thickness 0.25)
		(keepout
			(tracks not_allowed)
			(vias allowed)
			(pads allowed)
			(copperpour not_allowed)
			(footprints allowed)
		)
		(placement
			(enabled no)
			(sheetname "")
		)
		(fill
			(thermal_gap 0.5)
			(thermal_bridge_width 0.5)
			(island_removal_mode 0)
		)
		(polygon
			(pts
				(arc
					(start 300.57344 -251.132086)
					(mid 300.56972 -251.141066)
					(end 300.56074 -251.144786)
				)
				(arc
					(start 299.08754 -251.144786)
					(mid 299.07856 -251.141066)
					(end 299.07484 -251.132086)
				)
				(arc
					(start 299.07484 -250.637548)
					(mid 299.07856 -250.628568)
					(end 299.08754 -250.624848)
				)
				(arc
					(start 300.56074 -250.624848)
					(mid 300.56972 -250.628568)
					(end 300.57344 -250.637548)
				)
			)
		)
	)
	(zone
		(layer "In1.Cu")
		(hatch none 0.5)
		(connect_pads
			(clearance 0)
		)
		(min_thickness 0.25)
		(keepout
			(tracks not_allowed)
			(vias allowed)
			(pads allowed)
			(copperpour not_allowed)
			(footprints allowed)
		)
		(placement
			(enabled no)
			(sheetname "")
		)
		(fill
			(thermal_gap 0.5)
			(thermal_bridge_width 0.5)
			(island_removal_mode 0)
		)
		(polygon
			(pts
				(arc
					(start 424.761406 -227.332286)
					(mid 424.757686 -227.341266)
					(end 424.748706 -227.344986)
				)
				(arc
					(start 423.275506 -227.344986)
					(mid 423.266526 -227.341266)
					(end 423.262806 -227.332286)
				)
				(arc
					(start 423.262806 -226.837748)
					(mid 423.266526 -226.828768)
					(end 423.275506 -226.825048)
				)
				(arc
					(start 424.748706 -226.825048)
					(mid 424.757686 -226.828768)
					(end 424.761406 -226.837748)
				)
			)
		)
	)
	(zone
		(layer "In1.Cu")
		(hatch none 0.5)
		(connect_pads
			(clearance 0)
		)
		(min_thickness 0.25)
		(keepout
			(tracks not_allowed)
			(vias allowed)
			(pads allowed)
			(copperpour not_allowed)
			(footprints allowed)
		)
		(placement
			(enabled no)
			(sheetname "")
		)
		(fill
			(thermal_gap 0.5)
			(thermal_bridge_width 0.5)
			(island_removal_mode 0)
		)
		(polygon
			(pts
				(arc
					(start 146.618706 -391.319258)
					(mid 146.745706 -391.446258)
					(end 146.872706 -391.319258)
				)
				(arc
					(start 146.872706 -391.243058)
					(mid 146.745706 -391.116058)
					(end 146.618706 -391.243058)
				)
			)
		)
	)
	(zone
		(layer "In1.Cu")
		(hatch none 0.5)
		(connect_pads
			(clearance 0)
		)
		(min_thickness 0.25)
		(keepout
			(tracks not_allowed)
			(vias allowed)
			(pads allowed)
			(copperpour not_allowed)
			(footprints allowed)
		)
		(placement
			(enabled no)
			(sheetname "")
		)
		(fill
			(thermal_gap 0.5)
			(thermal_bridge_width 0.5)
			(island_removal_mode 0)
		)
		(polygon
			(pts
				(arc
					(start 18.357342 -265.5824)
					(mid 18.353622 -265.59138)
					(end 18.344642 -265.5951)
				)
				(arc
					(start 16.871442 -265.5951)
					(mid 16.862462 -265.59138)
					(end 16.858742 -265.5824)
				)
				(arc
					(start 16.858742 -265.087862)
					(mid 16.862462 -265.078882)
					(end 16.871442 -265.075162)
				)
				(arc
					(start 18.344642 -265.075162)
					(mid 18.353622 -265.078882)
					(end 18.357342 -265.087862)
				)
			)
		)
	)
	(zone
		(layer "In1.Cu")
		(hatch none 0.5)
		(connect_pads
			(clearance 0)
		)
		(min_thickness 0.25)
		(keepout
			(tracks not_allowed)
			(vias allowed)
			(pads allowed)
			(copperpour not_allowed)
			(footprints allowed)
		)
		(placement
			(enabled no)
			(sheetname "")
		)
		(fill
			(thermal_gap 0.5)
			(thermal_bridge_width 0.5)
			(island_removal_mode 0)
		)
		(polygon
			(pts
				(arc
					(start 159.818832 -391.319258)
					(mid 159.945832 -391.446258)
					(end 160.072832 -391.319258)
				)
				(arc
					(start 160.072832 -391.243058)
					(mid 159.945832 -391.116058)
					(end 159.818832 -391.243058)
				)
			)
		)
	)
	(zone
		(layer "In1.Cu")
		(hatch none 0.5)
		(connect_pads
			(clearance 0)
		)
		(min_thickness 0.25)
		(keepout
			(tracks not_allowed)
			(vias allowed)
			(pads allowed)
			(copperpour not_allowed)
			(footprints allowed)
		)
		(placement
			(enabled no)
			(sheetname "")
		)
		(fill
			(thermal_gap 0.5)
			(thermal_bridge_width 0.5)
			(island_removal_mode 0)
		)
		(polygon
			(pts
				(arc
					(start 52.633372 -285.132526)
					(mid 52.629652 -285.141506)
					(end 52.620672 -285.145226)
				)
				(arc
					(start 51.147472 -285.145226)
					(mid 51.138492 -285.141506)
					(end 51.134772 -285.132526)
				)
				(arc
					(start 51.134772 -284.637988)
					(mid 51.138492 -284.629008)
					(end 51.147472 -284.625288)
				)
				(arc
					(start 52.620672 -284.625288)
					(mid 52.629652 -284.629008)
					(end 52.633372 -284.637988)
				)
			)
		)
	)
	(zone
		(layer "In1.Cu")
		(hatch none 0.5)
		(connect_pads
			(clearance 0)
		)
		(min_thickness 0.25)
		(keepout
			(tracks not_allowed)
			(vias allowed)
			(pads allowed)
			(copperpour not_allowed)
			(footprints allowed)
		)
		(placement
			(enabled no)
			(sheetname "")
		)
		(fill
			(thermal_gap 0.5)
			(thermal_bridge_width 0.5)
			(island_removal_mode 0)
		)
		(polygon
			(pts
				(arc
					(start 454.937368 -285.982156)
					(mid 454.933648 -285.991136)
					(end 454.924668 -285.994856)
				)
				(arc
					(start 453.451468 -285.994856)
					(mid 453.442488 -285.991136)
					(end 453.438768 -285.982156)
				)
				(arc
					(start 453.438768 -285.487618)
					(mid 453.442488 -285.478638)
					(end 453.451468 -285.474918)
				)
				(arc
					(start 454.924668 -285.474918)
					(mid 454.933648 -285.478638)
					(end 454.937368 -285.487618)
				)
			)
		)
	)
	(zone
		(layer "In1.Cu")
		(hatch none 0.5)
		(connect_pads
			(clearance 0)
		)
		(min_thickness 0.25)
		(keepout
			(tracks not_allowed)
			(vias allowed)
			(pads allowed)
			(copperpour not_allowed)
			(footprints allowed)
		)
		(placement
			(enabled no)
			(sheetname "")
		)
		(fill
			(thermal_gap 0.5)
			(thermal_bridge_width 0.5)
			(island_removal_mode 0)
		)
		(polygon
			(pts
				(arc
					(start 18.357342 -286.832548)
					(mid 18.353622 -286.841528)
					(end 18.344642 -286.845248)
				)
				(arc
					(start 16.871442 -286.845248)
					(mid 16.862462 -286.841528)
					(end 16.858742 -286.832548)
				)
				(arc
					(start 16.858742 -286.33801)
					(mid 16.862462 -286.32903)
					(end 16.871442 -286.32531)
				)
				(arc
					(start 18.344642 -286.32531)
					(mid 18.353622 -286.32903)
					(end 18.357342 -286.33801)
				)
			)
		)
	)
	(zone
		(layer "In1.Cu")
		(hatch none 0.5)
		(connect_pads
			(clearance 0)
		)
		(min_thickness 0.25)
		(keepout
			(tracks not_allowed)
			(vias allowed)
			(pads allowed)
			(copperpour not_allowed)
			(footprints allowed)
		)
		(placement
			(enabled no)
			(sheetname "")
		)
		(fill
			(thermal_gap 0.5)
			(thermal_bridge_width 0.5)
			(island_removal_mode 0)
		)
		(polygon
			(pts
				(arc
					(start 300.57344 -269.832328)
					(mid 300.56972 -269.841308)
					(end 300.56074 -269.845028)
				)
				(arc
					(start 299.08754 -269.845028)
					(mid 299.07856 -269.841308)
					(end 299.07484 -269.832328)
				)
				(arc
					(start 299.07484 -269.33779)
					(mid 299.07856 -269.32881)
					(end 299.08754 -269.32509)
				)
				(arc
					(start 300.56074 -269.32509)
					(mid 300.56972 -269.32881)
					(end 300.57344 -269.33779)
				)
			)
		)
	)
	(zone
		(layer "In1.Cu")
		(hatch none 0.5)
		(connect_pads
			(clearance 0)
		)
		(min_thickness 0.25)
		(keepout
			(tracks not_allowed)
			(vias allowed)
			(pads allowed)
			(copperpour not_allowed)
			(footprints allowed)
		)
		(placement
			(enabled no)
			(sheetname "")
		)
		(fill
			(thermal_gap 0.5)
			(thermal_bridge_width 0.5)
			(island_removal_mode 0)
		)
		(polygon
			(pts
				(arc
					(start 58.661046 -389.467344)
					(mid 58.280046 -389.467344)
					(end 58.661046 -389.467344)
				)
			)
		)
	)
	(zone
		(layer "In1.Cu")
		(hatch none 0.5)
		(connect_pads
			(clearance 0)
		)
		(min_thickness 0.25)
		(keepout
			(tracks not_allowed)
			(vias allowed)
			(pads allowed)
			(copperpour not_allowed)
			(footprints allowed)
		)
		(placement
			(enabled no)
			(sheetname "")
		)
		(fill
			(thermal_gap 0.5)
			(thermal_bridge_width 0.5)
			(island_removal_mode 0)
		)
		(polygon
			(pts
				(arc
					(start 48.533304 -267.282422)
					(mid 48.529584 -267.291402)
					(end 48.520604 -267.295122)
				)
				(arc
					(start 47.047404 -267.295122)
					(mid 47.038424 -267.291402)
					(end 47.034704 -267.282422)
				)
				(arc
					(start 47.034704 -266.787884)
					(mid 47.038424 -266.778904)
					(end 47.047404 -266.775184)
				)
				(arc
					(start 48.520604 -266.775184)
					(mid 48.529584 -266.778904)
					(end 48.533304 -266.787884)
				)
			)
		)
	)
	(zone
		(layer "In1.Cu")
		(hatch none 0.5)
		(connect_pads
			(clearance 0)
		)
		(min_thickness 0.25)
		(keepout
			(tracks not_allowed)
			(vias allowed)
			(pads allowed)
			(copperpour not_allowed)
			(footprints allowed)
		)
		(placement
			(enabled no)
			(sheetname "")
		)
		(fill
			(thermal_gap 0.5)
			(thermal_bridge_width 0.5)
			(island_removal_mode 0)
		)
		(polygon
			(pts
				(arc
					(start 30.841696 -11.91768)
					(mid 30.819378 -11.971562)
					(end 30.765496 -11.99388)
				)
				(arc
					(start 29.728922 -11.99388)
					(mid 29.67504 -11.971562)
					(end 29.652722 -11.91768)
				)
				(arc
					(start 29.652722 -10.51814)
					(mid 29.67504 -10.464258)
					(end 29.728922 -10.44194)
				)
				(arc
					(start 30.765496 -10.44194)
					(mid 30.819378 -10.464258)
					(end 30.841696 -10.51814)
				)
			)
		)
	)
	(zone
		(layer "In1.Cu")
		(hatch none 0.5)
		(connect_pads
			(clearance 0)
		)
		(min_thickness 0.25)
		(keepout
			(tracks not_allowed)
			(vias allowed)
			(pads allowed)
			(copperpour not_allowed)
			(footprints allowed)
		)
		(placement
			(enabled no)
			(sheetname "")
		)
		(fill
			(thermal_gap 0.5)
			(thermal_bridge_width 0.5)
			(island_removal_mode 0)
		)
		(polygon
			(pts
				(arc
					(start 164.288724 -386.003292)
					(mid 163.907724 -386.003292)
					(end 164.288724 -386.003292)
				)
			)
		)
	)
	(zone
		(layer "In1.Cu")
		(hatch none 0.5)
		(connect_pads
			(clearance 0)
		)
		(min_thickness 0.25)
		(keepout
			(tracks not_allowed)
			(vias allowed)
			(pads allowed)
			(copperpour not_allowed)
			(footprints allowed)
		)
		(placement
			(enabled no)
			(sheetname "")
		)
		(fill
			(thermal_gap 0.5)
			(thermal_bridge_width 0.5)
			(island_removal_mode 0)
		)
		(polygon
			(pts
				(arc
					(start 447.393568 -281.732228)
					(mid 447.389848 -281.741208)
					(end 447.380868 -281.744928)
				)
				(arc
					(start 445.907668 -281.744928)
					(mid 445.898688 -281.741208)
					(end 445.894968 -281.732228)
				)
				(arc
					(start 445.894968 -281.23769)
					(mid 445.898688 -281.22871)
					(end 445.907668 -281.22499)
				)
				(arc
					(start 447.380868 -281.22499)
					(mid 447.389848 -281.22871)
					(end 447.393568 -281.23769)
				)
			)
		)
	)
	(zone
		(layer "In1.Cu")
		(hatch none 0.5)
		(connect_pads
			(clearance 0)
		)
		(min_thickness 0.25)
		(keepout
			(tracks not_allowed)
			(vias allowed)
			(pads allowed)
			(copperpour not_allowed)
			(footprints allowed)
		)
		(placement
			(enabled no)
			(sheetname "")
		)
		(fill
			(thermal_gap 0.5)
			(thermal_bridge_width 0.5)
			(island_removal_mode 0)
		)
		(polygon
			(pts
				(arc
					(start 25.901396 -312.33237)
					(mid 25.897676 -312.34135)
					(end 25.888696 -312.34507)
				)
				(arc
					(start 24.415496 -312.34507)
					(mid 24.406516 -312.34135)
					(end 24.402796 -312.33237)
				)
				(arc
					(start 24.402796 -311.837832)
					(mid 24.406516 -311.828852)
					(end 24.415496 -311.825132)
				)
				(arc
					(start 25.888696 -311.825132)
					(mid 25.897676 -311.828852)
					(end 25.901396 -311.837832)
				)
			)
		)
	)
	(zone
		(layer "In1.Cu")
		(hatch none 0.5)
		(connect_pads
			(clearance 0)
		)
		(min_thickness 0.25)
		(keepout
			(tracks not_allowed)
			(vias allowed)
			(pads allowed)
			(copperpour not_allowed)
			(footprints allowed)
		)
		(placement
			(enabled no)
			(sheetname "")
		)
		(fill
			(thermal_gap 0.5)
			(thermal_bridge_width 0.5)
			(island_removal_mode 0)
		)
		(polygon
			(pts
				(arc
					(start 288.929318 -211.182204)
					(mid 288.925598 -211.191184)
					(end 288.916618 -211.194904)
				)
				(arc
					(start 287.443418 -211.194904)
					(mid 287.434438 -211.191184)
					(end 287.430718 -211.182204)
				)
				(arc
					(start 287.430718 -210.687666)
					(mid 287.434438 -210.678686)
					(end 287.443418 -210.674966)
				)
				(arc
					(start 288.916618 -210.674966)
					(mid 288.925598 -210.678686)
					(end 288.929318 -210.687666)
				)
			)
		)
	)
	(zone
		(layer "In1.Cu")
		(hatch none 0.5)
		(connect_pads
			(clearance 0)
		)
		(min_thickness 0.25)
		(keepout
			(tracks not_allowed)
			(vias allowed)
			(pads allowed)
			(copperpour not_allowed)
			(footprints allowed)
		)
		(placement
			(enabled no)
			(sheetname "")
		)
		(fill
			(thermal_gap 0.5)
			(thermal_bridge_width 0.5)
			(island_removal_mode 0)
		)
		(polygon
			(pts
				(arc
					(start 52.633372 -266.432538)
					(mid 52.629652 -266.441518)
					(end 52.620672 -266.445238)
				)
				(arc
					(start 51.147472 -266.445238)
					(mid 51.138492 -266.441518)
					(end 51.134772 -266.432538)
				)
				(arc
					(start 51.134772 -265.938)
					(mid 51.138492 -265.92902)
					(end 51.147472 -265.9253)
				)
				(arc
					(start 52.620672 -265.9253)
					(mid 52.629652 -265.92902)
					(end 52.633372 -265.938)
				)
			)
		)
	)
	(zone
		(layer "In1.Cu")
		(hatch none 0.5)
		(connect_pads
			(clearance 0)
		)
		(min_thickness 0.25)
		(keepout
			(tracks not_allowed)
			(vias allowed)
			(pads allowed)
			(copperpour not_allowed)
			(footprints allowed)
		)
		(placement
			(enabled no)
			(sheetname "")
		)
		(fill
			(thermal_gap 0.5)
			(thermal_bridge_width 0.5)
			(island_removal_mode 0)
		)
		(polygon
			(pts
				(arc
					(start 281.385264 -218.832176)
					(mid 281.381544 -218.841156)
					(end 281.372564 -218.844876)
				)
				(arc
					(start 279.899364 -218.844876)
					(mid 279.890384 -218.841156)
					(end 279.886664 -218.832176)
				)
				(arc
					(start 279.886664 -218.337638)
					(mid 279.890384 -218.328658)
					(end 279.899364 -218.324938)
				)
				(arc
					(start 281.372564 -218.324938)
					(mid 281.381544 -218.328658)
					(end 281.385264 -218.337638)
				)
			)
		)
	)
	(zone
		(layer "In1.Cu")
		(hatch none 0.5)
		(connect_pads
			(clearance 0)
		)
		(min_thickness 0.25)
		(keepout
			(tracks not_allowed)
			(vias allowed)
			(pads allowed)
			(copperpour not_allowed)
			(footprints allowed)
		)
		(placement
			(enabled no)
			(sheetname "")
		)
		(fill
			(thermal_gap 0.5)
			(thermal_bridge_width 0.5)
			(island_removal_mode 0)
		)
		(polygon
			(pts
				(arc
					(start 206.5782 -242.385342)
					(mid 205.9178 -242.385342)
					(end 206.5782 -242.385342)
				)
			)
		)
	)
	(zone
		(layer "In1.Cu")
		(hatch none 0.5)
		(connect_pads
			(clearance 0)
		)
		(min_thickness 0.25)
		(keepout
			(tracks not_allowed)
			(vias allowed)
			(pads allowed)
			(copperpour not_allowed)
			(footprints allowed)
		)
		(placement
			(enabled no)
			(sheetname "")
		)
		(fill
			(thermal_gap 0.5)
			(thermal_bridge_width 0.5)
			(island_removal_mode 0)
		)
		(polygon
			(pts
				(arc
					(start 89.988898 -389.467344)
					(mid 89.607898 -389.467344)
					(end 89.988898 -389.467344)
				)
			)
		)
	)
	(zone
		(layer "In1.Cu")
		(hatch none 0.5)
		(connect_pads
			(clearance 0)
		)
		(min_thickness 0.25)
		(keepout
			(tracks not_allowed)
			(vias allowed)
			(pads allowed)
			(copperpour not_allowed)
			(footprints allowed)
		)
		(placement
			(enabled no)
			(sheetname "")
		)
		(fill
			(thermal_gap 0.5)
			(thermal_bridge_width 0.5)
			(island_removal_mode 0)
		)
		(polygon
			(pts
				(arc
					(start 172.72127 -299.582586)
					(mid 172.71755 -299.591566)
					(end 172.70857 -299.595286)
				)
				(arc
					(start 171.23537 -299.595286)
					(mid 171.22639 -299.591566)
					(end 171.22267 -299.582586)
				)
				(arc
					(start 171.22267 -299.088048)
					(mid 171.22639 -299.079068)
					(end 171.23537 -299.075348)
				)
				(arc
					(start 172.70857 -299.075348)
					(mid 172.71755 -299.079068)
					(end 172.72127 -299.088048)
				)
			)
		)
	)
	(zone
		(layer "In1.Cu")
		(hatch none 0.5)
		(connect_pads
			(clearance 0)
		)
		(min_thickness 0.25)
		(keepout
			(tracks not_allowed)
			(vias allowed)
			(pads allowed)
			(copperpour not_allowed)
			(footprints allowed)
		)
		(placement
			(enabled no)
			(sheetname "")
		)
		(fill
			(thermal_gap 0.5)
			(thermal_bridge_width 0.5)
			(island_removal_mode 0)
		)
		(polygon
			(pts
				(arc
					(start 152.288748 -386.003292)
					(mid 151.907748 -386.003292)
					(end 152.288748 -386.003292)
				)
			)
		)
	)
	(zone
		(layer "In1.Cu")
		(hatch none 0.5)
		(connect_pads
			(clearance 0)
		)
		(min_thickness 0.25)
		(keepout
			(tracks not_allowed)
			(vias allowed)
			(pads allowed)
			(copperpour not_allowed)
			(footprints allowed)
		)
		(placement
			(enabled no)
			(sheetname "")
		)
		(fill
			(thermal_gap 0.5)
			(thermal_bridge_width 0.5)
			(island_removal_mode 0)
		)
		(polygon
			(pts
				(arc
					(start 82.498184 -390.761474)
					(mid 82.193384 -390.761474)
					(end 82.498184 -390.761474)
				)
			)
		)
	)
	(zone
		(layer "In1.Cu")
		(hatch none 0.5)
		(connect_pads
			(clearance 0)
		)
		(min_thickness 0.25)
		(keepout
			(tracks not_allowed)
			(vias allowed)
			(pads allowed)
			(copperpour not_allowed)
			(footprints allowed)
		)
		(placement
			(enabled no)
			(sheetname "")
		)
		(fill
			(thermal_gap 0.5)
			(thermal_bridge_width 0.5)
			(island_removal_mode 0)
		)
		(polygon
			(pts
				(arc
					(start 320.990722 -391.822686)
					(mid 321.117722 -391.949686)
					(end 321.244722 -391.822686)
				)
				(arc
					(start 321.244722 -391.746486)
					(mid 321.117722 -391.619486)
					(end 320.990722 -391.746486)
				)
			)
		)
	)
	(zone
		(layer "In1.Cu")
		(hatch none 0.5)
		(connect_pads
			(clearance 0)
		)
		(min_thickness 0.25)
		(keepout
			(tracks not_allowed)
			(vias allowed)
			(pads allowed)
			(copperpour not_allowed)
			(footprints allowed)
		)
		(placement
			(enabled no)
			(sheetname "")
		)
		(fill
			(thermal_gap 0.5)
			(thermal_bridge_width 0.5)
			(island_removal_mode 0)
		)
		(polygon
			(pts
				(arc
					(start 443.2935 -218.832176)
					(mid 443.28978 -218.841156)
					(end 443.2808 -218.844876)
				)
				(arc
					(start 441.8076 -218.844876)
					(mid 441.79862 -218.841156)
					(end 441.7949 -218.832176)
				)
				(arc
					(start 441.7949 -218.337638)
					(mid 441.79862 -218.328658)
					(end 441.8076 -218.324938)
				)
				(arc
					(start 443.2808 -218.324938)
					(mid 443.28978 -218.328658)
					(end 443.2935 -218.337638)
				)
			)
		)
	)
	(zone
		(layer "In1.Cu")
		(hatch none 0.5)
		(connect_pads
			(clearance 0)
		)
		(min_thickness 0.25)
		(keepout
			(tracks not_allowed)
			(vias allowed)
			(pads allowed)
			(copperpour not_allowed)
			(footprints allowed)
		)
		(placement
			(enabled no)
			(sheetname "")
		)
		(fill
			(thermal_gap 0.5)
			(thermal_bridge_width 0.5)
			(island_removal_mode 0)
		)
		(polygon
			(pts
				(arc
					(start 157.08884 -389.467344)
					(mid 156.70784 -389.467344)
					(end 157.08884 -389.467344)
				)
			)
		)
	)
	(zone
		(layer "In1.Cu")
		(hatch none 0.5)
		(connect_pads
			(clearance 0)
		)
		(min_thickness 0.25)
		(keepout
			(tracks not_allowed)
			(vias allowed)
			(pads allowed)
			(copperpour not_allowed)
			(footprints allowed)
		)
		(placement
			(enabled no)
			(sheetname "")
		)
		(fill
			(thermal_gap 0.5)
			(thermal_bridge_width 0.5)
			(island_removal_mode 0)
		)
		(polygon
			(pts
				(arc
					(start 413.117284 -290.232338)
					(mid 413.113564 -290.241318)
					(end 413.104584 -290.245038)
				)
				(arc
					(start 411.631384 -290.245038)
					(mid 411.622404 -290.241318)
					(end 411.618684 -290.232338)
				)
				(arc
					(start 411.618684 -289.7378)
					(mid 411.622404 -289.72882)
					(end 411.631384 -289.7251)
				)
				(arc
					(start 413.104584 -289.7251)
					(mid 413.113564 -289.72882)
					(end 413.117284 -289.7378)
				)
			)
		)
	)
	(zone
		(layer "In1.Cu")
		(hatch none 0.5)
		(connect_pads
			(clearance 0)
		)
		(min_thickness 0.25)
		(keepout
			(tracks not_allowed)
			(vias allowed)
			(pads allowed)
			(copperpour not_allowed)
			(footprints allowed)
		)
		(placement
			(enabled no)
			(sheetname "")
		)
		(fill
			(thermal_gap 0.5)
			(thermal_bridge_width 0.5)
			(island_removal_mode 0)
		)
		(polygon
			(pts
				(arc
					(start 59.861196 -389.467344)
					(mid 59.480196 -389.467344)
					(end 59.861196 -389.467344)
				)
			)
		)
	)
	(zone
		(layer "In1.Cu")
		(hatch none 0.5)
		(connect_pads
			(clearance 0)
		)
		(min_thickness 0.25)
		(keepout
			(tracks not_allowed)
			(vias allowed)
			(pads allowed)
			(copperpour not_allowed)
			(footprints allowed)
		)
		(placement
			(enabled no)
			(sheetname "")
		)
		(fill
			(thermal_gap 0.5)
			(thermal_bridge_width 0.5)
			(island_removal_mode 0)
		)
		(polygon
			(pts
				(arc
					(start 191.909446 -295.332404)
					(mid 191.905726 -295.341384)
					(end 191.896746 -295.345104)
				)
				(arc
					(start 190.423546 -295.345104)
					(mid 190.414566 -295.341384)
					(end 190.410846 -295.332404)
				)
				(arc
					(start 190.410846 -294.837866)
					(mid 190.414566 -294.828886)
					(end 190.423546 -294.825166)
				)
				(arc
					(start 191.896746 -294.825166)
					(mid 191.905726 -294.828886)
					(end 191.909446 -294.837866)
				)
			)
		)
	)
	(zone
		(layer "In1.Cu")
		(hatch none 0.5)
		(connect_pads
			(clearance 0)
		)
		(min_thickness 0.25)
		(keepout
			(tracks not_allowed)
			(vias allowed)
			(pads allowed)
			(copperpour not_allowed)
			(footprints allowed)
		)
		(placement
			(enabled no)
			(sheetname "")
		)
		(fill
			(thermal_gap 0.5)
			(thermal_bridge_width 0.5)
			(island_removal_mode 0)
		)
		(polygon
			(pts
				(arc
					(start 447.393568 -231.582214)
					(mid 447.389848 -231.591194)
					(end 447.380868 -231.594914)
				)
				(arc
					(start 445.907668 -231.594914)
					(mid 445.898688 -231.591194)
					(end 445.894968 -231.582214)
				)
				(arc
					(start 445.894968 -231.087676)
					(mid 445.898688 -231.078696)
					(end 445.907668 -231.074976)
				)
				(arc
					(start 447.380868 -231.074976)
					(mid 447.389848 -231.078696)
					(end 447.393568 -231.087676)
				)
			)
		)
	)
	(zone
		(layer "In1.Cu")
		(hatch none 0.5)
		(connect_pads
			(clearance 0)
		)
		(min_thickness 0.25)
		(keepout
			(tracks not_allowed)
			(vias allowed)
			(pads allowed)
			(copperpour not_allowed)
			(footprints allowed)
		)
		(placement
			(enabled no)
			(sheetname "")
		)
		(fill
			(thermal_gap 0.5)
			(thermal_bridge_width 0.5)
			(island_removal_mode 0)
		)
		(polygon
			(pts
				(arc
					(start 176.821338 -317.432436)
					(mid 176.817618 -317.441416)
					(end 176.808638 -317.445136)
				)
				(arc
					(start 175.335438 -317.445136)
					(mid 175.326458 -317.441416)
					(end 175.322738 -317.432436)
				)
				(arc
					(start 175.322738 -316.937898)
					(mid 175.326458 -316.928918)
					(end 175.335438 -316.925198)
				)
				(arc
					(start 176.808638 -316.925198)
					(mid 176.817618 -316.928918)
					(end 176.821338 -316.937898)
				)
			)
		)
	)
	(zone
		(layer "In1.Cu")
		(hatch none 0.5)
		(connect_pads
			(clearance 0)
		)
		(min_thickness 0.25)
		(keepout
			(tracks not_allowed)
			(vias allowed)
			(pads allowed)
			(copperpour not_allowed)
			(footprints allowed)
		)
		(placement
			(enabled no)
			(sheetname "")
		)
		(fill
			(thermal_gap 0.5)
			(thermal_bridge_width 0.5)
			(island_removal_mode 0)
		)
		(polygon
			(pts
				(arc
					(start 443.2935 -286.832294)
					(mid 443.28978 -286.841274)
					(end 443.2808 -286.844994)
				)
				(arc
					(start 441.8076 -286.844994)
					(mid 441.79862 -286.841274)
					(end 441.7949 -286.832294)
				)
				(arc
					(start 441.7949 -286.337756)
					(mid 441.79862 -286.328776)
					(end 441.8076 -286.325056)
				)
				(arc
					(start 443.2808 -286.325056)
					(mid 443.28978 -286.328776)
					(end 443.2935 -286.337756)
				)
			)
		)
	)
	(zone
		(layer "In1.Cu")
		(hatch none 0.5)
		(connect_pads
			(clearance 0)
		)
		(min_thickness 0.25)
		(keepout
			(tracks not_allowed)
			(vias allowed)
			(pads allowed)
			(copperpour not_allowed)
			(footprints allowed)
		)
		(placement
			(enabled no)
			(sheetname "")
		)
		(fill
			(thermal_gap 0.5)
			(thermal_bridge_width 0.5)
			(island_removal_mode 0)
		)
		(polygon
			(pts
				(arc
					(start 30.001464 -287.682432)
					(mid 29.997744 -287.691412)
					(end 29.988764 -287.695132)
				)
				(arc
					(start 28.515564 -287.695132)
					(mid 28.506584 -287.691412)
					(end 28.502864 -287.682432)
				)
				(arc
					(start 28.502864 -287.187894)
					(mid 28.506584 -287.178914)
					(end 28.515564 -287.175194)
				)
				(arc
					(start 29.988764 -287.175194)
					(mid 29.997744 -287.178914)
					(end 30.001464 -287.187894)
				)
			)
		)
	)
	(zone
		(layer "In1.Cu")
		(hatch none 0.5)
		(connect_pads
			(clearance 0)
		)
		(min_thickness 0.25)
		(keepout
			(tracks not_allowed)
			(vias allowed)
			(pads allowed)
			(copperpour not_allowed)
			(footprints allowed)
		)
		(placement
			(enabled no)
			(sheetname "")
		)
		(fill
			(thermal_gap 0.5)
			(thermal_bridge_width 0.5)
			(island_removal_mode 0)
		)
		(polygon
			(pts
				(arc
					(start 413.117284 -217.132154)
					(mid 413.113564 -217.141134)
					(end 413.104584 -217.144854)
				)
				(arc
					(start 411.631384 -217.144854)
					(mid 411.622404 -217.141134)
					(end 411.618684 -217.132154)
				)
				(arc
					(start 411.618684 -216.637616)
					(mid 411.622404 -216.628636)
					(end 411.631384 -216.624916)
				)
				(arc
					(start 413.104584 -216.624916)
					(mid 413.113564 -216.628636)
					(end 413.117284 -216.637616)
				)
			)
		)
	)
	(zone
		(layer "In1.Cu")
		(hatch none 0.5)
		(connect_pads
			(clearance 0)
		)
		(min_thickness 0.25)
		(keepout
			(tracks not_allowed)
			(vias allowed)
			(pads allowed)
			(copperpour not_allowed)
			(footprints allowed)
		)
		(placement
			(enabled no)
			(sheetname "")
		)
		(fill
			(thermal_gap 0.5)
			(thermal_bridge_width 0.5)
			(island_removal_mode 0)
		)
		(polygon
			(pts
				(arc
					(start 413.998156 -399.143474)
					(mid 413.693356 -399.143474)
					(end 413.998156 -399.143474)
				)
			)
		)
	)
	(zone
		(layer "In1.Cu")
		(hatch none 0.5)
		(connect_pads
			(clearance 0)
		)
		(min_thickness 0.25)
		(keepout
			(tracks not_allowed)
			(vias allowed)
			(pads allowed)
			(copperpour not_allowed)
			(footprints allowed)
		)
		(placement
			(enabled no)
			(sheetname "")
		)
		(fill
			(thermal_gap 0.5)
			(thermal_bridge_width 0.5)
			(island_removal_mode 0)
		)
		(polygon
			(pts
				(arc
					(start 25.901396 -240.082578)
					(mid 25.897676 -240.091558)
					(end 25.888696 -240.095278)
				)
				(arc
					(start 24.415496 -240.095278)
					(mid 24.406516 -240.091558)
					(end 24.402796 -240.082578)
				)
				(arc
					(start 24.402796 -239.58804)
					(mid 24.406516 -239.57906)
					(end 24.415496 -239.57534)
				)
				(arc
					(start 25.888696 -239.57534)
					(mid 25.897676 -239.57906)
					(end 25.901396 -239.58804)
				)
			)
		)
	)
	(zone
		(layer "In1.Cu")
		(hatch none 0.5)
		(connect_pads
			(clearance 0)
		)
		(min_thickness 0.25)
		(keepout
			(tracks not_allowed)
			(vias allowed)
			(pads allowed)
			(copperpour not_allowed)
			(footprints allowed)
		)
		(placement
			(enabled no)
			(sheetname "")
		)
		(fill
			(thermal_gap 0.5)
			(thermal_bridge_width 0.5)
			(island_removal_mode 0)
		)
		(polygon
			(pts
				(arc
					(start 447.393568 -234.982258)
					(mid 447.389848 -234.991238)
					(end 447.380868 -234.994958)
				)
				(arc
					(start 445.907668 -234.994958)
					(mid 445.898688 -234.991238)
					(end 445.894968 -234.982258)
				)
				(arc
					(start 445.894968 -234.48772)
					(mid 445.898688 -234.47874)
					(end 445.907668 -234.47502)
				)
				(arc
					(start 447.380868 -234.47502)
					(mid 447.389848 -234.47874)
					(end 447.393568 -234.48772)
				)
			)
		)
	)
	(zone
		(layer "In1.Cu")
		(hatch none 0.5)
		(connect_pads
			(clearance 0)
		)
		(min_thickness 0.25)
		(keepout
			(tracks not_allowed)
			(vias allowed)
			(pads allowed)
			(copperpour not_allowed)
			(footprints allowed)
		)
		(placement
			(enabled no)
			(sheetname "")
		)
		(fill
			(thermal_gap 0.5)
			(thermal_bridge_width 0.5)
			(island_removal_mode 0)
		)
		(polygon
			(pts
				(arc
					(start 206.9973 -197.582536)
					(mid 206.99358 -197.591516)
					(end 206.9846 -197.595236)
				)
				(arc
					(start 205.5114 -197.595236)
					(mid 205.50242 -197.591516)
					(end 205.4987 -197.582536)
				)
				(arc
					(start 205.4987 -197.087998)
					(mid 205.50242 -197.079018)
					(end 205.5114 -197.075298)
				)
				(arc
					(start 206.9846 -197.075298)
					(mid 206.99358 -197.079018)
					(end 206.9973 -197.087998)
				)
			)
		)
	)
	(zone
		(layer "In1.Cu")
		(hatch none 0.5)
		(connect_pads
			(clearance 0)
		)
		(min_thickness 0.25)
		(keepout
			(tracks not_allowed)
			(vias allowed)
			(pads allowed)
			(copperpour not_allowed)
			(footprints allowed)
		)
		(placement
			(enabled no)
			(sheetname "")
		)
		(fill
			(thermal_gap 0.5)
			(thermal_bridge_width 0.5)
			(island_removal_mode 0)
		)
		(polygon
			(pts
				(arc
					(start 454.937368 -214.582248)
					(mid 454.933648 -214.591228)
					(end 454.924668 -214.594948)
				)
				(arc
					(start 453.451468 -214.594948)
					(mid 453.442488 -214.591228)
					(end 453.438768 -214.582248)
				)
				(arc
					(start 453.438768 -214.08771)
					(mid 453.442488 -214.07873)
					(end 453.451468 -214.07501)
				)
				(arc
					(start 454.924668 -214.07501)
					(mid 454.933648 -214.07873)
					(end 454.937368 -214.08771)
				)
			)
		)
	)
	(zone
		(layer "In1.Cu")
		(hatch none 0.5)
		(connect_pads
			(clearance 0)
		)
		(min_thickness 0.25)
		(keepout
			(tracks not_allowed)
			(vias allowed)
			(pads allowed)
			(copperpour not_allowed)
			(footprints allowed)
		)
		(placement
			(enabled no)
			(sheetname "")
		)
		(fill
			(thermal_gap 0.5)
			(thermal_bridge_width 0.5)
			(island_removal_mode 0)
		)
		(polygon
			(pts
				(arc
					(start 450.8373 -307.232304)
					(mid 450.83358 -307.241284)
					(end 450.8246 -307.245004)
				)
				(arc
					(start 449.3514 -307.245004)
					(mid 449.34242 -307.241284)
					(end 449.3387 -307.232304)
				)
				(arc
					(start 449.3387 -306.737766)
					(mid 449.34242 -306.728786)
					(end 449.3514 -306.725066)
				)
				(arc
					(start 450.8246 -306.725066)
					(mid 450.83358 -306.728786)
					(end 450.8373 -306.737766)
				)
			)
		)
	)
	(zone
		(layer "In1.Cu")
		(hatch none 0.5)
		(connect_pads
			(clearance 0)
		)
		(min_thickness 0.25)
		(keepout
			(tracks not_allowed)
			(vias allowed)
			(pads allowed)
			(copperpour not_allowed)
			(footprints allowed)
		)
		(placement
			(enabled no)
			(sheetname "")
		)
		(fill
			(thermal_gap 0.5)
			(thermal_bridge_width 0.5)
			(island_removal_mode 0)
		)
		(polygon
			(pts
				(arc
					(start 22.45741 -309.782464)
					(mid 22.45369 -309.791444)
					(end 22.44471 -309.795164)
				)
				(arc
					(start 20.97151 -309.795164)
					(mid 20.96253 -309.791444)
					(end 20.95881 -309.782464)
				)
				(arc
					(start 20.95881 -309.287926)
					(mid 20.96253 -309.278946)
					(end 20.97151 -309.275226)
				)
				(arc
					(start 22.44471 -309.275226)
					(mid 22.45369 -309.278946)
					(end 22.45741 -309.287926)
				)
			)
		)
	)
	(zone
		(layer "In1.Cu")
		(hatch none 0.5)
		(connect_pads
			(clearance 0)
		)
		(min_thickness 0.25)
		(keepout
			(tracks not_allowed)
			(vias allowed)
			(pads allowed)
			(copperpour not_allowed)
			(footprints allowed)
		)
		(placement
			(enabled no)
			(sheetname "")
		)
		(fill
			(thermal_gap 0.5)
			(thermal_bridge_width 0.5)
			(island_removal_mode 0)
		)
		(polygon
			(pts
				(arc
					(start 187.809378 -307.232558)
					(mid 187.805658 -307.241538)
					(end 187.796678 -307.245258)
				)
				(arc
					(start 186.323478 -307.245258)
					(mid 186.314498 -307.241538)
					(end 186.310778 -307.232558)
				)
				(arc
					(start 186.310778 -306.73802)
					(mid 186.314498 -306.72904)
					(end 186.323478 -306.72532)
				)
				(arc
					(start 187.796678 -306.72532)
					(mid 187.805658 -306.72904)
					(end 187.809378 -306.73802)
				)
			)
		)
	)
	(zone
		(layer "In1.Cu")
		(hatch none 0.5)
		(connect_pads
			(clearance 0)
		)
		(min_thickness 0.25)
		(keepout
			(tracks not_allowed)
			(vias allowed)
			(pads allowed)
			(copperpour not_allowed)
			(footprints allowed)
		)
		(placement
			(enabled no)
			(sheetname "")
		)
		(fill
			(thermal_gap 0.5)
			(thermal_bridge_width 0.5)
			(island_removal_mode 0)
		)
		(polygon
			(pts
				(arc
					(start 365.939578 4.531614)
					(mid 365.91726 4.477732)
					(end 365.863378 4.455414)
				)
				(arc
					(start 365.251238 4.455414)
					(mid 365.197356 4.477732)
					(end 365.175038 4.531614)
				)
				(arc
					(start 365.175038 5.628894)
					(mid 365.197356 5.682776)
					(end 365.251238 5.705094)
				)
				(arc
					(start 365.863378 5.705094)
					(mid 365.91726 5.682776)
					(end 365.939578 5.628894)
				)
			)
		)
	)
	(zone
		(layer "In1.Cu")
		(hatch none 0.5)
		(connect_pads
			(clearance 0)
		)
		(min_thickness 0.25)
		(keepout
			(tracks not_allowed)
			(vias allowed)
			(pads allowed)
			(copperpour not_allowed)
			(footprints allowed)
		)
		(placement
			(enabled no)
			(sheetname "")
		)
		(fill
			(thermal_gap 0.5)
			(thermal_bridge_width 0.5)
			(island_removal_mode 0)
		)
		(polygon
			(pts
				(arc
					(start 320.2051 -381.824484)
					(mid 320.225024 -381.83372)
					(end 320.246756 -381.83693)
				)
				(arc
					(start 320.44132 -381.83693)
					(mid 320.495202 -381.814612)
					(end 320.51752 -381.76073)
				)
				(arc
					(start 320.51752 -381.07493)
					(mid 320.495202 -381.021048)
					(end 320.44132 -380.99873)
				)
				(arc
					(start 320.246756 -380.99873)
					(mid 320.225012 -381.001898)
					(end 320.2051 -381.011176)
				)
				(arc
					(start 319.908936 -381.203962)
					(mid 319.867252 -381.216184)
					(end 319.825624 -381.203708)
				)
				(arc
					(start 319.532 -381.011176)
					(mid 319.512076 -381.00194)
					(end 319.490344 -380.99873)
				)
				(arc
					(start 319.29578 -380.99873)
					(mid 319.241898 -381.021048)
					(end 319.21958 -381.07493)
				)
				(arc
					(start 319.21958 -381.76073)
					(mid 319.241898 -381.814612)
					(end 319.29578 -381.83693)
				)
				(arc
					(start 319.491614 -381.83693)
					(mid 319.513358 -381.833762)
					(end 319.53327 -381.824484)
				)
				(arc
					(start 319.826894 -381.631952)
					(mid 319.86855 -381.61955)
					(end 319.910206 -381.631952)
				)
			)
		)
	)
	(zone
		(layer "In1.Cu")
		(hatch none 0.5)
		(connect_pads
			(clearance 0)
		)
		(min_thickness 0.25)
		(keepout
			(tracks not_allowed)
			(vias allowed)
			(pads allowed)
			(copperpour not_allowed)
			(footprints allowed)
		)
		(placement
			(enabled no)
			(sheetname "")
		)
		(fill
			(thermal_gap 0.5)
			(thermal_bridge_width 0.5)
			(island_removal_mode 0)
		)
		(polygon
			(pts
				(arc
					(start 52.633372 -246.032528)
					(mid 52.629652 -246.041508)
					(end 52.620672 -246.045228)
				)
				(arc
					(start 51.147472 -246.045228)
					(mid 51.138492 -246.041508)
					(end 51.134772 -246.032528)
				)
				(arc
					(start 51.134772 -245.53799)
					(mid 51.138492 -245.52901)
					(end 51.147472 -245.52529)
				)
				(arc
					(start 52.620672 -245.52529)
					(mid 52.629652 -245.52901)
					(end 52.633372 -245.53799)
				)
			)
		)
	)
	(zone
		(layer "In1.Cu")
		(hatch none 0.5)
		(connect_pads
			(clearance 0)
		)
		(min_thickness 0.25)
		(keepout
			(tracks not_allowed)
			(vias allowed)
			(pads allowed)
			(copperpour not_allowed)
			(footprints allowed)
		)
		(placement
			(enabled no)
			(sheetname "")
		)
		(fill
			(thermal_gap 0.5)
			(thermal_bridge_width 0.5)
			(island_removal_mode 0)
		)
		(polygon
			(pts
				(arc
					(start 270.397478 -210.33232)
					(mid 270.393758 -210.3413)
					(end 270.384778 -210.34502)
				)
				(arc
					(start 268.911578 -210.34502)
					(mid 268.902598 -210.3413)
					(end 268.898878 -210.33232)
				)
				(arc
					(start 268.898878 -209.837782)
					(mid 268.902598 -209.828802)
					(end 268.911578 -209.825082)
				)
				(arc
					(start 270.384778 -209.825082)
					(mid 270.393758 -209.828802)
					(end 270.397478 -209.837782)
				)
			)
		)
	)
	(zone
		(layer "In1.Cu")
		(hatch none 0.5)
		(connect_pads
			(clearance 0)
		)
		(min_thickness 0.25)
		(keepout
			(tracks not_allowed)
			(vias allowed)
			(pads allowed)
			(copperpour not_allowed)
			(footprints allowed)
		)
		(placement
			(enabled no)
			(sheetname "")
		)
		(fill
			(thermal_gap 0.5)
			(thermal_bridge_width 0.5)
			(island_removal_mode 0)
		)
		(polygon
			(pts
				(arc
					(start 18.357342 -273.232372)
					(mid 18.353622 -273.241352)
					(end 18.344642 -273.245072)
				)
				(arc
					(start 16.871442 -273.245072)
					(mid 16.862462 -273.241352)
					(end 16.858742 -273.232372)
				)
				(arc
					(start 16.858742 -272.737834)
					(mid 16.862462 -272.728854)
					(end 16.871442 -272.725134)
				)
				(arc
					(start 18.344642 -272.725134)
					(mid 18.353622 -272.728854)
					(end 18.357342 -272.737834)
				)
			)
		)
	)
	(zone
		(layer "In1.Cu")
		(hatch none 0.5)
		(connect_pads
			(clearance 0)
		)
		(min_thickness 0.25)
		(keepout
			(tracks not_allowed)
			(vias allowed)
			(pads allowed)
			(copperpour not_allowed)
			(footprints allowed)
		)
		(placement
			(enabled no)
			(sheetname "")
		)
		(fill
			(thermal_gap 0.5)
			(thermal_bridge_width 0.5)
			(island_removal_mode 0)
		)
		(polygon
			(pts
				(arc
					(start 25.901396 -310.632348)
					(mid 25.897676 -310.641328)
					(end 25.888696 -310.645048)
				)
				(arc
					(start 24.415496 -310.645048)
					(mid 24.406516 -310.641328)
					(end 24.402796 -310.632348)
				)
				(arc
					(start 24.402796 -310.13781)
					(mid 24.406516 -310.12883)
					(end 24.415496 -310.12511)
				)
				(arc
					(start 25.888696 -310.12511)
					(mid 25.897676 -310.12883)
					(end 25.901396 -310.13781)
				)
			)
		)
	)
	(zone
		(layer "In1.Cu")
		(hatch none 0.5)
		(connect_pads
			(clearance 0)
		)
		(min_thickness 0.25)
		(keepout
			(tracks not_allowed)
			(vias allowed)
			(pads allowed)
			(copperpour not_allowed)
			(footprints allowed)
		)
		(placement
			(enabled no)
			(sheetname "")
		)
		(fill
			(thermal_gap 0.5)
			(thermal_bridge_width 0.5)
			(island_removal_mode 0)
		)
		(polygon
			(pts
				(arc
					(start 202.897232 -204.38237)
					(mid 202.893512 -204.39135)
					(end 202.884532 -204.39507)
				)
				(arc
					(start 201.411332 -204.39507)
					(mid 201.402352 -204.39135)
					(end 201.398632 -204.38237)
				)
				(arc
					(start 201.398632 -203.887832)
					(mid 201.402352 -203.878852)
					(end 201.411332 -203.875132)
				)
				(arc
					(start 202.884532 -203.875132)
					(mid 202.893512 -203.878852)
					(end 202.897232 -203.887832)
				)
			)
		)
	)
	(zone
		(layer "In1.Cu")
		(hatch none 0.5)
		(connect_pads
			(clearance 0)
		)
		(min_thickness 0.25)
		(keepout
			(tracks not_allowed)
			(vias allowed)
			(pads allowed)
			(copperpour not_allowed)
			(footprints allowed)
		)
		(placement
			(enabled no)
			(sheetname "")
		)
		(fill
			(thermal_gap 0.5)
			(thermal_bridge_width 0.5)
			(island_removal_mode 0)
		)
		(polygon
			(pts
				(arc
					(start 412.798006 -392.30427)
					(mid 412.493206 -392.30427)
					(end 412.798006 -392.30427)
				)
			)
		)
	)
	(zone
		(layer "In1.Cu")
		(hatch none 0.5)
		(connect_pads
			(clearance 0)
		)
		(min_thickness 0.25)
		(keepout
			(tracks not_allowed)
			(vias allowed)
			(pads allowed)
			(copperpour not_allowed)
			(footprints allowed)
		)
		(placement
			(enabled no)
			(sheetname "")
		)
		(fill
			(thermal_gap 0.5)
			(thermal_bridge_width 0.5)
			(island_removal_mode 0)
		)
		(polygon
			(pts
				(arc
					(start 450.8373 -204.382116)
					(mid 450.83358 -204.391096)
					(end 450.8246 -204.394816)
				)
				(arc
					(start 449.3514 -204.394816)
					(mid 449.34242 -204.391096)
					(end 449.3387 -204.382116)
				)
				(arc
					(start 449.3387 -203.887578)
					(mid 449.34242 -203.878598)
					(end 449.3514 -203.874878)
				)
				(arc
					(start 450.8246 -203.874878)
					(mid 450.83358 -203.878598)
					(end 450.8373 -203.887578)
				)
			)
		)
	)
	(zone
		(layer "In1.Cu")
		(hatch none 0.5)
		(connect_pads
			(clearance 0)
		)
		(min_thickness 0.25)
		(keepout
			(tracks not_allowed)
			(vias allowed)
			(pads allowed)
			(copperpour not_allowed)
			(footprints allowed)
		)
		(placement
			(enabled no)
			(sheetname "")
		)
		(fill
			(thermal_gap 0.5)
			(thermal_bridge_width 0.5)
			(island_removal_mode 0)
		)
		(polygon
			(pts
				(arc
					(start 176.821338 -272.382488)
					(mid 176.817618 -272.391468)
					(end 176.808638 -272.395188)
				)
				(arc
					(start 175.335438 -272.395188)
					(mid 175.326458 -272.391468)
					(end 175.322738 -272.382488)
				)
				(arc
					(start 175.322738 -271.88795)
					(mid 175.326458 -271.87897)
					(end 175.335438 -271.87525)
				)
				(arc
					(start 176.808638 -271.87525)
					(mid 176.817618 -271.87897)
					(end 176.821338 -271.88795)
				)
			)
		)
	)
	(zone
		(layer "In1.Cu")
		(hatch none 0.5)
		(connect_pads
			(clearance 0)
		)
		(min_thickness 0.25)
		(keepout
			(tracks not_allowed)
			(vias allowed)
			(pads allowed)
			(copperpour not_allowed)
			(footprints allowed)
		)
		(placement
			(enabled no)
			(sheetname "")
		)
		(fill
			(thermal_gap 0.5)
			(thermal_bridge_width 0.5)
			(island_removal_mode 0)
		)
		(polygon
			(pts
				(arc
					(start 165.177216 -308.93258)
					(mid 165.173496 -308.94156)
					(end 165.164516 -308.94528)
				)
				(arc
					(start 163.691316 -308.94528)
					(mid 163.682336 -308.94156)
					(end 163.678616 -308.93258)
				)
				(arc
					(start 163.678616 -308.438042)
					(mid 163.682336 -308.429062)
					(end 163.691316 -308.425342)
				)
				(arc
					(start 165.164516 -308.425342)
					(mid 165.173496 -308.429062)
					(end 165.177216 -308.438042)
				)
			)
		)
	)
	(zone
		(layer "In1.Cu")
		(hatch none 0.5)
		(connect_pads
			(clearance 0)
		)
		(min_thickness 0.25)
		(keepout
			(tracks not_allowed)
			(vias allowed)
			(pads allowed)
			(copperpour not_allowed)
			(footprints allowed)
		)
		(placement
			(enabled no)
			(sheetname "")
		)
		(fill
			(thermal_gap 0.5)
			(thermal_bridge_width 0.5)
			(island_removal_mode 0)
		)
		(polygon
			(pts
				(arc
					(start 88.788748 -389.467344)
					(mid 88.407748 -389.467344)
					(end 88.788748 -389.467344)
				)
			)
		)
	)
	(zone
		(layer "In1.Cu")
		(hatch none 0.5)
		(connect_pads
			(clearance 0)
		)
		(min_thickness 0.25)
		(keepout
			(tracks not_allowed)
			(vias allowed)
			(pads allowed)
			(copperpour not_allowed)
			(footprints allowed)
		)
		(placement
			(enabled no)
			(sheetname "")
		)
		(fill
			(thermal_gap 0.5)
			(thermal_bridge_width 0.5)
			(island_removal_mode 0)
		)
		(polygon
			(pts
				(arc
					(start 151.998172 -390.761474)
					(mid 151.693372 -390.761474)
					(end 151.998172 -390.761474)
				)
			)
		)
	)
	(zone
		(layer "In1.Cu")
		(hatch none 0.5)
		(connect_pads
			(clearance 0)
		)
		(min_thickness 0.25)
		(keepout
			(tracks not_allowed)
			(vias allowed)
			(pads allowed)
			(copperpour not_allowed)
			(footprints allowed)
		)
		(placement
			(enabled no)
			(sheetname "")
		)
		(fill
			(thermal_gap 0.5)
			(thermal_bridge_width 0.5)
			(island_removal_mode 0)
		)
		(polygon
			(pts
				(arc
					(start 172.72127 -241.782346)
					(mid 172.71755 -241.791326)
					(end 172.70857 -241.795046)
				)
				(arc
					(start 171.23537 -241.795046)
					(mid 171.22639 -241.791326)
					(end 171.22267 -241.782346)
				)
				(arc
					(start 171.22267 -241.287808)
					(mid 171.22639 -241.278828)
					(end 171.23537 -241.275108)
				)
				(arc
					(start 172.70857 -241.275108)
					(mid 172.71755 -241.278828)
					(end 172.72127 -241.287808)
				)
			)
		)
	)
	(zone
		(layer "In1.Cu")
		(hatch none 0.5)
		(connect_pads
			(clearance 0)
		)
		(min_thickness 0.25)
		(keepout
			(tracks not_allowed)
			(vias allowed)
			(pads allowed)
			(copperpour not_allowed)
			(footprints allowed)
		)
		(placement
			(enabled no)
			(sheetname "")
		)
		(fill
			(thermal_gap 0.5)
			(thermal_bridge_width 0.5)
			(island_removal_mode 0)
		)
		(polygon
			(pts
				(arc
					(start 420.661338 -215.432132)
					(mid 420.657618 -215.441112)
					(end 420.648638 -215.444832)
				)
				(arc
					(start 419.175438 -215.444832)
					(mid 419.166458 -215.441112)
					(end 419.162738 -215.432132)
				)
				(arc
					(start 419.162738 -214.937594)
					(mid 419.166458 -214.928614)
					(end 419.175438 -214.924894)
				)
				(arc
					(start 420.648638 -214.924894)
					(mid 420.657618 -214.928614)
					(end 420.661338 -214.937594)
				)
			)
		)
	)
	(zone
		(layer "In1.Cu")
		(hatch none 0.5)
		(connect_pads
			(clearance 0)
		)
		(min_thickness 0.25)
		(keepout
			(tracks not_allowed)
			(vias allowed)
			(pads allowed)
			(copperpour not_allowed)
			(footprints allowed)
		)
		(placement
			(enabled no)
			(sheetname "")
		)
		(fill
			(thermal_gap 0.5)
			(thermal_bridge_width 0.5)
			(island_removal_mode 0)
		)
		(polygon
			(pts
				(arc
					(start 265.87831 -227.935028)
					(mid 265.21791 -227.935028)
					(end 265.87831 -227.935028)
				)
			)
		)
	)
	(zone
		(layer "In1.Cu")
		(hatch none 0.5)
		(connect_pads
			(clearance 0)
		)
		(min_thickness 0.25)
		(keepout
			(tracks not_allowed)
			(vias allowed)
			(pads allowed)
			(copperpour not_allowed)
			(footprints allowed)
		)
		(placement
			(enabled no)
			(sheetname "")
		)
		(fill
			(thermal_gap 0.5)
			(thermal_bridge_width 0.5)
			(island_removal_mode 0)
		)
		(polygon
			(pts
				(arc
					(start 417.217352 -252.832108)
					(mid 417.213632 -252.841088)
					(end 417.204652 -252.844808)
				)
				(arc
					(start 415.731452 -252.844808)
					(mid 415.722472 -252.841088)
					(end 415.718752 -252.832108)
				)
				(arc
					(start 415.718752 -252.33757)
					(mid 415.722472 -252.32859)
					(end 415.731452 -252.32487)
				)
				(arc
					(start 417.204652 -252.32487)
					(mid 417.213632 -252.32859)
					(end 417.217352 -252.33757)
				)
			)
		)
	)
	(zone
		(layer "In1.Cu")
		(hatch none 0.5)
		(connect_pads
			(clearance 0)
		)
		(min_thickness 0.25)
		(keepout
			(tracks not_allowed)
			(vias allowed)
			(pads allowed)
			(copperpour not_allowed)
			(footprints allowed)
		)
		(placement
			(enabled no)
			(sheetname "")
		)
		(fill
			(thermal_gap 0.5)
			(thermal_bridge_width 0.5)
			(island_removal_mode 0)
		)
		(polygon
			(pts
				(arc
					(start 22.45741 -285.98241)
					(mid 22.45369 -285.99139)
					(end 22.44471 -285.99511)
				)
				(arc
					(start 20.97151 -285.99511)
					(mid 20.96253 -285.99139)
					(end 20.95881 -285.98241)
				)
				(arc
					(start 20.95881 -285.487872)
					(mid 20.96253 -285.478892)
					(end 20.97151 -285.475172)
				)
				(arc
					(start 22.44471 -285.475172)
					(mid 22.45369 -285.478892)
					(end 22.45741 -285.487872)
				)
			)
		)
	)
	(zone
		(layer "In1.Cu")
		(hatch none 0.5)
		(connect_pads
			(clearance 0)
		)
		(min_thickness 0.25)
		(keepout
			(tracks not_allowed)
			(vias allowed)
			(pads allowed)
			(copperpour not_allowed)
			(footprints allowed)
		)
		(placement
			(enabled no)
			(sheetname "")
		)
		(fill
			(thermal_gap 0.5)
			(thermal_bridge_width 0.5)
			(island_removal_mode 0)
		)
		(polygon
			(pts
				(arc
					(start 153.198068 -390.761474)
					(mid 152.893268 -390.761474)
					(end 153.198068 -390.761474)
				)
			)
		)
	)
	(zone
		(layer "In1.Cu")
		(hatch none 0.5)
		(connect_pads
			(clearance 0)
		)
		(min_thickness 0.25)
		(keepout
			(tracks not_allowed)
			(vias allowed)
			(pads allowed)
			(copperpour not_allowed)
			(footprints allowed)
		)
		(placement
			(enabled no)
			(sheetname "")
		)
		(fill
			(thermal_gap 0.5)
			(thermal_bridge_width 0.5)
			(island_removal_mode 0)
		)
		(polygon
			(pts
				(arc
					(start 206.5782 -287.43529)
					(mid 205.9178 -287.43529)
					(end 206.5782 -287.43529)
				)
			)
		)
	)
	(zone
		(layer "In1.Cu")
		(hatch none 0.5)
		(connect_pads
			(clearance 0)
		)
		(min_thickness 0.25)
		(keepout
			(tracks not_allowed)
			(vias allowed)
			(pads allowed)
			(copperpour not_allowed)
			(footprints allowed)
		)
		(placement
			(enabled no)
			(sheetname "")
		)
		(fill
			(thermal_gap 0.5)
			(thermal_bridge_width 0.5)
			(island_removal_mode 0)
		)
		(polygon
			(pts
				(arc
					(start 443.2935 -291.932106)
					(mid 443.28978 -291.941086)
					(end 443.2808 -291.944806)
				)
				(arc
					(start 441.8076 -291.944806)
					(mid 441.79862 -291.941086)
					(end 441.7949 -291.932106)
				)
				(arc
					(start 441.7949 -291.437568)
					(mid 441.79862 -291.428588)
					(end 441.8076 -291.424868)
				)
				(arc
					(start 443.2808 -291.424868)
					(mid 443.28978 -291.428588)
					(end 443.2935 -291.437568)
				)
			)
		)
	)
	(zone
		(layer "In1.Cu")
		(hatch none 0.5)
		(connect_pads
			(clearance 0)
		)
		(min_thickness 0.25)
		(keepout
			(tracks not_allowed)
			(vias allowed)
			(pads allowed)
			(copperpour not_allowed)
			(footprints allowed)
		)
		(placement
			(enabled no)
			(sheetname "")
		)
		(fill
			(thermal_gap 0.5)
			(thermal_bridge_width 0.5)
			(island_removal_mode 0)
		)
		(polygon
			(pts
				(arc
					(start 98.098102 -390.761474)
					(mid 97.793302 -390.761474)
					(end 98.098102 -390.761474)
				)
			)
		)
	)
	(zone
		(layer "In1.Cu")
		(hatch none 0.5)
		(connect_pads
			(clearance 0)
		)
		(min_thickness 0.25)
		(keepout
			(tracks not_allowed)
			(vias allowed)
			(pads allowed)
			(copperpour not_allowed)
			(footprints allowed)
		)
		(placement
			(enabled no)
			(sheetname "")
		)
		(fill
			(thermal_gap 0.5)
			(thermal_bridge_width 0.5)
			(island_removal_mode 0)
		)
		(polygon
			(pts
				(arc
					(start 191.909446 -223.932496)
					(mid 191.905726 -223.941476)
					(end 191.896746 -223.945196)
				)
				(arc
					(start 190.423546 -223.945196)
					(mid 190.414566 -223.941476)
					(end 190.410846 -223.932496)
				)
				(arc
					(start 190.410846 -223.437958)
					(mid 190.414566 -223.428978)
					(end 190.423546 -223.425258)
				)
				(arc
					(start 191.896746 -223.425258)
					(mid 191.905726 -223.428978)
					(end 191.909446 -223.437958)
				)
			)
		)
	)
	(zone
		(layer "In1.Cu")
		(hatch none 0.5)
		(connect_pads
			(clearance 0)
		)
		(min_thickness 0.25)
		(keepout
			(tracks not_allowed)
			(vias allowed)
			(pads allowed)
			(copperpour not_allowed)
			(footprints allowed)
		)
		(placement
			(enabled no)
			(sheetname "")
		)
		(fill
			(thermal_gap 0.5)
			(thermal_bridge_width 0.5)
			(island_removal_mode 0)
		)
		(polygon
			(pts
				(arc
					(start 81.91881 -391.319258)
					(mid 82.04581 -391.446258)
					(end 82.17281 -391.319258)
				)
				(arc
					(start 82.17281 -391.243058)
					(mid 82.04581 -391.116058)
					(end 81.91881 -391.243058)
				)
			)
		)
	)
	(zone
		(layer "In1.Cu")
		(hatch none 0.5)
		(connect_pads
			(clearance 0)
		)
		(min_thickness 0.25)
		(keepout
			(tracks not_allowed)
			(vias allowed)
			(pads allowed)
			(copperpour not_allowed)
			(footprints allowed)
		)
		(placement
			(enabled no)
			(sheetname "")
		)
		(fill
			(thermal_gap 0.5)
			(thermal_bridge_width 0.5)
			(island_removal_mode 0)
		)
		(polygon
			(pts
				(arc
					(start 270.397478 -205.232254)
					(mid 270.393758 -205.241234)
					(end 270.384778 -205.244954)
				)
				(arc
					(start 268.911578 -205.244954)
					(mid 268.902598 -205.241234)
					(end 268.898878 -205.232254)
				)
				(arc
					(start 268.898878 -204.737716)
					(mid 268.902598 -204.728736)
					(end 268.911578 -204.725016)
				)
				(arc
					(start 270.384778 -204.725016)
					(mid 270.393758 -204.728736)
					(end 270.397478 -204.737716)
				)
			)
		)
	)
	(zone
		(layer "In1.Cu")
		(hatch none 0.5)
		(connect_pads
			(clearance 0)
		)
		(min_thickness 0.25)
		(keepout
			(tracks not_allowed)
			(vias allowed)
			(pads allowed)
			(copperpour not_allowed)
			(footprints allowed)
		)
		(placement
			(enabled no)
			(sheetname "")
		)
		(fill
			(thermal_gap 0.5)
			(thermal_bridge_width 0.5)
			(island_removal_mode 0)
		)
		(polygon
			(pts
				(arc
					(start 273.841464 -243.482114)
					(mid 273.837744 -243.491094)
					(end 273.828764 -243.494814)
				)
				(arc
					(start 272.355564 -243.494814)
					(mid 272.346584 -243.491094)
					(end 272.342864 -243.482114)
				)
				(arc
					(start 272.342864 -242.987576)
					(mid 272.346584 -242.978596)
					(end 272.355564 -242.974876)
				)
				(arc
					(start 273.828764 -242.974876)
					(mid 273.837744 -242.978596)
					(end 273.841464 -242.987576)
				)
			)
		)
	)
	(zone
		(layer "In1.Cu")
		(hatch none 0.5)
		(connect_pads
			(clearance 0)
		)
		(min_thickness 0.25)
		(keepout
			(tracks not_allowed)
			(vias allowed)
			(pads allowed)
			(copperpour not_allowed)
			(footprints allowed)
		)
		(placement
			(enabled no)
			(sheetname "")
		)
		(fill
			(thermal_gap 0.5)
			(thermal_bridge_width 0.5)
			(island_removal_mode 0)
		)
		(polygon
			(pts
				(arc
					(start 172.72127 -221.382336)
					(mid 172.71755 -221.391316)
					(end 172.70857 -221.395036)
				)
				(arc
					(start 171.23537 -221.395036)
					(mid 171.22639 -221.391316)
					(end 171.22267 -221.382336)
				)
				(arc
					(start 171.22267 -220.887798)
					(mid 171.22639 -220.878818)
					(end 171.23537 -220.875098)
				)
				(arc
					(start 172.70857 -220.875098)
					(mid 172.71755 -220.878818)
					(end 172.72127 -220.887798)
				)
			)
		)
	)
	(zone
		(layer "In1.Cu")
		(hatch none 0.5)
		(connect_pads
			(clearance 0)
		)
		(min_thickness 0.25)
		(keepout
			(tracks not_allowed)
			(vias allowed)
			(pads allowed)
			(copperpour not_allowed)
			(footprints allowed)
		)
		(placement
			(enabled no)
			(sheetname "")
		)
		(fill
			(thermal_gap 0.5)
			(thermal_bridge_width 0.5)
			(island_removal_mode 0)
		)
		(polygon
			(pts
				(arc
					(start 165.177216 -235.832396)
					(mid 165.173496 -235.841376)
					(end 165.164516 -235.845096)
				)
				(arc
					(start 163.691316 -235.845096)
					(mid 163.682336 -235.841376)
					(end 163.678616 -235.832396)
				)
				(arc
					(start 163.678616 -235.337858)
					(mid 163.682336 -235.328878)
					(end 163.691316 -235.325158)
				)
				(arc
					(start 165.164516 -235.325158)
					(mid 165.173496 -235.328878)
					(end 165.177216 -235.337858)
				)
			)
		)
	)
	(zone
		(layer "In1.Cu")
		(hatch none 0.5)
		(connect_pads
			(clearance 0)
		)
		(min_thickness 0.25)
		(keepout
			(tracks not_allowed)
			(vias allowed)
			(pads allowed)
			(copperpour not_allowed)
			(footprints allowed)
		)
		(placement
			(enabled no)
			(sheetname "")
		)
		(fill
			(thermal_gap 0.5)
			(thermal_bridge_width 0.5)
			(island_removal_mode 0)
		)
		(polygon
			(pts
				(arc
					(start 348.388686 -397.849344)
					(mid 348.007686 -397.849344)
					(end 348.388686 -397.849344)
				)
			)
		)
	)
	(zone
		(layer "In1.Cu")
		(hatch none 0.5)
		(connect_pads
			(clearance 0)
		)
		(min_thickness 0.25)
		(keepout
			(tracks not_allowed)
			(vias allowed)
			(pads allowed)
			(copperpour not_allowed)
			(footprints allowed)
		)
		(placement
			(enabled no)
			(sheetname "")
		)
		(fill
			(thermal_gap 0.5)
			(thermal_bridge_width 0.5)
			(island_removal_mode 0)
		)
		(polygon
			(pts
				(arc
					(start 169.277284 -294.48252)
					(mid 169.273564 -294.4915)
					(end 169.264584 -294.49522)
				)
				(arc
					(start 167.791384 -294.49522)
					(mid 167.782404 -294.4915)
					(end 167.778684 -294.48252)
				)
				(arc
					(start 167.778684 -293.987982)
					(mid 167.782404 -293.979002)
					(end 167.791384 -293.975282)
				)
				(arc
					(start 169.264584 -293.975282)
					(mid 169.273564 -293.979002)
					(end 169.277284 -293.987982)
				)
			)
		)
	)
	(zone
		(layer "In1.Cu")
		(hatch none 0.5)
		(connect_pads
			(clearance 0)
		)
		(min_thickness 0.25)
		(keepout
			(tracks not_allowed)
			(vias allowed)
			(pads allowed)
			(copperpour not_allowed)
			(footprints allowed)
		)
		(placement
			(enabled no)
			(sheetname "")
		)
		(fill
			(thermal_gap 0.5)
			(thermal_bridge_width 0.5)
			(island_removal_mode 0)
		)
		(polygon
			(pts
				(arc
					(start 413.888936 -393.69238)
					(mid 413.507936 -393.69238)
					(end 413.888936 -393.69238)
				)
			)
		)
	)
	(zone
		(layer "In1.Cu")
		(hatch none 0.5)
		(connect_pads
			(clearance 0)
		)
		(min_thickness 0.25)
		(keepout
			(tracks not_allowed)
			(vias allowed)
			(pads allowed)
			(copperpour not_allowed)
			(footprints allowed)
		)
		(placement
			(enabled no)
			(sheetname "")
		)
		(fill
			(thermal_gap 0.5)
			(thermal_bridge_width 0.5)
			(island_removal_mode 0)
		)
		(polygon
			(pts
				(arc
					(start 454.937368 -266.432284)
					(mid 454.933648 -266.441264)
					(end 454.924668 -266.444984)
				)
				(arc
					(start 453.451468 -266.444984)
					(mid 453.442488 -266.441264)
					(end 453.438768 -266.432284)
				)
				(arc
					(start 453.438768 -265.937746)
					(mid 453.442488 -265.928766)
					(end 453.451468 -265.925046)
				)
				(arc
					(start 454.924668 -265.925046)
					(mid 454.933648 -265.928766)
					(end 454.937368 -265.937746)
				)
			)
		)
	)
	(zone
		(layer "In1.Cu")
		(hatch none 0.5)
		(connect_pads
			(clearance 0)
		)
		(min_thickness 0.25)
		(keepout
			(tracks not_allowed)
			(vias allowed)
			(pads allowed)
			(copperpour not_allowed)
			(footprints allowed)
		)
		(placement
			(enabled no)
			(sheetname "")
		)
		(fill
			(thermal_gap 0.5)
			(thermal_bridge_width 0.5)
			(island_removal_mode 0)
		)
		(polygon
			(pts
				(arc
					(start 199.4535 -236.682534)
					(mid 199.44978 -236.691514)
					(end 199.4408 -236.695234)
				)
				(arc
					(start 197.9676 -236.695234)
					(mid 197.95862 -236.691514)
					(end 197.9549 -236.682534)
				)
				(arc
					(start 197.9549 -236.187996)
					(mid 197.95862 -236.179016)
					(end 197.9676 -236.175296)
				)
				(arc
					(start 199.4408 -236.175296)
					(mid 199.44978 -236.179016)
					(end 199.4535 -236.187996)
				)
			)
		)
	)
	(zone
		(layer "In1.Cu")
		(hatch none 0.5)
		(connect_pads
			(clearance 0)
		)
		(min_thickness 0.25)
		(keepout
			(tracks not_allowed)
			(vias allowed)
			(pads allowed)
			(copperpour not_allowed)
			(footprints allowed)
		)
		(placement
			(enabled no)
			(sheetname "")
		)
		(fill
			(thermal_gap 0.5)
			(thermal_bridge_width 0.5)
			(island_removal_mode 0)
		)
		(polygon
			(pts
				(arc
					(start 169.277284 -219.682568)
					(mid 169.273564 -219.691548)
					(end 169.264584 -219.695268)
				)
				(arc
					(start 167.791384 -219.695268)
					(mid 167.782404 -219.691548)
					(end 167.778684 -219.682568)
				)
				(arc
					(start 167.778684 -219.18803)
					(mid 167.782404 -219.17905)
					(end 167.791384 -219.17533)
				)
				(arc
					(start 169.264584 -219.17533)
					(mid 169.273564 -219.17905)
					(end 169.277284 -219.18803)
				)
			)
		)
	)
	(zone
		(layer "In1.Cu")
		(hatch none 0.5)
		(connect_pads
			(clearance 0)
		)
		(min_thickness 0.25)
		(keepout
			(tracks not_allowed)
			(vias allowed)
			(pads allowed)
			(copperpour not_allowed)
			(footprints allowed)
		)
		(placement
			(enabled no)
			(sheetname "")
		)
		(fill
			(thermal_gap 0.5)
			(thermal_bridge_width 0.5)
			(island_removal_mode 0)
		)
		(polygon
			(pts
				(arc
					(start 199.4535 -220.532452)
					(mid 199.44978 -220.541432)
					(end 199.4408 -220.545152)
				)
				(arc
					(start 197.9676 -220.545152)
					(mid 197.95862 -220.541432)
					(end 197.9549 -220.532452)
				)
				(arc
					(start 197.9549 -220.037914)
					(mid 197.95862 -220.028934)
					(end 197.9676 -220.025214)
				)
				(arc
					(start 199.4408 -220.025214)
					(mid 199.44978 -220.028934)
					(end 199.4535 -220.037914)
				)
			)
		)
	)
	(zone
		(layer "In1.Cu")
		(hatch none 0.5)
		(connect_pads
			(clearance 0)
		)
		(min_thickness 0.25)
		(keepout
			(tracks not_allowed)
			(vias allowed)
			(pads allowed)
			(copperpour not_allowed)
			(footprints allowed)
		)
		(placement
			(enabled no)
			(sheetname "")
		)
		(fill
			(thermal_gap 0.5)
			(thermal_bridge_width 0.5)
			(island_removal_mode 0)
		)
		(polygon
			(pts
				(arc
					(start 285.485332 -217.982292)
					(mid 285.481612 -217.991272)
					(end 285.472632 -217.994992)
				)
				(arc
					(start 283.999432 -217.994992)
					(mid 283.990452 -217.991272)
					(end 283.986732 -217.982292)
				)
				(arc
					(start 283.986732 -217.487754)
					(mid 283.990452 -217.478774)
					(end 283.999432 -217.475054)
				)
				(arc
					(start 285.472632 -217.475054)
					(mid 285.481612 -217.478774)
					(end 285.485332 -217.487754)
				)
			)
		)
	)
	(zone
		(layer "In1.Cu")
		(hatch none 0.5)
		(connect_pads
			(clearance 0)
		)
		(min_thickness 0.25)
		(keepout
			(tracks not_allowed)
			(vias allowed)
			(pads allowed)
			(copperpour not_allowed)
			(footprints allowed)
		)
		(placement
			(enabled no)
			(sheetname "")
		)
		(fill
			(thermal_gap 0.5)
			(thermal_bridge_width 0.5)
			(island_removal_mode 0)
		)
		(polygon
			(pts
				(arc
					(start 372.161054 -397.849344)
					(mid 371.780054 -397.849344)
					(end 372.161054 -397.849344)
				)
			)
		)
	)
	(zone
		(layer "In1.Cu")
		(hatch none 0.5)
		(connect_pads
			(clearance 0)
		)
		(min_thickness 0.25)
		(keepout
			(tracks not_allowed)
			(vias allowed)
			(pads allowed)
			(copperpour not_allowed)
			(footprints allowed)
		)
		(placement
			(enabled no)
			(sheetname "")
		)
		(fill
			(thermal_gap 0.5)
			(thermal_bridge_width 0.5)
			(island_removal_mode 0)
		)
		(polygon
			(pts
				(arc
					(start 149.888702 -389.467344)
					(mid 149.507702 -389.467344)
					(end 149.888702 -389.467344)
				)
			)
		)
	)
	(zone
		(layer "In1.Cu")
		(hatch none 0.5)
		(connect_pads
			(clearance 0)
		)
		(min_thickness 0.25)
		(keepout
			(tracks not_allowed)
			(vias allowed)
			(pads allowed)
			(copperpour not_allowed)
			(footprints allowed)
		)
		(placement
			(enabled no)
			(sheetname "")
		)
		(fill
			(thermal_gap 0.5)
			(thermal_bridge_width 0.5)
			(island_removal_mode 0)
		)
		(polygon
			(pts
				(arc
					(start 30.001464 -292.782498)
					(mid 29.997744 -292.791478)
					(end 29.988764 -292.795198)
				)
				(arc
					(start 28.515564 -292.795198)
					(mid 28.506584 -292.791478)
					(end 28.502864 -292.782498)
				)
				(arc
					(start 28.502864 -292.28796)
					(mid 28.506584 -292.27898)
					(end 28.515564 -292.27526)
				)
				(arc
					(start 29.988764 -292.27526)
					(mid 29.997744 -292.27898)
					(end 30.001464 -292.28796)
				)
			)
		)
	)
	(zone
		(layer "In1.Cu")
		(hatch none 0.5)
		(connect_pads
			(clearance 0)
		)
		(min_thickness 0.25)
		(keepout
			(tracks not_allowed)
			(vias allowed)
			(pads allowed)
			(copperpour not_allowed)
			(footprints allowed)
		)
		(placement
			(enabled no)
			(sheetname "")
		)
		(fill
			(thermal_gap 0.5)
			(thermal_bridge_width 0.5)
			(island_removal_mode 0)
		)
		(polygon
			(pts
				(arc
					(start 58.37047 -383.92227)
					(mid 58.06567 -383.92227)
					(end 58.37047 -383.92227)
				)
			)
		)
	)
	(zone
		(layer "In1.Cu")
		(hatch none 0.5)
		(connect_pads
			(clearance 0)
		)
		(min_thickness 0.25)
		(keepout
			(tracks not_allowed)
			(vias allowed)
			(pads allowed)
			(copperpour not_allowed)
			(footprints allowed)
		)
		(placement
			(enabled no)
			(sheetname "")
		)
		(fill
			(thermal_gap 0.5)
			(thermal_bridge_width 0.5)
			(island_removal_mode 0)
		)
		(polygon
			(pts
				(arc
					(start 277.941532 -201.83221)
					(mid 277.937812 -201.84119)
					(end 277.928832 -201.84491)
				)
				(arc
					(start 276.455632 -201.84491)
					(mid 276.446652 -201.84119)
					(end 276.442932 -201.83221)
				)
				(arc
					(start 276.442932 -201.337672)
					(mid 276.446652 -201.328692)
					(end 276.455632 -201.324972)
				)
				(arc
					(start 277.928832 -201.324972)
					(mid 277.937812 -201.328692)
					(end 277.941532 -201.337672)
				)
			)
		)
	)
	(zone
		(layer "In1.Cu")
		(hatch none 0.5)
		(connect_pads
			(clearance 0)
		)
		(min_thickness 0.25)
		(keepout
			(tracks not_allowed)
			(vias allowed)
			(pads allowed)
			(copperpour not_allowed)
			(footprints allowed)
		)
		(placement
			(enabled no)
			(sheetname "")
		)
		(fill
			(thermal_gap 0.5)
			(thermal_bridge_width 0.5)
			(island_removal_mode 0)
		)
		(polygon
			(pts
				(arc
					(start 273.841464 -215.432132)
					(mid 273.837744 -215.441112)
					(end 273.828764 -215.444832)
				)
				(arc
					(start 272.355564 -215.444832)
					(mid 272.346584 -215.441112)
					(end 272.342864 -215.432132)
				)
				(arc
					(start 272.342864 -214.937594)
					(mid 272.346584 -214.928614)
					(end 272.355564 -214.924894)
				)
				(arc
					(start 273.828764 -214.924894)
					(mid 273.837744 -214.928614)
					(end 273.841464 -214.937594)
				)
			)
		)
	)
	(zone
		(layer "In1.Cu")
		(hatch none 0.5)
		(connect_pads
			(clearance 0)
		)
		(min_thickness 0.25)
		(keepout
			(tracks not_allowed)
			(vias allowed)
			(pads allowed)
			(copperpour not_allowed)
			(footprints allowed)
		)
		(placement
			(enabled no)
			(sheetname "")
		)
		(fill
			(thermal_gap 0.5)
			(thermal_bridge_width 0.5)
			(island_removal_mode 0)
		)
		(polygon
			(pts
				(arc
					(start 114.670332 -390.761474)
					(mid 114.365532 -390.761474)
					(end 114.670332 -390.761474)
				)
			)
		)
	)
	(zone
		(layer "In1.Cu")
		(hatch none 0.5)
		(connect_pads
			(clearance 0)
		)
		(min_thickness 0.25)
		(keepout
			(tracks not_allowed)
			(vias allowed)
			(pads allowed)
			(copperpour not_allowed)
			(footprints allowed)
		)
		(placement
			(enabled no)
			(sheetname "")
		)
		(fill
			(thermal_gap 0.5)
			(thermal_bridge_width 0.5)
			(island_removal_mode 0)
		)
		(polygon
			(pts
				(arc
					(start 413.088836 -394.385292)
					(mid 412.707836 -394.385292)
					(end 413.088836 -394.385292)
				)
			)
		)
	)
	(zone
		(layer "In1.Cu")
		(hatch none 0.5)
		(connect_pads
			(clearance 0)
		)
		(min_thickness 0.25)
		(keepout
			(tracks not_allowed)
			(vias allowed)
			(pads allowed)
			(copperpour not_allowed)
			(footprints allowed)
		)
		(placement
			(enabled no)
			(sheetname "")
		)
		(fill
			(thermal_gap 0.5)
			(thermal_bridge_width 0.5)
			(island_removal_mode 0)
		)
		(polygon
			(pts
				(arc
					(start 199.4535 -238.382556)
					(mid 199.44978 -238.391536)
					(end 199.4408 -238.395256)
				)
				(arc
					(start 197.9676 -238.395256)
					(mid 197.95862 -238.391536)
					(end 197.9549 -238.382556)
				)
				(arc
					(start 197.9549 -237.888018)
					(mid 197.95862 -237.879038)
					(end 197.9676 -237.875318)
				)
				(arc
					(start 199.4408 -237.875318)
					(mid 199.44978 -237.879038)
					(end 199.4535 -237.888018)
				)
			)
		)
	)
	(zone
		(layer "In1.Cu")
		(hatch none 0.5)
		(connect_pads
			(clearance 0)
		)
		(min_thickness 0.25)
		(keepout
			(tracks not_allowed)
			(vias allowed)
			(pads allowed)
			(copperpour not_allowed)
			(footprints allowed)
		)
		(placement
			(enabled no)
			(sheetname "")
		)
		(fill
			(thermal_gap 0.5)
			(thermal_bridge_width 0.5)
			(island_removal_mode 0)
		)
		(polygon
			(pts
				(arc
					(start 127.761238 -388.774432)
					(mid 127.380238 -388.774432)
					(end 127.761238 -388.774432)
				)
			)
		)
	)
	(zone
		(layer "In1.Cu")
		(hatch none 0.5)
		(connect_pads
			(clearance 0)
		)
		(min_thickness 0.25)
		(keepout
			(tracks not_allowed)
			(vias allowed)
			(pads allowed)
			(copperpour not_allowed)
			(footprints allowed)
		)
		(placement
			(enabled no)
			(sheetname "")
		)
		(fill
			(thermal_gap 0.5)
			(thermal_bridge_width 0.5)
			(island_removal_mode 0)
		)
		(polygon
			(pts
				(arc
					(start 165.177216 -285.98241)
					(mid 165.173496 -285.99139)
					(end 165.164516 -285.99511)
				)
				(arc
					(start 163.691316 -285.99511)
					(mid 163.682336 -285.99139)
					(end 163.678616 -285.98241)
				)
				(arc
					(start 163.678616 -285.487872)
					(mid 163.682336 -285.478892)
					(end 163.691316 -285.475172)
				)
				(arc
					(start 165.164516 -285.475172)
					(mid 165.173496 -285.478892)
					(end 165.177216 -285.487872)
				)
			)
		)
	)
	(zone
		(layer "In1.Cu")
		(hatch none 0.5)
		(connect_pads
			(clearance 0)
		)
		(min_thickness 0.25)
		(keepout
			(tracks not_allowed)
			(vias allowed)
			(pads allowed)
			(copperpour not_allowed)
			(footprints allowed)
		)
		(placement
			(enabled no)
			(sheetname "")
		)
		(fill
			(thermal_gap 0.5)
			(thermal_bridge_width 0.5)
			(island_removal_mode 0)
		)
		(polygon
			(pts
				(arc
					(start 176.821338 -263.032494)
					(mid 176.817618 -263.041474)
					(end 176.808638 -263.045194)
				)
				(arc
					(start 175.335438 -263.045194)
					(mid 175.326458 -263.041474)
					(end 175.322738 -263.032494)
				)
				(arc
					(start 175.322738 -262.537956)
					(mid 175.326458 -262.528976)
					(end 175.335438 -262.525256)
				)
				(arc
					(start 176.808638 -262.525256)
					(mid 176.817618 -262.528976)
					(end 176.821338 -262.537956)
				)
			)
		)
	)
	(zone
		(layer "In1.Cu")
		(hatch none 0.5)
		(connect_pads
			(clearance 0)
		)
		(min_thickness 0.25)
		(keepout
			(tracks not_allowed)
			(vias allowed)
			(pads allowed)
			(copperpour not_allowed)
			(footprints allowed)
		)
		(placement
			(enabled no)
			(sheetname "")
		)
		(fill
			(thermal_gap 0.5)
			(thermal_bridge_width 0.5)
			(island_removal_mode 0)
		)
		(polygon
			(pts
				(arc
					(start 266.29741 -285.982156)
					(mid 266.29369 -285.991136)
					(end 266.28471 -285.994856)
				)
				(arc
					(start 264.81151 -285.994856)
					(mid 264.80253 -285.991136)
					(end 264.79881 -285.982156)
				)
				(arc
					(start 264.79881 -285.487618)
					(mid 264.80253 -285.478638)
					(end 264.81151 -285.474918)
				)
				(arc
					(start 266.28471 -285.474918)
					(mid 266.29369 -285.478638)
					(end 266.29741 -285.487618)
				)
			)
		)
	)
	(zone
		(layer "In1.Cu")
		(hatch none 0.5)
		(connect_pads
			(clearance 0)
		)
		(min_thickness 0.25)
		(keepout
			(tracks not_allowed)
			(vias allowed)
			(pads allowed)
			(copperpour not_allowed)
			(footprints allowed)
		)
		(placement
			(enabled no)
			(sheetname "")
		)
		(fill
			(thermal_gap 0.5)
			(thermal_bridge_width 0.5)
			(island_removal_mode 0)
		)
		(polygon
			(pts
				(arc
					(start 25.901396 -241.782346)
					(mid 25.897676 -241.791326)
					(end 25.888696 -241.795046)
				)
				(arc
					(start 24.415496 -241.795046)
					(mid 24.406516 -241.791326)
					(end 24.402796 -241.782346)
				)
				(arc
					(start 24.402796 -241.287808)
					(mid 24.406516 -241.278828)
					(end 24.415496 -241.275108)
				)
				(arc
					(start 25.888696 -241.275108)
					(mid 25.897676 -241.278828)
					(end 25.901396 -241.287808)
				)
			)
		)
	)
	(zone
		(layer "In1.Cu")
		(hatch none 0.5)
		(connect_pads
			(clearance 0)
		)
		(min_thickness 0.25)
		(keepout
			(tracks not_allowed)
			(vias allowed)
			(pads allowed)
			(copperpour not_allowed)
			(footprints allowed)
		)
		(placement
			(enabled no)
			(sheetname "")
		)
		(fill
			(thermal_gap 0.5)
			(thermal_bridge_width 0.5)
			(island_removal_mode 0)
		)
		(polygon
			(pts
				(arc
					(start 428.205392 -288.532316)
					(mid 428.201672 -288.541296)
					(end 428.192692 -288.545016)
				)
				(arc
					(start 426.719492 -288.545016)
					(mid 426.710512 -288.541296)
					(end 426.706792 -288.532316)
				)
				(arc
					(start 426.706792 -288.037778)
					(mid 426.710512 -288.028798)
					(end 426.719492 -288.025078)
				)
				(arc
					(start 428.192692 -288.025078)
					(mid 428.201672 -288.028798)
					(end 428.205392 -288.037778)
				)
			)
		)
	)
	(zone
		(layer "In1.Cu")
		(hatch none 0.5)
		(connect_pads
			(clearance 0)
		)
		(min_thickness 0.25)
		(keepout
			(tracks not_allowed)
			(vias allowed)
			(pads allowed)
			(copperpour not_allowed)
			(footprints allowed)
		)
		(placement
			(enabled no)
			(sheetname "")
		)
		(fill
			(thermal_gap 0.5)
			(thermal_bridge_width 0.5)
			(island_removal_mode 0)
		)
		(polygon
			(pts
				(arc
					(start 374.161304 -393.69238)
					(mid 373.780304 -393.69238)
					(end 374.161304 -393.69238)
				)
			)
		)
	)
	(zone
		(layer "In1.Cu")
		(hatch none 0.5)
		(connect_pads
			(clearance 0)
		)
		(min_thickness 0.25)
		(keepout
			(tracks not_allowed)
			(vias allowed)
			(pads allowed)
			(copperpour not_allowed)
			(footprints allowed)
		)
		(placement
			(enabled no)
			(sheetname "")
		)
		(fill
			(thermal_gap 0.5)
			(thermal_bridge_width 0.5)
			(island_removal_mode 0)
		)
		(polygon
			(pts
				(arc
					(start 126.090934 -391.319258)
					(mid 126.217934 -391.446258)
					(end 126.344934 -391.319258)
				)
				(arc
					(start 126.344934 -391.243058)
					(mid 126.217934 -391.116058)
					(end 126.090934 -391.243058)
				)
			)
		)
	)
	(zone
		(layer "In1.Cu")
		(hatch none 0.5)
		(connect_pads
			(clearance 0)
		)
		(min_thickness 0.25)
		(keepout
			(tracks not_allowed)
			(vias allowed)
			(pads allowed)
			(copperpour not_allowed)
			(footprints allowed)
		)
		(placement
			(enabled no)
			(sheetname "")
		)
		(fill
			(thermal_gap 0.5)
			(thermal_bridge_width 0.5)
			(island_removal_mode 0)
		)
		(polygon
			(pts
				(arc
					(start 447.393568 -297.032172)
					(mid 447.389848 -297.041152)
					(end 447.380868 -297.044872)
				)
				(arc
					(start 445.907668 -297.044872)
					(mid 445.898688 -297.041152)
					(end 445.894968 -297.032172)
				)
				(arc
					(start 445.894968 -296.537634)
					(mid 445.898688 -296.528654)
					(end 445.907668 -296.524934)
				)
				(arc
					(start 447.380868 -296.524934)
					(mid 447.389848 -296.528654)
					(end 447.393568 -296.537634)
				)
			)
		)
	)
	(zone
		(layer "In1.Cu")
		(hatch none 0.5)
		(connect_pads
			(clearance 0)
		)
		(min_thickness 0.25)
		(keepout
			(tracks not_allowed)
			(vias allowed)
			(pads allowed)
			(copperpour not_allowed)
			(footprints allowed)
		)
		(placement
			(enabled no)
			(sheetname "")
		)
		(fill
			(thermal_gap 0.5)
			(thermal_bridge_width 0.5)
			(island_removal_mode 0)
		)
		(polygon
			(pts
				(arc
					(start 60.177426 -308.082442)
					(mid 60.173706 -308.091422)
					(end 60.164726 -308.095142)
				)
				(arc
					(start 58.691526 -308.095142)
					(mid 58.682546 -308.091422)
					(end 58.678826 -308.082442)
				)
				(arc
					(start 58.678826 -307.587904)
					(mid 58.682546 -307.578924)
					(end 58.691526 -307.575204)
				)
				(arc
					(start 60.164726 -307.575204)
					(mid 60.173706 -307.578924)
					(end 60.177426 -307.587904)
				)
			)
		)
	)
	(zone
		(layer "In1.Cu")
		(hatch none 0.5)
		(connect_pads
			(clearance 0)
		)
		(min_thickness 0.25)
		(keepout
			(tracks not_allowed)
			(vias allowed)
			(pads allowed)
			(copperpour not_allowed)
			(footprints allowed)
		)
		(placement
			(enabled no)
			(sheetname "")
		)
		(fill
			(thermal_gap 0.5)
			(thermal_bridge_width 0.5)
			(island_removal_mode 0)
		)
		(polygon
			(pts
				(arc
					(start 191.909446 -302.132492)
					(mid 191.905726 -302.141472)
					(end 191.896746 -302.145192)
				)
				(arc
					(start 190.423546 -302.145192)
					(mid 190.414566 -302.141472)
					(end 190.410846 -302.132492)
				)
				(arc
					(start 190.410846 -301.637954)
					(mid 190.414566 -301.628974)
					(end 190.423546 -301.625254)
				)
				(arc
					(start 191.896746 -301.625254)
					(mid 191.905726 -301.628974)
					(end 191.909446 -301.637954)
				)
			)
		)
	)
	(zone
		(layer "In1.Cu")
		(hatch none 0.5)
		(connect_pads
			(clearance 0)
		)
		(min_thickness 0.25)
		(keepout
			(tracks not_allowed)
			(vias allowed)
			(pads allowed)
			(copperpour not_allowed)
			(footprints allowed)
		)
		(placement
			(enabled no)
			(sheetname "")
		)
		(fill
			(thermal_gap 0.5)
			(thermal_bridge_width 0.5)
			(island_removal_mode 0)
		)
		(polygon
			(pts
				(arc
					(start 454.937368 -315.73216)
					(mid 454.933648 -315.74114)
					(end 454.924668 -315.74486)
				)
				(arc
					(start 453.451468 -315.74486)
					(mid 453.442488 -315.74114)
					(end 453.438768 -315.73216)
				)
				(arc
					(start 453.438768 -315.237622)
					(mid 453.442488 -315.228642)
					(end 453.451468 -315.224922)
				)
				(arc
					(start 454.924668 -315.224922)
					(mid 454.933648 -315.228642)
					(end 454.937368 -315.237622)
				)
			)
		)
	)
	(zone
		(layer "In1.Cu")
		(hatch none 0.5)
		(connect_pads
			(clearance 0)
		)
		(min_thickness 0.25)
		(keepout
			(tracks not_allowed)
			(vias allowed)
			(pads allowed)
			(copperpour not_allowed)
			(footprints allowed)
		)
		(placement
			(enabled no)
			(sheetname "")
		)
		(fill
			(thermal_gap 0.5)
			(thermal_bridge_width 0.5)
			(island_removal_mode 0)
		)
		(polygon
			(pts
				(arc
					(start 285.485332 -303.83226)
					(mid 285.481612 -303.84124)
					(end 285.472632 -303.84496)
				)
				(arc
					(start 283.999432 -303.84496)
					(mid 283.990452 -303.84124)
					(end 283.986732 -303.83226)
				)
				(arc
					(start 283.986732 -303.337722)
					(mid 283.990452 -303.328742)
					(end 283.999432 -303.325022)
				)
				(arc
					(start 285.472632 -303.325022)
					(mid 285.481612 -303.328742)
					(end 285.485332 -303.337722)
				)
			)
		)
	)
	(zone
		(layer "In1.Cu")
		(hatch none 0.5)
		(connect_pads
			(clearance 0)
		)
		(min_thickness 0.25)
		(keepout
			(tracks not_allowed)
			(vias allowed)
			(pads allowed)
			(copperpour not_allowed)
			(footprints allowed)
		)
		(placement
			(enabled no)
			(sheetname "")
		)
		(fill
			(thermal_gap 0.5)
			(thermal_bridge_width 0.5)
			(island_removal_mode 0)
		)
		(polygon
			(pts
				(arc
					(start 40.98925 -217.132408)
					(mid 40.98553 -217.141388)
					(end 40.97655 -217.145108)
				)
				(arc
					(start 39.50335 -217.145108)
					(mid 39.49437 -217.141388)
					(end 39.49065 -217.132408)
				)
				(arc
					(start 39.49065 -216.63787)
					(mid 39.49437 -216.62889)
					(end 39.50335 -216.62517)
				)
				(arc
					(start 40.97655 -216.62517)
					(mid 40.98553 -216.62889)
					(end 40.98925 -216.63787)
				)
			)
		)
	)
	(zone
		(layer "In1.Cu")
		(hatch none 0.5)
		(connect_pads
			(clearance 0)
		)
		(min_thickness 0.25)
		(keepout
			(tracks not_allowed)
			(vias allowed)
			(pads allowed)
			(copperpour not_allowed)
			(footprints allowed)
		)
		(placement
			(enabled no)
			(sheetname "")
		)
		(fill
			(thermal_gap 0.5)
			(thermal_bridge_width 0.5)
			(island_removal_mode 0)
		)
		(polygon
			(pts
				(arc
					(start 18.357342 -212.032342)
					(mid 18.353622 -212.041322)
					(end 18.344642 -212.045042)
				)
				(arc
					(start 16.871442 -212.045042)
					(mid 16.862462 -212.041322)
					(end 16.858742 -212.032342)
				)
				(arc
					(start 16.858742 -211.537804)
					(mid 16.862462 -211.528824)
					(end 16.871442 -211.525104)
				)
				(arc
					(start 18.344642 -211.525104)
					(mid 18.353622 -211.528824)
					(end 18.357342 -211.537804)
				)
			)
		)
	)
	(zone
		(layer "In1.Cu")
		(hatch none 0.5)
		(connect_pads
			(clearance 0)
		)
		(min_thickness 0.25)
		(keepout
			(tracks not_allowed)
			(vias allowed)
			(pads allowed)
			(copperpour not_allowed)
			(footprints allowed)
		)
		(placement
			(enabled no)
			(sheetname "")
		)
		(fill
			(thermal_gap 0.5)
			(thermal_bridge_width 0.5)
			(island_removal_mode 0)
		)
		(polygon
			(pts
				(arc
					(start 296.473372 -240.082324)
					(mid 296.469652 -240.091304)
					(end 296.460672 -240.095024)
				)
				(arc
					(start 294.987472 -240.095024)
					(mid 294.978492 -240.091304)
					(end 294.974772 -240.082324)
				)
				(arc
					(start 294.974772 -239.587786)
					(mid 294.978492 -239.578806)
					(end 294.987472 -239.575086)
				)
				(arc
					(start 296.460672 -239.575086)
					(mid 296.469652 -239.578806)
					(end 296.473372 -239.587786)
				)
			)
		)
	)
	(zone
		(layer "In1.Cu")
		(hatch none 0.5)
		(connect_pads
			(clearance 0)
		)
		(min_thickness 0.25)
		(keepout
			(tracks not_allowed)
			(vias allowed)
			(pads allowed)
			(copperpour not_allowed)
			(footprints allowed)
		)
		(placement
			(enabled no)
			(sheetname "")
		)
		(fill
			(thermal_gap 0.5)
			(thermal_bridge_width 0.5)
			(island_removal_mode 0)
		)
		(polygon
			(pts
				(arc
					(start 304.017426 -310.632094)
					(mid 304.013706 -310.641074)
					(end 304.004726 -310.644794)
				)
				(arc
					(start 302.531526 -310.644794)
					(mid 302.522546 -310.641074)
					(end 302.518826 -310.632094)
				)
				(arc
					(start 302.518826 -310.137556)
					(mid 302.522546 -310.128576)
					(end 302.531526 -310.124856)
				)
				(arc
					(start 304.004726 -310.124856)
					(mid 304.013706 -310.128576)
					(end 304.017426 -310.137556)
				)
			)
		)
	)
	(zone
		(layer "In1.Cu")
		(hatch none 0.5)
		(connect_pads
			(clearance 0)
		)
		(min_thickness 0.25)
		(keepout
			(tracks not_allowed)
			(vias allowed)
			(pads allowed)
			(copperpour not_allowed)
			(footprints allowed)
		)
		(placement
			(enabled no)
			(sheetname "")
		)
		(fill
			(thermal_gap 0.5)
			(thermal_bridge_width 0.5)
			(island_removal_mode 0)
		)
		(polygon
			(pts
				(arc
					(start 18.357342 -296.182542)
					(mid 18.353622 -296.191522)
					(end 18.344642 -296.195242)
				)
				(arc
					(start 16.871442 -296.195242)
					(mid 16.862462 -296.191522)
					(end 16.858742 -296.182542)
				)
				(arc
					(start 16.858742 -295.688004)
					(mid 16.862462 -295.679024)
					(end 16.871442 -295.675304)
				)
				(arc
					(start 18.344642 -295.675304)
					(mid 18.353622 -295.679024)
					(end 18.357342 -295.688004)
				)
			)
		)
	)
	(zone
		(layer "In1.Cu")
		(hatch none 0.5)
		(connect_pads
			(clearance 0)
		)
		(min_thickness 0.25)
		(keepout
			(tracks not_allowed)
			(vias allowed)
			(pads allowed)
			(copperpour not_allowed)
			(footprints allowed)
		)
		(placement
			(enabled no)
			(sheetname "")
		)
		(fill
			(thermal_gap 0.5)
			(thermal_bridge_width 0.5)
			(island_removal_mode 0)
		)
		(polygon
			(pts
				(arc
					(start 265.87831 -304.435002)
					(mid 265.21791 -304.435002)
					(end 265.87831 -304.435002)
				)
			)
		)
	)
	(zone
		(layer "In1.Cu")
		(hatch none 0.5)
		(connect_pads
			(clearance 0)
		)
		(min_thickness 0.25)
		(keepout
			(tracks not_allowed)
			(vias allowed)
			(pads allowed)
			(copperpour not_allowed)
			(footprints allowed)
		)
		(placement
			(enabled no)
			(sheetname "")
		)
		(fill
			(thermal_gap 0.5)
			(thermal_bridge_width 0.5)
			(island_removal_mode 0)
		)
		(polygon
			(pts
				(arc
					(start 311.390792 -391.822686)
					(mid 311.517792 -391.949686)
					(end 311.644792 -391.822686)
				)
				(arc
					(start 311.644792 -391.746486)
					(mid 311.517792 -391.619486)
					(end 311.390792 -391.746486)
				)
			)
		)
	)
	(zone
		(layer "In1.Cu")
		(hatch none 0.5)
		(connect_pads
			(clearance 0)
		)
		(min_thickness 0.25)
		(keepout
			(tracks not_allowed)
			(vias allowed)
			(pads allowed)
			(copperpour not_allowed)
			(footprints allowed)
		)
		(placement
			(enabled no)
			(sheetname "")
		)
		(fill
			(thermal_gap 0.5)
			(thermal_bridge_width 0.5)
			(island_removal_mode 0)
		)
		(polygon
			(pts
				(arc
					(start 439.849514 -283.43225)
					(mid 439.845794 -283.44123)
					(end 439.836814 -283.44495)
				)
				(arc
					(start 438.363614 -283.44495)
					(mid 438.354634 -283.44123)
					(end 438.350914 -283.43225)
				)
				(arc
					(start 438.350914 -282.937712)
					(mid 438.354634 -282.928732)
					(end 438.363614 -282.925012)
				)
				(arc
					(start 439.836814 -282.925012)
					(mid 439.845794 -282.928732)
					(end 439.849514 -282.937712)
				)
			)
		)
	)
	(zone
		(layer "In1.Cu")
		(hatch none 0.5)
		(connect_pads
			(clearance 0)
		)
		(min_thickness 0.25)
		(keepout
			(tracks not_allowed)
			(vias allowed)
			(pads allowed)
			(copperpour not_allowed)
			(footprints allowed)
		)
		(placement
			(enabled no)
			(sheetname "")
		)
		(fill
			(thermal_gap 0.5)
			(thermal_bridge_width 0.5)
			(island_removal_mode 0)
		)
		(polygon
			(pts
				(arc
					(start 184.365392 -269.832582)
					(mid 184.361672 -269.841562)
					(end 184.352692 -269.845282)
				)
				(arc
					(start 182.879492 -269.845282)
					(mid 182.870512 -269.841562)
					(end 182.866792 -269.832582)
				)
				(arc
					(start 182.866792 -269.338044)
					(mid 182.870512 -269.329064)
					(end 182.879492 -269.325344)
				)
				(arc
					(start 184.352692 -269.325344)
					(mid 184.361672 -269.329064)
					(end 184.365392 -269.338044)
				)
			)
		)
	)
	(zone
		(layer "In1.Cu")
		(hatch none 0.5)
		(connect_pads
			(clearance 0)
		)
		(min_thickness 0.25)
		(keepout
			(tracks not_allowed)
			(vias allowed)
			(pads allowed)
			(copperpour not_allowed)
			(footprints allowed)
		)
		(placement
			(enabled no)
			(sheetname "")
		)
		(fill
			(thermal_gap 0.5)
			(thermal_bridge_width 0.5)
			(island_removal_mode 0)
		)
		(polygon
			(pts
				(arc
					(start 300.57344 -264.732262)
					(mid 300.56972 -264.741242)
					(end 300.56074 -264.744962)
				)
				(arc
					(start 299.08754 -264.744962)
					(mid 299.07856 -264.741242)
					(end 299.07484 -264.732262)
				)
				(arc
					(start 299.07484 -264.237724)
					(mid 299.07856 -264.228744)
					(end 299.08754 -264.225024)
				)
				(arc
					(start 300.56074 -264.225024)
					(mid 300.56972 -264.228744)
					(end 300.57344 -264.237724)
				)
			)
		)
	)
	(zone
		(layer "In1.Cu")
		(hatch none 0.5)
		(connect_pads
			(clearance 0)
		)
		(min_thickness 0.25)
		(keepout
			(tracks not_allowed)
			(vias allowed)
			(pads allowed)
			(copperpour not_allowed)
			(footprints allowed)
		)
		(placement
			(enabled no)
			(sheetname "")
		)
		(fill
			(thermal_gap 0.5)
			(thermal_bridge_width 0.5)
			(island_removal_mode 0)
		)
		(polygon
			(pts
				(arc
					(start 80.098138 -390.761474)
					(mid 79.793338 -390.761474)
					(end 80.098138 -390.761474)
				)
			)
		)
	)
	(zone
		(layer "In1.Cu")
		(hatch none 0.5)
		(connect_pads
			(clearance 0)
		)
		(min_thickness 0.25)
		(keepout
			(tracks not_allowed)
			(vias allowed)
			(pads allowed)
			(copperpour not_allowed)
			(footprints allowed)
		)
		(placement
			(enabled no)
			(sheetname "")
		)
		(fill
			(thermal_gap 0.5)
			(thermal_bridge_width 0.5)
			(island_removal_mode 0)
		)
		(polygon
			(pts
				(arc
					(start 343.588594 -394.385292)
					(mid 343.207594 -394.385292)
					(end 343.588594 -394.385292)
				)
			)
		)
	)
	(zone
		(layer "In1.Cu")
		(hatch none 0.5)
		(connect_pads
			(clearance 0)
		)
		(min_thickness 0.25)
		(keepout
			(tracks not_allowed)
			(vias allowed)
			(pads allowed)
			(copperpour not_allowed)
			(footprints allowed)
		)
		(placement
			(enabled no)
			(sheetname "")
		)
		(fill
			(thermal_gap 0.5)
			(thermal_bridge_width 0.5)
			(island_removal_mode 0)
		)
		(polygon
			(pts
				(arc
					(start 435.749446 -248.58218)
					(mid 435.745726 -248.59116)
					(end 435.736746 -248.59488)
				)
				(arc
					(start 434.263546 -248.59488)
					(mid 434.254566 -248.59116)
					(end 434.250846 -248.58218)
				)
				(arc
					(start 434.250846 -248.087642)
					(mid 434.254566 -248.078662)
					(end 434.263546 -248.074942)
				)
				(arc
					(start 435.736746 -248.074942)
					(mid 435.745726 -248.078662)
					(end 435.749446 -248.087642)
				)
			)
		)
	)
	(zone
		(layer "In1.Cu")
		(hatch none 0.5)
		(connect_pads
			(clearance 0)
		)
		(min_thickness 0.25)
		(keepout
			(tracks not_allowed)
			(vias allowed)
			(pads allowed)
			(copperpour not_allowed)
			(footprints allowed)
		)
		(placement
			(enabled no)
			(sheetname "")
		)
		(fill
			(thermal_gap 0.5)
			(thermal_bridge_width 0.5)
			(island_removal_mode 0)
		)
		(polygon
			(pts
				(arc
					(start 270.397478 -247.732296)
					(mid 270.393758 -247.741276)
					(end 270.384778 -247.744996)
				)
				(arc
					(start 268.911578 -247.744996)
					(mid 268.902598 -247.741276)
					(end 268.898878 -247.732296)
				)
				(arc
					(start 268.898878 -247.237758)
					(mid 268.902598 -247.228778)
					(end 268.911578 -247.225058)
				)
				(arc
					(start 270.384778 -247.225058)
					(mid 270.393758 -247.228778)
					(end 270.397478 -247.237758)
				)
			)
		)
	)
	(zone
		(layer "In1.Cu")
		(hatch none 0.5)
		(connect_pads
			(clearance 0)
		)
		(min_thickness 0.25)
		(keepout
			(tracks not_allowed)
			(vias allowed)
			(pads allowed)
			(copperpour not_allowed)
			(footprints allowed)
		)
		(placement
			(enabled no)
			(sheetname "")
		)
		(fill
			(thermal_gap 0.5)
			(thermal_bridge_width 0.5)
			(island_removal_mode 0)
		)
		(polygon
			(pts
				(arc
					(start 281.385264 -307.232304)
					(mid 281.381544 -307.241284)
					(end 281.372564 -307.245004)
				)
				(arc
					(start 279.899364 -307.245004)
					(mid 279.890384 -307.241284)
					(end 279.886664 -307.232304)
				)
				(arc
					(start 279.886664 -306.737766)
					(mid 279.890384 -306.728786)
					(end 279.899364 -306.725066)
				)
				(arc
					(start 281.372564 -306.725066)
					(mid 281.381544 -306.728786)
					(end 281.385264 -306.737766)
				)
			)
		)
	)
	(zone
		(layer "In1.Cu")
		(hatch none 0.5)
		(connect_pads
			(clearance 0)
		)
		(min_thickness 0.25)
		(keepout
			(tracks not_allowed)
			(vias allowed)
			(pads allowed)
			(copperpour not_allowed)
			(footprints allowed)
		)
		(placement
			(enabled no)
			(sheetname "")
		)
		(fill
			(thermal_gap 0.5)
			(thermal_bridge_width 0.5)
			(island_removal_mode 0)
		)
		(polygon
			(pts
				(arc
					(start 48.533304 -286.832548)
					(mid 48.529584 -286.841528)
					(end 48.520604 -286.845248)
				)
				(arc
					(start 47.047404 -286.845248)
					(mid 47.038424 -286.841528)
					(end 47.034704 -286.832548)
				)
				(arc
					(start 47.034704 -286.33801)
					(mid 47.038424 -286.32903)
					(end 47.047404 -286.32531)
				)
				(arc
					(start 48.520604 -286.32531)
					(mid 48.529584 -286.32903)
					(end 48.533304 -286.33801)
				)
			)
		)
	)
	(zone
		(layer "In1.Cu")
		(hatch none 0.5)
		(connect_pads
			(clearance 0)
		)
		(min_thickness 0.25)
		(keepout
			(tracks not_allowed)
			(vias allowed)
			(pads allowed)
			(copperpour not_allowed)
			(footprints allowed)
		)
		(placement
			(enabled no)
			(sheetname "")
		)
		(fill
			(thermal_gap 0.5)
			(thermal_bridge_width 0.5)
			(island_removal_mode 0)
		)
		(polygon
			(pts
				(arc
					(start 450.8373 -226.482148)
					(mid 450.83358 -226.491128)
					(end 450.8246 -226.494848)
				)
				(arc
					(start 449.3514 -226.494848)
					(mid 449.34242 -226.491128)
					(end 449.3387 -226.482148)
				)
				(arc
					(start 449.3387 -225.98761)
					(mid 449.34242 -225.97863)
					(end 449.3514 -225.97491)
				)
				(arc
					(start 450.8246 -225.97491)
					(mid 450.83358 -225.97863)
					(end 450.8373 -225.98761)
				)
			)
		)
	)
	(zone
		(layer "In1.Cu")
		(hatch none 0.5)
		(connect_pads
			(clearance 0)
		)
		(min_thickness 0.25)
		(keepout
			(tracks not_allowed)
			(vias allowed)
			(pads allowed)
			(copperpour not_allowed)
			(footprints allowed)
		)
		(placement
			(enabled no)
			(sheetname "")
		)
		(fill
			(thermal_gap 0.5)
			(thermal_bridge_width 0.5)
			(island_removal_mode 0)
		)
		(polygon
			(pts
				(arc
					(start 403.198076 -399.143474)
					(mid 402.893276 -399.143474)
					(end 403.198076 -399.143474)
				)
			)
		)
	)
	(zone
		(layer "In1.Cu")
		(hatch none 0.5)
		(connect_pads
			(clearance 0)
		)
		(min_thickness 0.25)
		(keepout
			(tracks not_allowed)
			(vias allowed)
			(pads allowed)
			(copperpour not_allowed)
			(footprints allowed)
		)
		(placement
			(enabled no)
			(sheetname "")
		)
		(fill
			(thermal_gap 0.5)
			(thermal_bridge_width 0.5)
			(island_removal_mode 0)
		)
		(polygon
			(pts
				(arc
					(start 378.961142 -393.69238)
					(mid 378.580142 -393.69238)
					(end 378.961142 -393.69238)
				)
			)
		)
	)
	(zone
		(layer "In1.Cu")
		(hatch none 0.5)
		(connect_pads
			(clearance 0)
		)
		(min_thickness 0.25)
		(keepout
			(tracks not_allowed)
			(vias allowed)
			(pads allowed)
			(copperpour not_allowed)
			(footprints allowed)
		)
		(placement
			(enabled no)
			(sheetname "")
		)
		(fill
			(thermal_gap 0.5)
			(thermal_bridge_width 0.5)
			(island_removal_mode 0)
		)
		(polygon
			(pts
				(arc
					(start 165.177216 -262.182356)
					(mid 165.173496 -262.191336)
					(end 165.164516 -262.195056)
				)
				(arc
					(start 163.691316 -262.195056)
					(mid 163.682336 -262.191336)
					(end 163.678616 -262.182356)
				)
				(arc
					(start 163.678616 -261.687818)
					(mid 163.682336 -261.678838)
					(end 163.691316 -261.675118)
				)
				(arc
					(start 165.164516 -261.675118)
					(mid 165.173496 -261.678838)
					(end 165.177216 -261.687818)
				)
			)
		)
	)
	(zone
		(layer "In1.Cu")
		(hatch none 0.5)
		(connect_pads
			(clearance 0)
		)
		(min_thickness 0.25)
		(keepout
			(tracks not_allowed)
			(vias allowed)
			(pads allowed)
			(copperpour not_allowed)
			(footprints allowed)
		)
		(placement
			(enabled no)
			(sheetname "")
		)
		(fill
			(thermal_gap 0.5)
			(thermal_bridge_width 0.5)
			(island_removal_mode 0)
		)
		(polygon
			(pts
				(arc
					(start 195.353432 -206.082392)
					(mid 195.349712 -206.091372)
					(end 195.340732 -206.095092)
				)
				(arc
					(start 193.867532 -206.095092)
					(mid 193.858552 -206.091372)
					(end 193.854832 -206.082392)
				)
				(arc
					(start 193.854832 -205.587854)
					(mid 193.858552 -205.578874)
					(end 193.867532 -205.575154)
				)
				(arc
					(start 195.340732 -205.575154)
					(mid 195.349712 -205.578874)
					(end 195.353432 -205.587854)
				)
			)
		)
	)
	(zone
		(layer "In1.Cu")
		(hatch none 0.5)
		(connect_pads
			(clearance 0)
		)
		(min_thickness 0.25)
		(keepout
			(tracks not_allowed)
			(vias allowed)
			(pads allowed)
			(copperpour not_allowed)
			(footprints allowed)
		)
		(placement
			(enabled no)
			(sheetname "")
		)
		(fill
			(thermal_gap 0.5)
			(thermal_bridge_width 0.5)
			(island_removal_mode 0)
		)
		(polygon
			(pts
				(arc
					(start 45.089318 -300.43247)
					(mid 45.085598 -300.44145)
					(end 45.076618 -300.44517)
				)
				(arc
					(start 43.603418 -300.44517)
					(mid 43.594438 -300.44145)
					(end 43.590718 -300.43247)
				)
				(arc
					(start 43.590718 -299.937932)
					(mid 43.594438 -299.928952)
					(end 43.603418 -299.925232)
				)
				(arc
					(start 45.076618 -299.925232)
					(mid 45.085598 -299.928952)
					(end 45.089318 -299.937932)
				)
			)
		)
	)
	(zone
		(layer "In1.Cu")
		(hatch none 0.5)
		(connect_pads
			(clearance 0)
		)
		(min_thickness 0.25)
		(keepout
			(tracks not_allowed)
			(vias allowed)
			(pads allowed)
			(copperpour not_allowed)
			(footprints allowed)
		)
		(placement
			(enabled no)
			(sheetname "")
		)
		(fill
			(thermal_gap 0.5)
			(thermal_bridge_width 0.5)
			(island_removal_mode 0)
		)
		(polygon
			(pts
				(arc
					(start 18.357342 -202.682348)
					(mid 18.353622 -202.691328)
					(end 18.344642 -202.695048)
				)
				(arc
					(start 16.871442 -202.695048)
					(mid 16.862462 -202.691328)
					(end 16.858742 -202.682348)
				)
				(arc
					(start 16.858742 -202.18781)
					(mid 16.862462 -202.17883)
					(end 16.871442 -202.17511)
				)
				(arc
					(start 18.344642 -202.17511)
					(mid 18.353622 -202.17883)
					(end 18.357342 -202.18781)
				)
			)
		)
	)
	(zone
		(layer "In1.Cu")
		(hatch none 0.5)
		(connect_pads
			(clearance 0)
		)
		(min_thickness 0.25)
		(keepout
			(tracks not_allowed)
			(vias allowed)
			(pads allowed)
			(copperpour not_allowed)
			(footprints allowed)
		)
		(placement
			(enabled no)
			(sheetname "")
		)
		(fill
			(thermal_gap 0.5)
			(thermal_bridge_width 0.5)
			(island_removal_mode 0)
		)
		(polygon
			(pts
				(arc
					(start 195.353432 -290.232592)
					(mid 195.349712 -290.241572)
					(end 195.340732 -290.245292)
				)
				(arc
					(start 193.867532 -290.245292)
					(mid 193.858552 -290.241572)
					(end 193.854832 -290.232592)
				)
				(arc
					(start 193.854832 -289.738054)
					(mid 193.858552 -289.729074)
					(end 193.867532 -289.725354)
				)
				(arc
					(start 195.340732 -289.725354)
					(mid 195.349712 -289.729074)
					(end 195.353432 -289.738054)
				)
			)
		)
	)
	(zone
		(layer "In1.Cu")
		(hatch none 0.5)
		(connect_pads
			(clearance 0)
		)
		(min_thickness 0.25)
		(keepout
			(tracks not_allowed)
			(vias allowed)
			(pads allowed)
			(copperpour not_allowed)
			(footprints allowed)
		)
		(placement
			(enabled no)
			(sheetname "")
		)
		(fill
			(thermal_gap 0.5)
			(thermal_bridge_width 0.5)
			(island_removal_mode 0)
		)
		(polygon
			(pts
				(arc
					(start 195.353432 -274.932394)
					(mid 195.349712 -274.941374)
					(end 195.340732 -274.945094)
				)
				(arc
					(start 193.867532 -274.945094)
					(mid 193.858552 -274.941374)
					(end 193.854832 -274.932394)
				)
				(arc
					(start 193.854832 -274.437856)
					(mid 193.858552 -274.428876)
					(end 193.867532 -274.425156)
				)
				(arc
					(start 195.340732 -274.425156)
					(mid 195.349712 -274.428876)
					(end 195.353432 -274.437856)
				)
			)
		)
	)
	(zone
		(layer "In1.Cu")
		(hatch none 0.5)
		(connect_pads
			(clearance 0)
		)
		(min_thickness 0.25)
		(keepout
			(tracks not_allowed)
			(vias allowed)
			(pads allowed)
			(copperpour not_allowed)
			(footprints allowed)
		)
		(placement
			(enabled no)
			(sheetname "")
		)
		(fill
			(thermal_gap 0.5)
			(thermal_bridge_width 0.5)
			(island_removal_mode 0)
		)
		(polygon
			(pts
				(arc
					(start 417.217352 -303.83226)
					(mid 417.213632 -303.84124)
					(end 417.204652 -303.84496)
				)
				(arc
					(start 415.731452 -303.84496)
					(mid 415.722472 -303.84124)
					(end 415.718752 -303.83226)
				)
				(arc
					(start 415.718752 -303.337722)
					(mid 415.722472 -303.328742)
					(end 415.731452 -303.325022)
				)
				(arc
					(start 417.204652 -303.325022)
					(mid 417.213632 -303.328742)
					(end 417.217352 -303.337722)
				)
			)
		)
	)
	(zone
		(layer "In1.Cu")
		(hatch none 0.5)
		(connect_pads
			(clearance 0)
		)
		(min_thickness 0.25)
		(keepout
			(tracks not_allowed)
			(vias allowed)
			(pads allowed)
			(copperpour not_allowed)
			(footprints allowed)
		)
		(placement
			(enabled no)
			(sheetname "")
		)
		(fill
			(thermal_gap 0.5)
			(thermal_bridge_width 0.5)
			(island_removal_mode 0)
		)
		(polygon
			(pts
				(arc
					(start 56.077358 -248.582434)
					(mid 56.073638 -248.591414)
					(end 56.064658 -248.595134)
				)
				(arc
					(start 54.591458 -248.595134)
					(mid 54.582478 -248.591414)
					(end 54.578758 -248.582434)
				)
				(arc
					(start 54.578758 -248.087896)
					(mid 54.582478 -248.078916)
					(end 54.591458 -248.075196)
				)
				(arc
					(start 56.064658 -248.075196)
					(mid 56.073638 -248.078916)
					(end 56.077358 -248.087896)
				)
			)
		)
	)
	(zone
		(layer "In1.Cu")
		(hatch none 0.5)
		(connect_pads
			(clearance 0)
		)
		(min_thickness 0.25)
		(keepout
			(tracks not_allowed)
			(vias allowed)
			(pads allowed)
			(copperpour not_allowed)
			(footprints allowed)
		)
		(placement
			(enabled no)
			(sheetname "")
		)
		(fill
			(thermal_gap 0.5)
			(thermal_bridge_width 0.5)
			(island_removal_mode 0)
		)
		(polygon
			(pts
				(arc
					(start 403.488906 -397.849344)
					(mid 403.107906 -397.849344)
					(end 403.488906 -397.849344)
				)
			)
		)
	)
	(zone
		(layer "In1.Cu")
		(hatch none 0.5)
		(connect_pads
			(clearance 0)
		)
		(min_thickness 0.25)
		(keepout
			(tracks not_allowed)
			(vias allowed)
			(pads allowed)
			(copperpour not_allowed)
			(footprints allowed)
		)
		(placement
			(enabled no)
			(sheetname "")
		)
		(fill
			(thermal_gap 0.5)
			(thermal_bridge_width 0.5)
			(island_removal_mode 0)
		)
		(polygon
			(pts
				(arc
					(start 52.633372 -306.38242)
					(mid 52.629652 -306.3914)
					(end 52.620672 -306.39512)
				)
				(arc
					(start 51.147472 -306.39512)
					(mid 51.138492 -306.3914)
					(end 51.134772 -306.38242)
				)
				(arc
					(start 51.134772 -305.887882)
					(mid 51.138492 -305.878902)
					(end 51.147472 -305.875182)
				)
				(arc
					(start 52.620672 -305.875182)
					(mid 52.629652 -305.878902)
					(end 52.633372 -305.887882)
				)
			)
		)
	)
	(zone
		(layer "In1.Cu")
		(hatch none 0.5)
		(connect_pads
			(clearance 0)
		)
		(min_thickness 0.25)
		(keepout
			(tracks not_allowed)
			(vias allowed)
			(pads allowed)
			(copperpour not_allowed)
			(footprints allowed)
		)
		(placement
			(enabled no)
			(sheetname "")
		)
		(fill
			(thermal_gap 0.5)
			(thermal_bridge_width 0.5)
			(island_removal_mode 0)
		)
		(polygon
			(pts
				(arc
					(start 293.029386 -313.182254)
					(mid 293.025666 -313.191234)
					(end 293.016686 -313.194954)
				)
				(arc
					(start 291.543486 -313.194954)
					(mid 291.534506 -313.191234)
					(end 291.530786 -313.182254)
				)
				(arc
					(start 291.530786 -312.687716)
					(mid 291.534506 -312.678736)
					(end 291.543486 -312.675016)
				)
				(arc
					(start 293.016686 -312.675016)
					(mid 293.025666 -312.678736)
					(end 293.029386 -312.687716)
				)
			)
		)
	)
	(zone
		(layer "In1.Cu")
		(hatch none 0.5)
		(connect_pads
			(clearance 0)
		)
		(min_thickness 0.25)
		(keepout
			(tracks not_allowed)
			(vias allowed)
			(pads allowed)
			(copperpour not_allowed)
			(footprints allowed)
		)
		(placement
			(enabled no)
			(sheetname "")
		)
		(fill
			(thermal_gap 0.5)
			(thermal_bridge_width 0.5)
			(island_removal_mode 0)
		)
		(polygon
			(pts
				(arc
					(start 435.749446 -295.33215)
					(mid 435.745726 -295.34113)
					(end 435.736746 -295.34485)
				)
				(arc
					(start 434.263546 -295.34485)
					(mid 434.254566 -295.34113)
					(end 434.250846 -295.33215)
				)
				(arc
					(start 434.250846 -294.837612)
					(mid 434.254566 -294.828632)
					(end 434.263546 -294.824912)
				)
				(arc
					(start 435.736746 -294.824912)
					(mid 435.745726 -294.828632)
					(end 435.749446 -294.837612)
				)
			)
		)
	)
	(zone
		(layer "In1.Cu")
		(hatch none 0.5)
		(connect_pads
			(clearance 0)
		)
		(min_thickness 0.25)
		(keepout
			(tracks not_allowed)
			(vias allowed)
			(pads allowed)
			(copperpour not_allowed)
			(footprints allowed)
		)
		(placement
			(enabled no)
			(sheetname "")
		)
		(fill
			(thermal_gap 0.5)
			(thermal_bridge_width 0.5)
			(island_removal_mode 0)
		)
		(polygon
			(pts
				(arc
					(start 321.9069 -379.360684)
					(mid 321.926824 -379.36992)
					(end 321.948556 -379.37313)
				)
				(arc
					(start 322.14312 -379.37313)
					(mid 322.197002 -379.350812)
					(end 322.21932 -379.29693)
				)
				(arc
					(start 322.21932 -378.61113)
					(mid 322.197002 -378.557248)
					(end 322.14312 -378.53493)
				)
				(arc
					(start 321.948556 -378.53493)
					(mid 321.926812 -378.538098)
					(end 321.9069 -378.547376)
				)
				(arc
					(start 321.610736 -378.740162)
					(mid 321.569052 -378.752384)
					(end 321.527424 -378.739908)
				)
				(arc
					(start 321.2338 -378.547376)
					(mid 321.213876 -378.53814)
					(end 321.192144 -378.53493)
				)
				(arc
					(start 320.99758 -378.53493)
					(mid 320.943698 -378.557248)
					(end 320.92138 -378.61113)
				)
				(arc
					(start 320.92138 -379.29693)
					(mid 320.943698 -379.350812)
					(end 320.99758 -379.37313)
				)
				(arc
					(start 321.193414 -379.37313)
					(mid 321.215158 -379.369962)
					(end 321.23507 -379.360684)
				)
				(arc
					(start 321.528694 -379.168152)
					(mid 321.57035 -379.15575)
					(end 321.612006 -379.168152)
				)
			)
		)
	)
	(zone
		(layer "In1.Cu")
		(hatch none 0.5)
		(connect_pads
			(clearance 0)
		)
		(min_thickness 0.25)
		(keepout
			(tracks not_allowed)
			(vias allowed)
			(pads allowed)
			(copperpour not_allowed)
			(footprints allowed)
		)
		(placement
			(enabled no)
			(sheetname "")
		)
		(fill
			(thermal_gap 0.5)
			(thermal_bridge_width 0.5)
			(island_removal_mode 0)
		)
		(polygon
			(pts
				(arc
					(start 40.98925 -250.282456)
					(mid 40.98553 -250.291436)
					(end 40.97655 -250.295156)
				)
				(arc
					(start 39.50335 -250.295156)
					(mid 39.49437 -250.291436)
					(end 39.49065 -250.282456)
				)
				(arc
					(start 39.49065 -249.787918)
					(mid 39.49437 -249.778938)
					(end 39.50335 -249.775218)
				)
				(arc
					(start 40.97655 -249.775218)
					(mid 40.98553 -249.778938)
					(end 40.98925 -249.787918)
				)
			)
		)
	)
	(zone
		(layer "In1.Cu")
		(hatch none 0.5)
		(connect_pads
			(clearance 0)
		)
		(min_thickness 0.25)
		(keepout
			(tracks not_allowed)
			(vias allowed)
			(pads allowed)
			(copperpour not_allowed)
			(footprints allowed)
		)
		(placement
			(enabled no)
			(sheetname "")
		)
		(fill
			(thermal_gap 0.5)
			(thermal_bridge_width 0.5)
			(island_removal_mode 0)
		)
		(polygon
			(pts
				(arc
					(start 432.30546 -227.332286)
					(mid 432.30174 -227.341266)
					(end 432.29276 -227.344986)
				)
				(arc
					(start 430.81956 -227.344986)
					(mid 430.81058 -227.341266)
					(end 430.80686 -227.332286)
				)
				(arc
					(start 430.80686 -226.837748)
					(mid 430.81058 -226.828768)
					(end 430.81956 -226.825048)
				)
				(arc
					(start 432.29276 -226.825048)
					(mid 432.30174 -226.828768)
					(end 432.30546 -226.837748)
				)
			)
		)
	)
	(zone
		(layer "In1.Cu")
		(hatch none 0.5)
		(connect_pads
			(clearance 0)
		)
		(min_thickness 0.25)
		(keepout
			(tracks not_allowed)
			(vias allowed)
			(pads allowed)
			(copperpour not_allowed)
			(footprints allowed)
		)
		(placement
			(enabled no)
			(sheetname "")
		)
		(fill
			(thermal_gap 0.5)
			(thermal_bridge_width 0.5)
			(island_removal_mode 0)
		)
		(polygon
			(pts
				(arc
					(start 409.198064 -392.30427)
					(mid 408.893264 -392.30427)
					(end 409.198064 -392.30427)
				)
			)
		)
	)
	(zone
		(layer "In1.Cu")
		(hatch none 0.5)
		(connect_pads
			(clearance 0)
		)
		(min_thickness 0.25)
		(keepout
			(tracks not_allowed)
			(vias allowed)
			(pads allowed)
			(copperpour not_allowed)
			(footprints allowed)
		)
		(placement
			(enabled no)
			(sheetname "")
		)
		(fill
			(thermal_gap 0.5)
			(thermal_bridge_width 0.5)
			(island_removal_mode 0)
		)
		(polygon
			(pts
				(arc
					(start 158.618682 -391.319258)
					(mid 158.745682 -391.446258)
					(end 158.872682 -391.319258)
				)
				(arc
					(start 158.872682 -391.243058)
					(mid 158.745682 -391.116058)
					(end 158.618682 -391.243058)
				)
			)
		)
	)
	(zone
		(layer "In1.Cu")
		(hatch none 0.5)
		(connect_pads
			(clearance 0)
		)
		(min_thickness 0.25)
		(keepout
			(tracks not_allowed)
			(vias allowed)
			(pads allowed)
			(copperpour not_allowed)
			(footprints allowed)
		)
		(placement
			(enabled no)
			(sheetname "")
		)
		(fill
			(thermal_gap 0.5)
			(thermal_bridge_width 0.5)
			(island_removal_mode 0)
		)
		(polygon
			(pts
				(arc
					(start 281.385264 -198.432166)
					(mid 281.381544 -198.441146)
					(end 281.372564 -198.444866)
				)
				(arc
					(start 279.899364 -198.444866)
					(mid 279.890384 -198.441146)
					(end 279.886664 -198.432166)
				)
				(arc
					(start 279.886664 -197.937628)
					(mid 279.890384 -197.928648)
					(end 279.899364 -197.924928)
				)
				(arc
					(start 281.372564 -197.924928)
					(mid 281.381544 -197.928648)
					(end 281.385264 -197.937628)
				)
			)
		)
	)
	(zone
		(layer "In1.Cu")
		(hatch none 0.5)
		(connect_pads
			(clearance 0)
		)
		(min_thickness 0.25)
		(keepout
			(tracks not_allowed)
			(vias allowed)
			(pads allowed)
			(copperpour not_allowed)
			(footprints allowed)
		)
		(placement
			(enabled no)
			(sheetname "")
		)
		(fill
			(thermal_gap 0.5)
			(thermal_bridge_width 0.5)
			(island_removal_mode 0)
		)
		(polygon
			(pts
				(arc
					(start 206.9973 -275.782532)
					(mid 206.99358 -275.791512)
					(end 206.9846 -275.795232)
				)
				(arc
					(start 205.5114 -275.795232)
					(mid 205.50242 -275.791512)
					(end 205.4987 -275.782532)
				)
				(arc
					(start 205.4987 -275.287994)
					(mid 205.50242 -275.279014)
					(end 205.5114 -275.275294)
				)
				(arc
					(start 206.9846 -275.275294)
					(mid 206.99358 -275.279014)
					(end 206.9973 -275.287994)
				)
			)
		)
	)
	(zone
		(layer "In1.Cu")
		(hatch none 0.5)
		(connect_pads
			(clearance 0)
		)
		(min_thickness 0.25)
		(keepout
			(tracks not_allowed)
			(vias allowed)
			(pads allowed)
			(copperpour not_allowed)
			(footprints allowed)
		)
		(placement
			(enabled no)
			(sheetname "")
		)
		(fill
			(thermal_gap 0.5)
			(thermal_bridge_width 0.5)
			(island_removal_mode 0)
		)
		(polygon
			(pts
				(arc
					(start 56.077358 -224.78238)
					(mid 56.073638 -224.79136)
					(end 56.064658 -224.79508)
				)
				(arc
					(start 54.591458 -224.79508)
					(mid 54.582478 -224.79136)
					(end 54.578758 -224.78238)
				)
				(arc
					(start 54.578758 -224.287842)
					(mid 54.582478 -224.278862)
					(end 54.591458 -224.275142)
				)
				(arc
					(start 56.064658 -224.275142)
					(mid 56.073638 -224.278862)
					(end 56.077358 -224.287842)
				)
			)
		)
	)
	(zone
		(layer "In1.Cu")
		(hatch none 0.5)
		(connect_pads
			(clearance 0)
		)
		(min_thickness 0.25)
		(keepout
			(tracks not_allowed)
			(vias allowed)
			(pads allowed)
			(copperpour not_allowed)
			(footprints allowed)
		)
		(placement
			(enabled no)
			(sheetname "")
		)
		(fill
			(thermal_gap 0.5)
			(thermal_bridge_width 0.5)
			(island_removal_mode 0)
		)
		(polygon
			(pts
				(arc
					(start 30.001464 -281.732482)
					(mid 29.997744 -281.741462)
					(end 29.988764 -281.745182)
				)
				(arc
					(start 28.515564 -281.745182)
					(mid 28.506584 -281.741462)
					(end 28.502864 -281.732482)
				)
				(arc
					(start 28.502864 -281.237944)
					(mid 28.506584 -281.228964)
					(end 28.515564 -281.225244)
				)
				(arc
					(start 29.988764 -281.225244)
					(mid 29.997744 -281.228964)
					(end 30.001464 -281.237944)
				)
			)
		)
	)
	(zone
		(layer "In1.Cu")
		(hatch none 0.5)
		(connect_pads
			(clearance 0)
		)
		(min_thickness 0.25)
		(keepout
			(tracks not_allowed)
			(vias allowed)
			(pads allowed)
			(copperpour not_allowed)
			(footprints allowed)
		)
		(placement
			(enabled no)
			(sheetname "")
		)
		(fill
			(thermal_gap 0.5)
			(thermal_bridge_width 0.5)
			(island_removal_mode 0)
		)
		(polygon
			(pts
				(arc
					(start 300.57344 -272.382234)
					(mid 300.56972 -272.391214)
					(end 300.56074 -272.394934)
				)
				(arc
					(start 299.08754 -272.394934)
					(mid 299.07856 -272.391214)
					(end 299.07484 -272.382234)
				)
				(arc
					(start 299.07484 -271.887696)
					(mid 299.07856 -271.878716)
					(end 299.08754 -271.874996)
				)
				(arc
					(start 300.56074 -271.874996)
					(mid 300.56972 -271.878716)
					(end 300.57344 -271.887696)
				)
			)
		)
	)
	(zone
		(layer "In1.Cu")
		(hatch none 0.5)
		(connect_pads
			(clearance 0)
		)
		(min_thickness 0.25)
		(keepout
			(tracks not_allowed)
			(vias allowed)
			(pads allowed)
			(copperpour not_allowed)
			(footprints allowed)
		)
		(placement
			(enabled no)
			(sheetname "")
		)
		(fill
			(thermal_gap 0.5)
			(thermal_bridge_width 0.5)
			(island_removal_mode 0)
		)
		(polygon
			(pts
				(arc
					(start 172.72127 -211.182458)
					(mid 172.71755 -211.191438)
					(end 172.70857 -211.195158)
				)
				(arc
					(start 171.23537 -211.195158)
					(mid 171.22639 -211.191438)
					(end 171.22267 -211.182458)
				)
				(arc
					(start 171.22267 -210.68792)
					(mid 171.22639 -210.67894)
					(end 171.23537 -210.67522)
				)
				(arc
					(start 172.70857 -210.67522)
					(mid 172.71755 -210.67894)
					(end 172.72127 -210.68792)
				)
			)
		)
	)
	(zone
		(layer "In1.Cu")
		(hatch none 0.5)
		(connect_pads
			(clearance 0)
		)
		(min_thickness 0.25)
		(keepout
			(tracks not_allowed)
			(vias allowed)
			(pads allowed)
			(copperpour not_allowed)
			(footprints allowed)
		)
		(placement
			(enabled no)
			(sheetname "")
		)
		(fill
			(thermal_gap 0.5)
			(thermal_bridge_width 0.5)
			(island_removal_mode 0)
		)
		(polygon
			(pts
				(arc
					(start 48.533304 -297.882564)
					(mid 48.529584 -297.891544)
					(end 48.520604 -297.895264)
				)
				(arc
					(start 47.047404 -297.895264)
					(mid 47.038424 -297.891544)
					(end 47.034704 -297.882564)
				)
				(arc
					(start 47.034704 -297.388026)
					(mid 47.038424 -297.379046)
					(end 47.047404 -297.375326)
				)
				(arc
					(start 48.520604 -297.375326)
					(mid 48.529584 -297.379046)
					(end 48.533304 -297.388026)
				)
			)
		)
	)
	(zone
		(layer "In1.Cu")
		(hatch none 0.5)
		(connect_pads
			(clearance 0)
		)
		(min_thickness 0.25)
		(keepout
			(tracks not_allowed)
			(vias allowed)
			(pads allowed)
			(copperpour not_allowed)
			(footprints allowed)
		)
		(placement
			(enabled no)
			(sheetname "")
		)
		(fill
			(thermal_gap 0.5)
			(thermal_bridge_width 0.5)
			(island_removal_mode 0)
		)
		(polygon
			(pts
				(arc
					(start 33.445196 -207.782414)
					(mid 33.441476 -207.791394)
					(end 33.432496 -207.795114)
				)
				(arc
					(start 31.959296 -207.795114)
					(mid 31.950316 -207.791394)
					(end 31.946596 -207.782414)
				)
				(arc
					(start 31.946596 -207.287876)
					(mid 31.950316 -207.278896)
					(end 31.959296 -207.275176)
				)
				(arc
					(start 33.432496 -207.275176)
					(mid 33.441476 -207.278896)
					(end 33.445196 -207.287876)
				)
			)
		)
	)
	(zone
		(layer "In1.Cu")
		(hatch none 0.5)
		(connect_pads
			(clearance 0)
		)
		(min_thickness 0.25)
		(keepout
			(tracks not_allowed)
			(vias allowed)
			(pads allowed)
			(copperpour not_allowed)
			(footprints allowed)
		)
		(placement
			(enabled no)
			(sheetname "")
		)
		(fill
			(thermal_gap 0.5)
			(thermal_bridge_width 0.5)
			(island_removal_mode 0)
		)
		(polygon
			(pts
				(arc
					(start 202.897232 -282.582366)
					(mid 202.893512 -282.591346)
					(end 202.884532 -282.595066)
				)
				(arc
					(start 201.411332 -282.595066)
					(mid 201.402352 -282.591346)
					(end 201.398632 -282.582366)
				)
				(arc
					(start 201.398632 -282.087828)
					(mid 201.402352 -282.078848)
					(end 201.411332 -282.075128)
				)
				(arc
					(start 202.884532 -282.075128)
					(mid 202.893512 -282.078848)
					(end 202.897232 -282.087828)
				)
			)
		)
	)
	(zone
		(layer "In1.Cu")
		(hatch none 0.5)
		(connect_pads
			(clearance 0)
		)
		(min_thickness 0.25)
		(keepout
			(tracks not_allowed)
			(vias allowed)
			(pads allowed)
			(copperpour not_allowed)
			(footprints allowed)
		)
		(placement
			(enabled no)
			(sheetname "")
		)
		(fill
			(thermal_gap 0.5)
			(thermal_bridge_width 0.5)
			(island_removal_mode 0)
		)
		(polygon
			(pts
				(arc
					(start 191.909446 -239.23244)
					(mid 191.905726 -239.24142)
					(end 191.896746 -239.24514)
				)
				(arc
					(start 190.423546 -239.24514)
					(mid 190.414566 -239.24142)
					(end 190.410846 -239.23244)
				)
				(arc
					(start 190.410846 -238.737902)
					(mid 190.414566 -238.728922)
					(end 190.423546 -238.725202)
				)
				(arc
					(start 191.896746 -238.725202)
					(mid 191.905726 -238.728922)
					(end 191.909446 -238.737902)
				)
			)
		)
	)
	(zone
		(layer "In1.Cu")
		(hatch none 0.5)
		(connect_pads
			(clearance 0)
		)
		(min_thickness 0.25)
		(keepout
			(tracks not_allowed)
			(vias allowed)
			(pads allowed)
			(copperpour not_allowed)
			(footprints allowed)
		)
		(placement
			(enabled no)
			(sheetname "")
		)
		(fill
			(thermal_gap 0.5)
			(thermal_bridge_width 0.5)
			(island_removal_mode 0)
		)
		(polygon
			(pts
				(arc
					(start 346.78874 -393.69238)
					(mid 346.40774 -393.69238)
					(end 346.78874 -393.69238)
				)
			)
		)
	)
	(zone
		(layer "In1.Cu")
		(hatch none 0.5)
		(connect_pads
			(clearance 0)
		)
		(min_thickness 0.25)
		(keepout
			(tracks not_allowed)
			(vias allowed)
			(pads allowed)
			(copperpour not_allowed)
			(footprints allowed)
		)
		(placement
			(enabled no)
			(sheetname "")
		)
		(fill
			(thermal_gap 0.5)
			(thermal_bridge_width 0.5)
			(island_removal_mode 0)
		)
		(polygon
			(pts
				(arc
					(start 191.909446 -311.482486)
					(mid 191.905726 -311.491466)
					(end 191.896746 -311.495186)
				)
				(arc
					(start 190.423546 -311.495186)
					(mid 190.414566 -311.491466)
					(end 190.410846 -311.482486)
				)
				(arc
					(start 190.410846 -310.987948)
					(mid 190.414566 -310.978968)
					(end 190.423546 -310.975248)
				)
				(arc
					(start 191.896746 -310.975248)
					(mid 191.905726 -310.978968)
					(end 191.909446 -310.987948)
				)
			)
		)
	)
	(zone
		(layer "In1.Cu")
		(hatch none 0.5)
		(connect_pads
			(clearance 0)
		)
		(min_thickness 0.25)
		(keepout
			(tracks not_allowed)
			(vias allowed)
			(pads allowed)
			(copperpour not_allowed)
			(footprints allowed)
		)
		(placement
			(enabled no)
			(sheetname "")
		)
		(fill
			(thermal_gap 0.5)
			(thermal_bridge_width 0.5)
			(island_removal_mode 0)
		)
		(polygon
			(pts
				(arc
					(start 180.265324 -299.582586)
					(mid 180.261604 -299.591566)
					(end 180.252624 -299.595286)
				)
				(arc
					(start 178.779424 -299.595286)
					(mid 178.770444 -299.591566)
					(end 178.766724 -299.582586)
				)
				(arc
					(start 178.766724 -299.088048)
					(mid 178.770444 -299.079068)
					(end 178.779424 -299.075348)
				)
				(arc
					(start 180.252624 -299.075348)
					(mid 180.261604 -299.079068)
					(end 180.265324 -299.088048)
				)
			)
		)
	)
	(zone
		(layer "In1.Cu")
		(hatch none 0.5)
		(connect_pads
			(clearance 0)
		)
		(min_thickness 0.25)
		(keepout
			(tracks not_allowed)
			(vias allowed)
			(pads allowed)
			(copperpour not_allowed)
			(footprints allowed)
		)
		(placement
			(enabled no)
			(sheetname "")
		)
		(fill
			(thermal_gap 0.5)
			(thermal_bridge_width 0.5)
			(island_removal_mode 0)
		)
		(polygon
			(pts
				(arc
					(start 296.473372 -254.53213)
					(mid 296.469652 -254.54111)
					(end 296.460672 -254.54483)
				)
				(arc
					(start 294.987472 -254.54483)
					(mid 294.978492 -254.54111)
					(end 294.974772 -254.53213)
				)
				(arc
					(start 294.974772 -254.037592)
					(mid 294.978492 -254.028612)
					(end 294.987472 -254.024892)
				)
				(arc
					(start 296.460672 -254.024892)
					(mid 296.469652 -254.028612)
					(end 296.473372 -254.037592)
				)
			)
		)
	)
	(zone
		(layer "In1.Cu")
		(hatch none 0.5)
		(connect_pads
			(clearance 0)
		)
		(min_thickness 0.25)
		(keepout
			(tracks not_allowed)
			(vias allowed)
			(pads allowed)
			(copperpour not_allowed)
			(footprints allowed)
		)
		(placement
			(enabled no)
			(sheetname "")
		)
		(fill
			(thermal_gap 0.5)
			(thermal_bridge_width 0.5)
			(island_removal_mode 0)
		)
		(polygon
			(pts
				(arc
					(start 304.017426 -245.182136)
					(mid 304.013706 -245.191116)
					(end 304.004726 -245.194836)
				)
				(arc
					(start 302.531526 -245.194836)
					(mid 302.522546 -245.191116)
					(end 302.518826 -245.182136)
				)
				(arc
					(start 302.518826 -244.687598)
					(mid 302.522546 -244.678618)
					(end 302.531526 -244.674898)
				)
				(arc
					(start 304.004726 -244.674898)
					(mid 304.013706 -244.678618)
					(end 304.017426 -244.687598)
				)
			)
		)
	)
	(zone
		(layer "In1.Cu")
		(hatch none 0.5)
		(connect_pads
			(clearance 0)
		)
		(min_thickness 0.25)
		(keepout
			(tracks not_allowed)
			(vias allowed)
			(pads allowed)
			(copperpour not_allowed)
			(footprints allowed)
		)
		(placement
			(enabled no)
			(sheetname "")
		)
		(fill
			(thermal_gap 0.5)
			(thermal_bridge_width 0.5)
			(island_removal_mode 0)
		)
		(polygon
			(pts
				(arc
					(start 88.388952 -388.774432)
					(mid 88.007952 -388.774432)
					(end 88.388952 -388.774432)
				)
			)
		)
	)
	(zone
		(layer "In1.Cu")
		(hatch none 0.5)
		(connect_pads
			(clearance 0)
		)
		(min_thickness 0.25)
		(keepout
			(tracks not_allowed)
			(vias allowed)
			(pads allowed)
			(copperpour not_allowed)
			(footprints allowed)
		)
		(placement
			(enabled no)
			(sheetname "")
		)
		(fill
			(thermal_gap 0.5)
			(thermal_bridge_width 0.5)
			(island_removal_mode 0)
		)
		(polygon
			(pts
				(arc
					(start 447.393568 -205.232254)
					(mid 447.389848 -205.241234)
					(end 447.380868 -205.244954)
				)
				(arc
					(start 445.907668 -205.244954)
					(mid 445.898688 -205.241234)
					(end 445.894968 -205.232254)
				)
				(arc
					(start 445.894968 -204.737716)
					(mid 445.898688 -204.728736)
					(end 445.907668 -204.725016)
				)
				(arc
					(start 447.380868 -204.725016)
					(mid 447.389848 -204.728736)
					(end 447.393568 -204.737716)
				)
			)
		)
	)
	(zone
		(layer "In1.Cu")
		(hatch none 0.5)
		(connect_pads
			(clearance 0)
		)
		(min_thickness 0.25)
		(keepout
			(tracks not_allowed)
			(vias allowed)
			(pads allowed)
			(copperpour not_allowed)
			(footprints allowed)
		)
		(placement
			(enabled no)
			(sheetname "")
		)
		(fill
			(thermal_gap 0.5)
			(thermal_bridge_width 0.5)
			(island_removal_mode 0)
		)
		(polygon
			(pts
				(arc
					(start 202.897232 -201.832464)
					(mid 202.893512 -201.841444)
					(end 202.884532 -201.845164)
				)
				(arc
					(start 201.411332 -201.845164)
					(mid 201.402352 -201.841444)
					(end 201.398632 -201.832464)
				)
				(arc
					(start 201.398632 -201.337926)
					(mid 201.402352 -201.328946)
					(end 201.411332 -201.325226)
				)
				(arc
					(start 202.884532 -201.325226)
					(mid 202.893512 -201.328946)
					(end 202.897232 -201.337926)
				)
			)
		)
	)
	(zone
		(layer "In1.Cu")
		(hatch none 0.5)
		(connect_pads
			(clearance 0)
		)
		(min_thickness 0.25)
		(keepout
			(tracks not_allowed)
			(vias allowed)
			(pads allowed)
			(copperpour not_allowed)
			(footprints allowed)
		)
		(placement
			(enabled no)
			(sheetname "")
		)
		(fill
			(thermal_gap 0.5)
			(thermal_bridge_width 0.5)
			(island_removal_mode 0)
		)
		(polygon
			(pts
				(arc
					(start 163.888928 -388.774432)
					(mid 163.507928 -388.774432)
					(end 163.888928 -388.774432)
				)
			)
		)
	)
	(zone
		(layer "In1.Cu")
		(hatch none 0.5)
		(connect_pads
			(clearance 0)
		)
		(min_thickness 0.25)
		(keepout
			(tracks not_allowed)
			(vias allowed)
			(pads allowed)
			(copperpour not_allowed)
			(footprints allowed)
		)
		(placement
			(enabled no)
			(sheetname "")
		)
		(fill
			(thermal_gap 0.5)
			(thermal_bridge_width 0.5)
			(island_removal_mode 0)
		)
		(polygon
			(pts
				(arc
					(start 18.357342 -279.182576)
					(mid 18.353622 -279.191556)
					(end 18.344642 -279.195276)
				)
				(arc
					(start 16.871442 -279.195276)
					(mid 16.862462 -279.191556)
					(end 16.858742 -279.182576)
				)
				(arc
					(start 16.858742 -278.688038)
					(mid 16.862462 -278.679058)
					(end 16.871442 -278.675338)
				)
				(arc
					(start 18.344642 -278.675338)
					(mid 18.353622 -278.679058)
					(end 18.357342 -278.688038)
				)
			)
		)
	)
	(zone
		(layer "In1.Cu")
		(hatch none 0.5)
		(connect_pads
			(clearance 0)
		)
		(min_thickness 0.25)
		(keepout
			(tracks not_allowed)
			(vias allowed)
			(pads allowed)
			(copperpour not_allowed)
			(footprints allowed)
		)
		(placement
			(enabled no)
			(sheetname "")
		)
		(fill
			(thermal_gap 0.5)
			(thermal_bridge_width 0.5)
			(island_removal_mode 0)
		)
		(polygon
			(pts
				(arc
					(start 48.533304 -223.082358)
					(mid 48.529584 -223.091338)
					(end 48.520604 -223.095058)
				)
				(arc
					(start 47.047404 -223.095058)
					(mid 47.038424 -223.091338)
					(end 47.034704 -223.082358)
				)
				(arc
					(start 47.034704 -222.58782)
					(mid 47.038424 -222.57884)
					(end 47.047404 -222.57512)
				)
				(arc
					(start 48.520604 -222.57512)
					(mid 48.529584 -222.57884)
					(end 48.533304 -222.58782)
				)
			)
		)
	)
	(zone
		(layer "In1.Cu")
		(hatch none 0.5)
		(connect_pads
			(clearance 0)
		)
		(min_thickness 0.25)
		(keepout
			(tracks not_allowed)
			(vias allowed)
			(pads allowed)
			(copperpour not_allowed)
			(footprints allowed)
		)
		(placement
			(enabled no)
			(sheetname "")
		)
		(fill
			(thermal_gap 0.5)
			(thermal_bridge_width 0.5)
			(island_removal_mode 0)
		)
		(polygon
			(pts
				(arc
					(start 432.30546 -206.932276)
					(mid 432.30174 -206.941256)
					(end 432.29276 -206.944976)
				)
				(arc
					(start 430.81956 -206.944976)
					(mid 430.81058 -206.941256)
					(end 430.80686 -206.932276)
				)
				(arc
					(start 430.80686 -206.437738)
					(mid 430.81058 -206.428758)
					(end 430.81956 -206.425038)
				)
				(arc
					(start 432.29276 -206.425038)
					(mid 432.30174 -206.428758)
					(end 432.30546 -206.437738)
				)
			)
		)
	)
	(zone
		(layer "In1.Cu")
		(hatch none 0.5)
		(connect_pads
			(clearance 0)
		)
		(min_thickness 0.25)
		(keepout
			(tracks not_allowed)
			(vias allowed)
			(pads allowed)
			(copperpour not_allowed)
			(footprints allowed)
		)
		(placement
			(enabled no)
			(sheetname "")
		)
		(fill
			(thermal_gap 0.5)
			(thermal_bridge_width 0.5)
			(island_removal_mode 0)
		)
		(polygon
			(pts
				(arc
					(start 37.545264 -272.382488)
					(mid 37.541544 -272.391468)
					(end 37.532564 -272.395188)
				)
				(arc
					(start 36.059364 -272.395188)
					(mid 36.050384 -272.391468)
					(end 36.046664 -272.382488)
				)
				(arc
					(start 36.046664 -271.88795)
					(mid 36.050384 -271.87897)
					(end 36.059364 -271.87525)
				)
				(arc
					(start 37.532564 -271.87525)
					(mid 37.541544 -271.87897)
					(end 37.545264 -271.88795)
				)
			)
		)
	)
	(zone
		(layer "In1.Cu")
		(hatch none 0.5)
		(connect_pads
			(clearance 0)
		)
		(min_thickness 0.25)
		(keepout
			(tracks not_allowed)
			(vias allowed)
			(pads allowed)
			(copperpour not_allowed)
			(footprints allowed)
		)
		(placement
			(enabled no)
			(sheetname "")
		)
		(fill
			(thermal_gap 0.5)
			(thermal_bridge_width 0.5)
			(island_removal_mode 0)
		)
		(polygon
			(pts
				(arc
					(start 285.485332 -238.382302)
					(mid 285.481612 -238.391282)
					(end 285.472632 -238.395002)
				)
				(arc
					(start 283.999432 -238.395002)
					(mid 283.990452 -238.391282)
					(end 283.986732 -238.382302)
				)
				(arc
					(start 283.986732 -237.887764)
					(mid 283.990452 -237.878784)
					(end 283.999432 -237.875064)
				)
				(arc
					(start 285.472632 -237.875064)
					(mid 285.481612 -237.878784)
					(end 285.485332 -237.887764)
				)
			)
		)
	)
	(zone
		(layer "In1.Cu")
		(hatch none 0.5)
		(connect_pads
			(clearance 0)
		)
		(min_thickness 0.25)
		(keepout
			(tracks not_allowed)
			(vias allowed)
			(pads allowed)
			(copperpour not_allowed)
			(footprints allowed)
		)
		(placement
			(enabled no)
			(sheetname "")
		)
		(fill
			(thermal_gap 0.5)
			(thermal_bridge_width 0.5)
			(island_removal_mode 0)
		)
		(polygon
			(pts
				(arc
					(start 447.393568 -244.332252)
					(mid 447.389848 -244.341232)
					(end 447.380868 -244.344952)
				)
				(arc
					(start 445.907668 -244.344952)
					(mid 445.898688 -244.341232)
					(end 445.894968 -244.332252)
				)
				(arc
					(start 445.894968 -243.837714)
					(mid 445.898688 -243.828734)
					(end 445.907668 -243.825014)
				)
				(arc
					(start 447.380868 -243.825014)
					(mid 447.389848 -243.828734)
					(end 447.393568 -243.837714)
				)
			)
		)
	)
	(zone
		(layer "In1.Cu")
		(hatch none 0.5)
		(connect_pads
			(clearance 0)
		)
		(min_thickness 0.25)
		(keepout
			(tracks not_allowed)
			(vias allowed)
			(pads allowed)
			(copperpour not_allowed)
			(footprints allowed)
		)
		(placement
			(enabled no)
			(sheetname "")
		)
		(fill
			(thermal_gap 0.5)
			(thermal_bridge_width 0.5)
			(island_removal_mode 0)
		)
		(polygon
			(pts
				(arc
					(start 420.661338 -276.632162)
					(mid 420.657618 -276.641142)
					(end 420.648638 -276.644862)
				)
				(arc
					(start 419.175438 -276.644862)
					(mid 419.166458 -276.641142)
					(end 419.162738 -276.632162)
				)
				(arc
					(start 419.162738 -276.137624)
					(mid 419.166458 -276.128644)
					(end 419.175438 -276.124924)
				)
				(arc
					(start 420.648638 -276.124924)
					(mid 420.657618 -276.128644)
					(end 420.661338 -276.137624)
				)
			)
		)
	)
	(zone
		(layer "In1.Cu")
		(hatch none 0.5)
		(connect_pads
			(clearance 0)
		)
		(min_thickness 0.25)
		(keepout
			(tracks not_allowed)
			(vias allowed)
			(pads allowed)
			(copperpour not_allowed)
			(footprints allowed)
		)
		(placement
			(enabled no)
			(sheetname "")
		)
		(fill
			(thermal_gap 0.5)
			(thermal_bridge_width 0.5)
			(island_removal_mode 0)
		)
		(polygon
			(pts
				(arc
					(start 265.87831 -251.735082)
					(mid 265.21791 -251.735082)
					(end 265.87831 -251.735082)
				)
			)
		)
	)
	(zone
		(layer "In1.Cu")
		(hatch none 0.5)
		(connect_pads
			(clearance 0)
		)
		(min_thickness 0.25)
		(keepout
			(tracks not_allowed)
			(vias allowed)
			(pads allowed)
			(copperpour not_allowed)
			(footprints allowed)
		)
		(placement
			(enabled no)
			(sheetname "")
		)
		(fill
			(thermal_gap 0.5)
			(thermal_bridge_width 0.5)
			(island_removal_mode 0)
		)
		(polygon
			(pts
				(arc
					(start 92.388944 -386.003292)
					(mid 92.007944 -386.003292)
					(end 92.388944 -386.003292)
				)
			)
		)
	)
	(zone
		(layer "In1.Cu")
		(hatch none 0.5)
		(connect_pads
			(clearance 0)
		)
		(min_thickness 0.25)
		(keepout
			(tracks not_allowed)
			(vias allowed)
			(pads allowed)
			(copperpour not_allowed)
			(footprints allowed)
		)
		(placement
			(enabled no)
			(sheetname "")
		)
		(fill
			(thermal_gap 0.5)
			(thermal_bridge_width 0.5)
			(island_removal_mode 0)
		)
		(polygon
			(pts
				(arc
					(start 52.633372 -211.182458)
					(mid 52.629652 -211.191438)
					(end 52.620672 -211.195158)
				)
				(arc
					(start 51.147472 -211.195158)
					(mid 51.138492 -211.191438)
					(end 51.134772 -211.182458)
				)
				(arc
					(start 51.134772 -210.68792)
					(mid 51.138492 -210.67894)
					(end 51.147472 -210.67522)
				)
				(arc
					(start 52.620672 -210.67522)
					(mid 52.629652 -210.67894)
					(end 52.633372 -210.68792)
				)
			)
		)
	)
	(zone
		(layer "In1.Cu")
		(hatch none 0.5)
		(connect_pads
			(clearance 0)
		)
		(min_thickness 0.25)
		(keepout
			(tracks not_allowed)
			(vias allowed)
			(pads allowed)
			(copperpour not_allowed)
			(footprints allowed)
		)
		(placement
			(enabled no)
			(sheetname "")
		)
		(fill
			(thermal_gap 0.5)
			(thermal_bridge_width 0.5)
			(island_removal_mode 0)
		)
		(polygon
			(pts
				(arc
					(start 447.393568 -246.032274)
					(mid 447.389848 -246.041254)
					(end 447.380868 -246.044974)
				)
				(arc
					(start 445.907668 -246.044974)
					(mid 445.898688 -246.041254)
					(end 445.894968 -246.032274)
				)
				(arc
					(start 445.894968 -245.537736)
					(mid 445.898688 -245.528756)
					(end 445.907668 -245.525036)
				)
				(arc
					(start 447.380868 -245.525036)
					(mid 447.389848 -245.528756)
					(end 447.393568 -245.537736)
				)
			)
		)
	)
	(zone
		(layer "In1.Cu")
		(hatch none 0.5)
		(connect_pads
			(clearance 0)
		)
		(min_thickness 0.25)
		(keepout
			(tracks not_allowed)
			(vias allowed)
			(pads allowed)
			(copperpour not_allowed)
			(footprints allowed)
		)
		(placement
			(enabled no)
			(sheetname "")
		)
		(fill
			(thermal_gap 0.5)
			(thermal_bridge_width 0.5)
			(island_removal_mode 0)
		)
		(polygon
			(pts
				(arc
					(start 386.561076 -397.849344)
					(mid 386.180076 -397.849344)
					(end 386.561076 -397.849344)
				)
			)
		)
	)
	(zone
		(layer "In1.Cu")
		(hatch none 0.5)
		(connect_pads
			(clearance 0)
		)
		(min_thickness 0.25)
		(keepout
			(tracks not_allowed)
			(vias allowed)
			(pads allowed)
			(copperpour not_allowed)
			(footprints allowed)
		)
		(placement
			(enabled no)
			(sheetname "")
		)
		(fill
			(thermal_gap 0.5)
			(thermal_bridge_width 0.5)
			(island_removal_mode 0)
		)
		(polygon
			(pts
				(arc
					(start 378.161042 -394.385292)
					(mid 377.780042 -394.385292)
					(end 378.161042 -394.385292)
				)
			)
		)
	)
	(zone
		(layer "In1.Cu")
		(hatch none 0.5)
		(connect_pads
			(clearance 0)
		)
		(min_thickness 0.25)
		(keepout
			(tracks not_allowed)
			(vias allowed)
			(pads allowed)
			(copperpour not_allowed)
			(footprints allowed)
		)
		(placement
			(enabled no)
			(sheetname "")
		)
		(fill
			(thermal_gap 0.5)
			(thermal_bridge_width 0.5)
			(island_removal_mode 0)
		)
		(polygon
			(pts
				(arc
					(start 420.661338 -232.432098)
					(mid 420.657618 -232.441078)
					(end 420.648638 -232.444798)
				)
				(arc
					(start 419.175438 -232.444798)
					(mid 419.166458 -232.441078)
					(end 419.162738 -232.432098)
				)
				(arc
					(start 419.162738 -231.93756)
					(mid 419.166458 -231.92858)
					(end 419.175438 -231.92486)
				)
				(arc
					(start 420.648638 -231.92486)
					(mid 420.657618 -231.92858)
					(end 420.661338 -231.93756)
				)
			)
		)
	)
	(zone
		(layer "In1.Cu")
		(hatch none 0.5)
		(connect_pads
			(clearance 0)
		)
		(min_thickness 0.25)
		(keepout
			(tracks not_allowed)
			(vias allowed)
			(pads allowed)
			(copperpour not_allowed)
			(footprints allowed)
		)
		(placement
			(enabled no)
			(sheetname "")
		)
		(fill
			(thermal_gap 0.5)
			(thermal_bridge_width 0.5)
			(island_removal_mode 0)
		)
		(polygon
			(pts
				(arc
					(start 52.633372 -233.28249)
					(mid 52.629652 -233.29147)
					(end 52.620672 -233.29519)
				)
				(arc
					(start 51.147472 -233.29519)
					(mid 51.138492 -233.29147)
					(end 51.134772 -233.28249)
				)
				(arc
					(start 51.134772 -232.787952)
					(mid 51.138492 -232.778972)
					(end 51.147472 -232.775252)
				)
				(arc
					(start 52.620672 -232.775252)
					(mid 52.629652 -232.778972)
					(end 52.633372 -232.787952)
				)
			)
		)
	)
	(zone
		(layer "In1.Cu")
		(hatch none 0.5)
		(connect_pads
			(clearance 0)
		)
		(min_thickness 0.25)
		(keepout
			(tracks not_allowed)
			(vias allowed)
			(pads allowed)
			(copperpour not_allowed)
			(footprints allowed)
		)
		(placement
			(enabled no)
			(sheetname "")
		)
		(fill
			(thermal_gap 0.5)
			(thermal_bridge_width 0.5)
			(island_removal_mode 0)
		)
		(polygon
			(pts
				(arc
					(start 306.5907 -399.701258)
					(mid 306.7177 -399.828258)
					(end 306.8447 -399.701258)
				)
				(arc
					(start 306.8447 -399.625058)
					(mid 306.7177 -399.498058)
					(end 306.5907 -399.625058)
				)
			)
		)
	)
	(zone
		(layer "In1.Cu")
		(hatch none 0.5)
		(connect_pads
			(clearance 0)
		)
		(min_thickness 0.25)
		(keepout
			(tracks not_allowed)
			(vias allowed)
			(pads allowed)
			(copperpour not_allowed)
			(footprints allowed)
		)
		(placement
			(enabled no)
			(sheetname "")
		)
		(fill
			(thermal_gap 0.5)
			(thermal_bridge_width 0.5)
			(island_removal_mode 0)
		)
		(polygon
			(pts
				(arc
					(start 165.177216 -250.282456)
					(mid 165.173496 -250.291436)
					(end 165.164516 -250.295156)
				)
				(arc
					(start 163.691316 -250.295156)
					(mid 163.682336 -250.291436)
					(end 163.678616 -250.282456)
				)
				(arc
					(start 163.678616 -249.787918)
					(mid 163.682336 -249.778938)
					(end 163.691316 -249.775218)
				)
				(arc
					(start 165.164516 -249.775218)
					(mid 165.173496 -249.778938)
					(end 165.177216 -249.787918)
				)
			)
		)
	)
	(zone
		(layer "In1.Cu")
		(hatch none 0.5)
		(connect_pads
			(clearance 0)
		)
		(min_thickness 0.25)
		(keepout
			(tracks not_allowed)
			(vias allowed)
			(pads allowed)
			(copperpour not_allowed)
			(footprints allowed)
		)
		(placement
			(enabled no)
			(sheetname "")
		)
		(fill
			(thermal_gap 0.5)
			(thermal_bridge_width 0.5)
			(island_removal_mode 0)
		)
		(polygon
			(pts
				(arc
					(start 288.929318 -314.032138)
					(mid 288.925598 -314.041118)
					(end 288.916618 -314.044838)
				)
				(arc
					(start 287.443418 -314.044838)
					(mid 287.434438 -314.041118)
					(end 287.430718 -314.032138)
				)
				(arc
					(start 287.430718 -313.5376)
					(mid 287.434438 -313.52862)
					(end 287.443418 -313.5249)
				)
				(arc
					(start 288.916618 -313.5249)
					(mid 288.925598 -313.52862)
					(end 288.929318 -313.5376)
				)
			)
		)
	)
	(zone
		(layer "In1.Cu")
		(hatch none 0.5)
		(connect_pads
			(clearance 0)
		)
		(min_thickness 0.25)
		(keepout
			(tracks not_allowed)
			(vias allowed)
			(pads allowed)
			(copperpour not_allowed)
			(footprints allowed)
		)
		(placement
			(enabled no)
			(sheetname "")
		)
		(fill
			(thermal_gap 0.5)
			(thermal_bridge_width 0.5)
			(island_removal_mode 0)
		)
		(polygon
			(pts
				(arc
					(start 33.445196 -285.98241)
					(mid 33.441476 -285.99139)
					(end 33.432496 -285.99511)
				)
				(arc
					(start 31.959296 -285.99511)
					(mid 31.950316 -285.99139)
					(end 31.946596 -285.98241)
				)
				(arc
					(start 31.946596 -285.487872)
					(mid 31.950316 -285.478892)
					(end 31.959296 -285.475172)
				)
				(arc
					(start 33.432496 -285.475172)
					(mid 33.441476 -285.478892)
					(end 33.445196 -285.487872)
				)
			)
		)
	)
	(zone
		(layer "In1.Cu")
		(hatch none 0.5)
		(connect_pads
			(clearance 0)
		)
		(min_thickness 0.25)
		(keepout
			(tracks not_allowed)
			(vias allowed)
			(pads allowed)
			(copperpour not_allowed)
			(footprints allowed)
		)
		(placement
			(enabled no)
			(sheetname "")
		)
		(fill
			(thermal_gap 0.5)
			(thermal_bridge_width 0.5)
			(island_removal_mode 0)
		)
		(polygon
			(pts
				(arc
					(start 414.288732 -397.849344)
					(mid 413.907732 -397.849344)
					(end 414.288732 -397.849344)
				)
			)
		)
	)
	(zone
		(layer "In1.Cu")
		(hatch none 0.5)
		(connect_pads
			(clearance 0)
		)
		(min_thickness 0.25)
		(keepout
			(tracks not_allowed)
			(vias allowed)
			(pads allowed)
			(copperpour not_allowed)
			(footprints allowed)
		)
		(placement
			(enabled no)
			(sheetname "")
		)
		(fill
			(thermal_gap 0.5)
			(thermal_bridge_width 0.5)
			(island_removal_mode 0)
		)
		(polygon
			(pts
				(arc
					(start 195.353432 -223.082358)
					(mid 195.349712 -223.091338)
					(end 195.340732 -223.095058)
				)
				(arc
					(start 193.867532 -223.095058)
					(mid 193.858552 -223.091338)
					(end 193.854832 -223.082358)
				)
				(arc
					(start 193.854832 -222.58782)
					(mid 193.858552 -222.57884)
					(end 193.867532 -222.57512)
				)
				(arc
					(start 195.340732 -222.57512)
					(mid 195.349712 -222.57884)
					(end 195.353432 -222.58782)
				)
			)
		)
	)
	(zone
		(layer "In1.Cu")
		(hatch none 0.5)
		(connect_pads
			(clearance 0)
		)
		(min_thickness 0.25)
		(keepout
			(tracks not_allowed)
			(vias allowed)
			(pads allowed)
			(copperpour not_allowed)
			(footprints allowed)
		)
		(placement
			(enabled no)
			(sheetname "")
		)
		(fill
			(thermal_gap 0.5)
			(thermal_bridge_width 0.5)
			(island_removal_mode 0)
		)
		(polygon
			(pts
				(arc
					(start 191.909446 -222.232474)
					(mid 191.905726 -222.241454)
					(end 191.896746 -222.245174)
				)
				(arc
					(start 190.423546 -222.245174)
					(mid 190.414566 -222.241454)
					(end 190.410846 -222.232474)
				)
				(arc
					(start 190.410846 -221.737936)
					(mid 190.414566 -221.728956)
					(end 190.423546 -221.725236)
				)
				(arc
					(start 191.896746 -221.725236)
					(mid 191.905726 -221.728956)
					(end 191.909446 -221.737936)
				)
			)
		)
	)
	(zone
		(layer "In1.Cu")
		(hatch none 0.5)
		(connect_pads
			(clearance 0)
		)
		(min_thickness 0.25)
		(keepout
			(tracks not_allowed)
			(vias allowed)
			(pads allowed)
			(copperpour not_allowed)
			(footprints allowed)
		)
		(placement
			(enabled no)
			(sheetname "")
		)
		(fill
			(thermal_gap 0.5)
			(thermal_bridge_width 0.5)
			(island_removal_mode 0)
		)
		(polygon
			(pts
				(arc
					(start 265.87831 -277.235158)
					(mid 265.21791 -277.235158)
					(end 265.87831 -277.235158)
				)
			)
		)
	)
	(zone
		(layer "In1.Cu")
		(hatch none 0.5)
		(connect_pads
			(clearance 0)
		)
		(min_thickness 0.25)
		(keepout
			(tracks not_allowed)
			(vias allowed)
			(pads allowed)
			(copperpour not_allowed)
			(footprints allowed)
		)
		(placement
			(enabled no)
			(sheetname "")
		)
		(fill
			(thermal_gap 0.5)
			(thermal_bridge_width 0.5)
			(island_removal_mode 0)
		)
		(polygon
			(pts
				(arc
					(start 169.277284 -275.782532)
					(mid 169.273564 -275.791512)
					(end 169.264584 -275.795232)
				)
				(arc
					(start 167.791384 -275.795232)
					(mid 167.782404 -275.791512)
					(end 167.778684 -275.782532)
				)
				(arc
					(start 167.778684 -275.287994)
					(mid 167.782404 -275.279014)
					(end 167.791384 -275.275294)
				)
				(arc
					(start 169.264584 -275.275294)
					(mid 169.273564 -275.279014)
					(end 169.277284 -275.287994)
				)
			)
		)
	)
	(zone
		(layer "In1.Cu")
		(hatch none 0.5)
		(connect_pads
			(clearance 0)
		)
		(min_thickness 0.25)
		(keepout
			(tracks not_allowed)
			(vias allowed)
			(pads allowed)
			(copperpour not_allowed)
			(footprints allowed)
		)
		(placement
			(enabled no)
			(sheetname "")
		)
		(fill
			(thermal_gap 0.5)
			(thermal_bridge_width 0.5)
			(island_removal_mode 0)
		)
		(polygon
			(pts
				(arc
					(start 415.818828 -391.822686)
					(mid 415.945828 -391.949686)
					(end 416.072828 -391.822686)
				)
				(arc
					(start 416.072828 -391.746486)
					(mid 415.945828 -391.619486)
					(end 415.818828 -391.746486)
				)
			)
		)
	)
	(zone
		(layer "In1.Cu")
		(hatch none 0.5)
		(connect_pads
			(clearance 0)
		)
		(min_thickness 0.25)
		(keepout
			(tracks not_allowed)
			(vias allowed)
			(pads allowed)
			(copperpour not_allowed)
			(footprints allowed)
		)
		(placement
			(enabled no)
			(sheetname "")
		)
		(fill
			(thermal_gap 0.5)
			(thermal_bridge_width 0.5)
			(island_removal_mode 0)
		)
		(polygon
			(pts
				(arc
					(start 147.48891 -386.003292)
					(mid 147.10791 -386.003292)
					(end 147.48891 -386.003292)
				)
			)
		)
	)
	(zone
		(layer "In1.Cu")
		(hatch none 0.5)
		(connect_pads
			(clearance 0)
		)
		(min_thickness 0.25)
		(keepout
			(tracks not_allowed)
			(vias allowed)
			(pads allowed)
			(copperpour not_allowed)
			(footprints allowed)
		)
		(placement
			(enabled no)
			(sheetname "")
		)
		(fill
			(thermal_gap 0.5)
			(thermal_bridge_width 0.5)
			(island_removal_mode 0)
		)
		(polygon
			(pts
				(arc
					(start 317.39078 -399.701258)
					(mid 317.51778 -399.828258)
					(end 317.64478 -399.701258)
				)
				(arc
					(start 317.64478 -399.625058)
					(mid 317.51778 -399.498058)
					(end 317.39078 -399.625058)
				)
			)
		)
	)
	(zone
		(layer "In1.Cu")
		(hatch none 0.5)
		(connect_pads
			(clearance 0)
		)
		(min_thickness 0.25)
		(keepout
			(tracks not_allowed)
			(vias allowed)
			(pads allowed)
			(copperpour not_allowed)
			(footprints allowed)
		)
		(placement
			(enabled no)
			(sheetname "")
		)
		(fill
			(thermal_gap 0.5)
			(thermal_bridge_width 0.5)
			(island_removal_mode 0)
		)
		(polygon
			(pts
				(arc
					(start 191.909446 -276.632416)
					(mid 191.905726 -276.641396)
					(end 191.896746 -276.645116)
				)
				(arc
					(start 190.423546 -276.645116)
					(mid 190.414566 -276.641396)
					(end 190.410846 -276.632416)
				)
				(arc
					(start 190.410846 -276.137878)
					(mid 190.414566 -276.128898)
					(end 190.423546 -276.125178)
				)
				(arc
					(start 191.896746 -276.125178)
					(mid 191.905726 -276.128898)
					(end 191.909446 -276.137878)
				)
			)
		)
	)
	(zone
		(layer "In1.Cu")
		(hatch none 0.5)
		(connect_pads
			(clearance 0)
		)
		(min_thickness 0.25)
		(keepout
			(tracks not_allowed)
			(vias allowed)
			(pads allowed)
			(copperpour not_allowed)
			(footprints allowed)
		)
		(placement
			(enabled no)
			(sheetname "")
		)
		(fill
			(thermal_gap 0.5)
			(thermal_bridge_width 0.5)
			(island_removal_mode 0)
		)
		(polygon
			(pts
				(arc
					(start 65.461388 -388.774432)
					(mid 65.080388 -388.774432)
					(end 65.461388 -388.774432)
				)
			)
		)
	)
	(zone
		(layer "In1.Cu")
		(hatch none 0.5)
		(connect_pads
			(clearance 0)
		)
		(min_thickness 0.25)
		(keepout
			(tracks not_allowed)
			(vias allowed)
			(pads allowed)
			(copperpour not_allowed)
			(footprints allowed)
		)
		(placement
			(enabled no)
			(sheetname "")
		)
		(fill
			(thermal_gap 0.5)
			(thermal_bridge_width 0.5)
			(island_removal_mode 0)
		)
		(polygon
			(pts
				(arc
					(start 124.561092 -386.003292)
					(mid 124.180092 -386.003292)
					(end 124.561092 -386.003292)
				)
			)
		)
	)
	(zone
		(layer "In1.Cu")
		(hatch none 0.5)
		(connect_pads
			(clearance 0)
		)
		(min_thickness 0.25)
		(keepout
			(tracks not_allowed)
			(vias allowed)
			(pads allowed)
			(copperpour not_allowed)
			(footprints allowed)
		)
		(placement
			(enabled no)
			(sheetname "")
		)
		(fill
			(thermal_gap 0.5)
			(thermal_bridge_width 0.5)
			(island_removal_mode 0)
		)
		(polygon
			(pts
				(arc
					(start 388.670292 -392.30427)
					(mid 388.365492 -392.30427)
					(end 388.670292 -392.30427)
				)
			)
		)
	)
	(zone
		(layer "In1.Cu")
		(hatch none 0.5)
		(connect_pads
			(clearance 0)
		)
		(min_thickness 0.25)
		(keepout
			(tracks not_allowed)
			(vias allowed)
			(pads allowed)
			(copperpour not_allowed)
			(footprints allowed)
		)
		(placement
			(enabled no)
			(sheetname "")
		)
		(fill
			(thermal_gap 0.5)
			(thermal_bridge_width 0.5)
			(island_removal_mode 0)
		)
		(polygon
			(pts
				(arc
					(start 308.990746 -391.822686)
					(mid 309.117746 -391.949686)
					(end 309.244746 -391.822686)
				)
				(arc
					(start 309.244746 -391.746486)
					(mid 309.117746 -391.619486)
					(end 308.990746 -391.746486)
				)
			)
		)
	)
	(zone
		(layer "In1.Cu")
		(hatch none 0.5)
		(connect_pads
			(clearance 0)
		)
		(min_thickness 0.25)
		(keepout
			(tracks not_allowed)
			(vias allowed)
			(pads allowed)
			(copperpour not_allowed)
			(footprints allowed)
		)
		(placement
			(enabled no)
			(sheetname "")
		)
		(fill
			(thermal_gap 0.5)
			(thermal_bridge_width 0.5)
			(island_removal_mode 0)
		)
		(polygon
			(pts
				(arc
					(start 191.909446 -208.632552)
					(mid 191.905726 -208.641532)
					(end 191.896746 -208.645252)
				)
				(arc
					(start 190.423546 -208.645252)
					(mid 190.414566 -208.641532)
					(end 190.410846 -208.632552)
				)
				(arc
					(start 190.410846 -208.138014)
					(mid 190.414566 -208.129034)
					(end 190.423546 -208.125314)
				)
				(arc
					(start 191.896746 -208.125314)
					(mid 191.905726 -208.129034)
					(end 191.909446 -208.138014)
				)
			)
		)
	)
	(zone
		(layer "In1.Cu")
		(hatch none 0.5)
		(connect_pads
			(clearance 0)
		)
		(min_thickness 0.25)
		(keepout
			(tracks not_allowed)
			(vias allowed)
			(pads allowed)
			(copperpour not_allowed)
			(footprints allowed)
		)
		(placement
			(enabled no)
			(sheetname "")
		)
		(fill
			(thermal_gap 0.5)
			(thermal_bridge_width 0.5)
			(island_removal_mode 0)
		)
		(polygon
			(pts
				(arc
					(start 293.029386 -200.982326)
					(mid 293.025666 -200.991306)
					(end 293.016686 -200.995026)
				)
				(arc
					(start 291.543486 -200.995026)
					(mid 291.534506 -200.991306)
					(end 291.530786 -200.982326)
				)
				(arc
					(start 291.530786 -200.487788)
					(mid 291.534506 -200.478808)
					(end 291.543486 -200.475088)
				)
				(arc
					(start 293.016686 -200.475088)
					(mid 293.025666 -200.478808)
					(end 293.029386 -200.487788)
				)
			)
		)
	)
	(zone
		(layer "In1.Cu")
		(hatch none 0.5)
		(connect_pads
			(clearance 0)
		)
		(min_thickness 0.25)
		(keepout
			(tracks not_allowed)
			(vias allowed)
			(pads allowed)
			(copperpour not_allowed)
			(footprints allowed)
		)
		(placement
			(enabled no)
			(sheetname "")
		)
		(fill
			(thermal_gap 0.5)
			(thermal_bridge_width 0.5)
			(island_removal_mode 0)
		)
		(polygon
			(pts
				(arc
					(start 22.45741 -203.532486)
					(mid 22.45369 -203.541466)
					(end 22.44471 -203.545186)
				)
				(arc
					(start 20.97151 -203.545186)
					(mid 20.96253 -203.541466)
					(end 20.95881 -203.532486)
				)
				(arc
					(start 20.95881 -203.037948)
					(mid 20.96253 -203.028968)
					(end 20.97151 -203.025248)
				)
				(arc
					(start 22.44471 -203.025248)
					(mid 22.45369 -203.028968)
					(end 22.45741 -203.037948)
				)
			)
		)
	)
	(zone
		(layer "In1.Cu")
		(hatch none 0.5)
		(connect_pads
			(clearance 0)
		)
		(min_thickness 0.25)
		(keepout
			(tracks not_allowed)
			(vias allowed)
			(pads allowed)
			(copperpour not_allowed)
			(footprints allowed)
		)
		(placement
			(enabled no)
			(sheetname "")
		)
		(fill
			(thermal_gap 0.5)
			(thermal_bridge_width 0.5)
			(island_removal_mode 0)
		)
		(polygon
			(pts
				(arc
					(start 206.5782 -296.785284)
					(mid 205.9178 -296.785284)
					(end 206.5782 -296.785284)
				)
			)
		)
	)
	(zone
		(layer "In1.Cu")
		(hatch none 0.5)
		(connect_pads
			(clearance 0)
		)
		(min_thickness 0.25)
		(keepout
			(tracks not_allowed)
			(vias allowed)
			(pads allowed)
			(copperpour not_allowed)
			(footprints allowed)
		)
		(placement
			(enabled no)
			(sheetname "")
		)
		(fill
			(thermal_gap 0.5)
			(thermal_bridge_width 0.5)
			(island_removal_mode 0)
		)
		(polygon
			(pts
				(arc
					(start 83.98891 -389.467344)
					(mid 83.60791 -389.467344)
					(end 83.98891 -389.467344)
				)
			)
		)
	)
	(zone
		(layer "In1.Cu")
		(hatch none 0.5)
		(connect_pads
			(clearance 0)
		)
		(min_thickness 0.25)
		(keepout
			(tracks not_allowed)
			(vias allowed)
			(pads allowed)
			(copperpour not_allowed)
			(footprints allowed)
		)
		(placement
			(enabled no)
			(sheetname "")
		)
		(fill
			(thermal_gap 0.5)
			(thermal_bridge_width 0.5)
			(island_removal_mode 0)
		)
		(polygon
			(pts
				(arc
					(start 372.491 -399.701258)
					(mid 372.618 -399.828258)
					(end 372.745 -399.701258)
				)
				(arc
					(start 372.745 -399.625058)
					(mid 372.618 -399.498058)
					(end 372.491 -399.625058)
				)
			)
		)
	)
	(zone
		(layer "In1.Cu")
		(hatch none 0.5)
		(connect_pads
			(clearance 0)
		)
		(min_thickness 0.25)
		(keepout
			(tracks not_allowed)
			(vias allowed)
			(pads allowed)
			(copperpour not_allowed)
			(footprints allowed)
		)
		(placement
			(enabled no)
			(sheetname "")
		)
		(fill
			(thermal_gap 0.5)
			(thermal_bridge_width 0.5)
			(island_removal_mode 0)
		)
		(polygon
			(pts
				(arc
					(start 56.077358 -282.582366)
					(mid 56.073638 -282.591346)
					(end 56.064658 -282.595066)
				)
				(arc
					(start 54.591458 -282.595066)
					(mid 54.582478 -282.591346)
					(end 54.578758 -282.582366)
				)
				(arc
					(start 54.578758 -282.087828)
					(mid 54.582478 -282.078848)
					(end 54.591458 -282.075128)
				)
				(arc
					(start 56.064658 -282.075128)
					(mid 56.073638 -282.078848)
					(end 56.077358 -282.087828)
				)
			)
		)
	)
	(zone
		(layer "In1.Cu")
		(hatch none 0.5)
		(connect_pads
			(clearance 0)
		)
		(min_thickness 0.25)
		(keepout
			(tracks not_allowed)
			(vias allowed)
			(pads allowed)
			(copperpour not_allowed)
			(footprints allowed)
		)
		(placement
			(enabled no)
			(sheetname "")
		)
		(fill
			(thermal_gap 0.5)
			(thermal_bridge_width 0.5)
			(island_removal_mode 0)
		)
		(polygon
			(pts
				(arc
					(start 206.5782 -290.835334)
					(mid 205.9178 -290.835334)
					(end 206.5782 -290.835334)
				)
			)
		)
	)
	(zone
		(layer "In1.Cu")
		(hatch none 0.5)
		(connect_pads
			(clearance 0)
		)
		(min_thickness 0.25)
		(keepout
			(tracks not_allowed)
			(vias allowed)
			(pads allowed)
			(copperpour not_allowed)
			(footprints allowed)
		)
		(placement
			(enabled no)
			(sheetname "")
		)
		(fill
			(thermal_gap 0.5)
			(thermal_bridge_width 0.5)
			(island_removal_mode 0)
		)
		(polygon
			(pts
				(arc
					(start 97.518728 -383.440686)
					(mid 97.645728 -383.567686)
					(end 97.772728 -383.440686)
				)
				(arc
					(start 97.772728 -383.364486)
					(mid 97.645728 -383.237486)
					(end 97.518728 -383.364486)
				)
			)
		)
	)
	(zone
		(layer "In1.Cu")
		(hatch none 0.5)
		(connect_pads
			(clearance 0)
		)
		(min_thickness 0.25)
		(keepout
			(tracks not_allowed)
			(vias allowed)
			(pads allowed)
			(copperpour not_allowed)
			(footprints allowed)
		)
		(placement
			(enabled no)
			(sheetname "")
		)
		(fill
			(thermal_gap 0.5)
			(thermal_bridge_width 0.5)
			(island_removal_mode 0)
		)
		(polygon
			(pts
				(arc
					(start 51.461162 -386.003292)
					(mid 51.080162 -386.003292)
					(end 51.461162 -386.003292)
				)
			)
		)
	)
	(zone
		(layer "In1.Cu")
		(hatch none 0.5)
		(connect_pads
			(clearance 0)
		)
		(min_thickness 0.25)
		(keepout
			(tracks not_allowed)
			(vias allowed)
			(pads allowed)
			(copperpour not_allowed)
			(footprints allowed)
		)
		(placement
			(enabled no)
			(sheetname "")
		)
		(fill
			(thermal_gap 0.5)
			(thermal_bridge_width 0.5)
			(island_removal_mode 0)
		)
		(polygon
			(pts
				(arc
					(start 184.365392 -234.982512)
					(mid 184.361672 -234.991492)
					(end 184.352692 -234.995212)
				)
				(arc
					(start 182.879492 -234.995212)
					(mid 182.870512 -234.991492)
					(end 182.866792 -234.982512)
				)
				(arc
					(start 182.866792 -234.487974)
					(mid 182.870512 -234.478994)
					(end 182.879492 -234.475274)
				)
				(arc
					(start 184.352692 -234.475274)
					(mid 184.361672 -234.478994)
					(end 184.365392 -234.487974)
				)
			)
		)
	)
	(zone
		(layer "In1.Cu")
		(hatch none 0.5)
		(connect_pads
			(clearance 0)
		)
		(min_thickness 0.25)
		(keepout
			(tracks not_allowed)
			(vias allowed)
			(pads allowed)
			(copperpour not_allowed)
			(footprints allowed)
		)
		(placement
			(enabled no)
			(sheetname "")
		)
		(fill
			(thermal_gap 0.5)
			(thermal_bridge_width 0.5)
			(island_removal_mode 0)
		)
		(polygon
			(pts
				(arc
					(start 79.989172 -388.774432)
					(mid 79.608172 -388.774432)
					(end 79.989172 -388.774432)
				)
			)
		)
	)
	(zone
		(layer "In1.Cu")
		(hatch none 0.5)
		(connect_pads
			(clearance 0)
		)
		(min_thickness 0.25)
		(keepout
			(tracks not_allowed)
			(vias allowed)
			(pads allowed)
			(copperpour not_allowed)
			(footprints allowed)
		)
		(placement
			(enabled no)
			(sheetname "")
		)
		(fill
			(thermal_gap 0.5)
			(thermal_bridge_width 0.5)
			(island_removal_mode 0)
		)
		(polygon
			(pts
				(arc
					(start 25.901396 -206.082392)
					(mid 25.897676 -206.091372)
					(end 25.888696 -206.095092)
				)
				(arc
					(start 24.415496 -206.095092)
					(mid 24.406516 -206.091372)
					(end 24.402796 -206.082392)
				)
				(arc
					(start 24.402796 -205.587854)
					(mid 24.406516 -205.578874)
					(end 24.415496 -205.575154)
				)
				(arc
					(start 25.888696 -205.575154)
					(mid 25.897676 -205.578874)
					(end 25.901396 -205.587854)
				)
			)
		)
	)
	(zone
		(layer "In1.Cu")
		(hatch none 0.5)
		(connect_pads
			(clearance 0)
		)
		(min_thickness 0.25)
		(keepout
			(tracks not_allowed)
			(vias allowed)
			(pads allowed)
			(copperpour not_allowed)
			(footprints allowed)
		)
		(placement
			(enabled no)
			(sheetname "")
		)
		(fill
			(thermal_gap 0.5)
			(thermal_bridge_width 0.5)
			(island_removal_mode 0)
		)
		(polygon
			(pts
				(arc
					(start 172.72127 -277.482554)
					(mid 172.71755 -277.491534)
					(end 172.70857 -277.495254)
				)
				(arc
					(start 171.23537 -277.495254)
					(mid 171.22639 -277.491534)
					(end 171.22267 -277.482554)
				)
				(arc
					(start 171.22267 -276.988016)
					(mid 171.22639 -276.979036)
					(end 171.23537 -276.975316)
				)
				(arc
					(start 172.70857 -276.975316)
					(mid 172.71755 -276.979036)
					(end 172.72127 -276.988016)
				)
			)
		)
	)
	(zone
		(layer "In1.Cu")
		(hatch none 0.5)
		(connect_pads
			(clearance 0)
		)
		(min_thickness 0.25)
		(keepout
			(tracks not_allowed)
			(vias allowed)
			(pads allowed)
			(copperpour not_allowed)
			(footprints allowed)
		)
		(placement
			(enabled no)
			(sheetname "")
		)
		(fill
			(thermal_gap 0.5)
			(thermal_bridge_width 0.5)
			(island_removal_mode 0)
		)
		(polygon
			(pts
				(arc
					(start 98.144838 6.614414)
					(mid 98.167156 6.668296)
					(end 98.221038 6.690614)
				)
				(arc
					(start 98.833178 6.690614)
					(mid 98.88706 6.668296)
					(end 98.909378 6.614414)
				)
				(arc
					(start 98.909378 5.517134)
					(mid 98.88706 5.463252)
					(end 98.833178 5.440934)
				)
				(arc
					(start 98.221038 5.440934)
					(mid 98.167156 5.463252)
					(end 98.144838 5.517134)
				)
			)
		)
	)
	(zone
		(layer "In1.Cu")
		(hatch none 0.5)
		(connect_pads
			(clearance 0)
		)
		(min_thickness 0.25)
		(keepout
			(tracks not_allowed)
			(vias allowed)
			(pads allowed)
			(copperpour not_allowed)
			(footprints allowed)
		)
		(placement
			(enabled no)
			(sheetname "")
		)
		(fill
			(thermal_gap 0.5)
			(thermal_bridge_width 0.5)
			(island_removal_mode 0)
		)
		(polygon
			(pts
				(arc
					(start 206.5782 -266.185396)
					(mid 205.9178 -266.185396)
					(end 206.5782 -266.185396)
				)
			)
		)
	)
	(zone
		(layer "In1.Cu")
		(hatch none 0.5)
		(connect_pads
			(clearance 0)
		)
		(min_thickness 0.25)
		(keepout
			(tracks not_allowed)
			(vias allowed)
			(pads allowed)
			(copperpour not_allowed)
			(footprints allowed)
		)
		(placement
			(enabled no)
			(sheetname "")
		)
		(fill
			(thermal_gap 0.5)
			(thermal_bridge_width 0.5)
			(island_removal_mode 0)
		)
		(polygon
			(pts
				(arc
					(start 344.981022 -294.031162)
					(mid 344.676222 -294.335962)
					(end 344.981022 -294.640762)
				)
				(arc
					(start 345.921076 -294.640762)
					(mid 346.225876 -294.335962)
					(end 345.921076 -294.031162)
				)
			)
		)
	)
	(zone
		(layer "In1.Cu")
		(hatch none 0.5)
		(connect_pads
			(clearance 0)
		)
		(min_thickness 0.25)
		(keepout
			(tracks not_allowed)
			(vias allowed)
			(pads allowed)
			(copperpour not_allowed)
			(footprints allowed)
		)
		(placement
			(enabled no)
			(sheetname "")
		)
		(fill
			(thermal_gap 0.5)
			(thermal_bridge_width 0.5)
			(island_removal_mode 0)
		)
		(polygon
			(pts
				(arc
					(start 115.761262 -388.774432)
					(mid 115.380262 -388.774432)
					(end 115.761262 -388.774432)
				)
			)
		)
	)
	(zone
		(layer "In1.Cu")
		(hatch none 0.5)
		(connect_pads
			(clearance 0)
		)
		(min_thickness 0.25)
		(keepout
			(tracks not_allowed)
			(vias allowed)
			(pads allowed)
			(copperpour not_allowed)
			(footprints allowed)
		)
		(placement
			(enabled no)
			(sheetname "")
		)
		(fill
			(thermal_gap 0.5)
			(thermal_bridge_width 0.5)
			(island_removal_mode 0)
		)
		(polygon
			(pts
				(arc
					(start 336.718402 -399.701258)
					(mid 336.845402 -399.828258)
					(end 336.972402 -399.701258)
				)
				(arc
					(start 336.972402 -399.625058)
					(mid 336.845402 -399.498058)
					(end 336.718402 -399.625058)
				)
			)
		)
	)
	(zone
		(layer "In1.Cu")
		(hatch none 0.5)
		(connect_pads
			(clearance 0)
		)
		(min_thickness 0.25)
		(keepout
			(tracks not_allowed)
			(vias allowed)
			(pads allowed)
			(copperpour not_allowed)
			(footprints allowed)
		)
		(placement
			(enabled no)
			(sheetname "")
		)
		(fill
			(thermal_gap 0.5)
			(thermal_bridge_width 0.5)
			(island_removal_mode 0)
		)
		(polygon
			(pts
				(arc
					(start 296.473372 -312.332116)
					(mid 296.469652 -312.341096)
					(end 296.460672 -312.344816)
				)
				(arc
					(start 294.987472 -312.344816)
					(mid 294.978492 -312.341096)
					(end 294.974772 -312.332116)
				)
				(arc
					(start 294.974772 -311.837578)
					(mid 294.978492 -311.828598)
					(end 294.987472 -311.824878)
				)
				(arc
					(start 296.460672 -311.824878)
					(mid 296.469652 -311.828598)
					(end 296.473372 -311.837578)
				)
			)
		)
	)
	(zone
		(layer "In1.Cu")
		(hatch none 0.5)
		(connect_pads
			(clearance 0)
		)
		(min_thickness 0.25)
		(keepout
			(tracks not_allowed)
			(vias allowed)
			(pads allowed)
			(copperpour not_allowed)
			(footprints allowed)
		)
		(placement
			(enabled no)
			(sheetname "")
		)
		(fill
			(thermal_gap 0.5)
			(thermal_bridge_width 0.5)
			(island_removal_mode 0)
		)
		(polygon
			(pts
				(arc
					(start 421.08882 -393.69238)
					(mid 420.70782 -393.69238)
					(end 421.08882 -393.69238)
				)
			)
		)
	)
	(zone
		(layer "In1.Cu")
		(hatch none 0.5)
		(connect_pads
			(clearance 0)
		)
		(min_thickness 0.25)
		(keepout
			(tracks not_allowed)
			(vias allowed)
			(pads allowed)
			(copperpour not_allowed)
			(footprints allowed)
		)
		(placement
			(enabled no)
			(sheetname "")
		)
		(fill
			(thermal_gap 0.5)
			(thermal_bridge_width 0.5)
			(island_removal_mode 0)
		)
		(polygon
			(pts
				(arc
					(start 304.017426 -267.282168)
					(mid 304.013706 -267.291148)
					(end 304.004726 -267.294868)
				)
				(arc
					(start 302.531526 -267.294868)
					(mid 302.522546 -267.291148)
					(end 302.518826 -267.282168)
				)
				(arc
					(start 302.518826 -266.78763)
					(mid 302.522546 -266.77865)
					(end 302.531526 -266.77493)
				)
				(arc
					(start 304.004726 -266.77493)
					(mid 304.013706 -266.77865)
					(end 304.017426 -266.78763)
				)
			)
		)
	)
	(zone
		(layer "In1.Cu")
		(hatch none 0.5)
		(connect_pads
			(clearance 0)
		)
		(min_thickness 0.25)
		(keepout
			(tracks not_allowed)
			(vias allowed)
			(pads allowed)
			(copperpour not_allowed)
			(footprints allowed)
		)
		(placement
			(enabled no)
			(sheetname "")
		)
		(fill
			(thermal_gap 0.5)
			(thermal_bridge_width 0.5)
			(island_removal_mode 0)
		)
		(polygon
			(pts
				(arc
					(start 293.029386 -300.432216)
					(mid 293.025666 -300.441196)
					(end 293.016686 -300.444916)
				)
				(arc
					(start 291.543486 -300.444916)
					(mid 291.534506 -300.441196)
					(end 291.530786 -300.432216)
				)
				(arc
					(start 291.530786 -299.937678)
					(mid 291.534506 -299.928698)
					(end 291.543486 -299.924978)
				)
				(arc
					(start 293.016686 -299.924978)
					(mid 293.025666 -299.928698)
					(end 293.029386 -299.937678)
				)
			)
		)
	)
	(zone
		(layer "In1.Cu")
		(hatch none 0.5)
		(connect_pads
			(clearance 0)
		)
		(min_thickness 0.25)
		(keepout
			(tracks not_allowed)
			(vias allowed)
			(pads allowed)
			(copperpour not_allowed)
			(footprints allowed)
		)
		(placement
			(enabled no)
			(sheetname "")
		)
		(fill
			(thermal_gap 0.5)
			(thermal_bridge_width 0.5)
			(island_removal_mode 0)
		)
		(polygon
			(pts
				(arc
					(start 33.445196 -291.93236)
					(mid 33.441476 -291.94134)
					(end 33.432496 -291.94506)
				)
				(arc
					(start 31.959296 -291.94506)
					(mid 31.950316 -291.94134)
					(end 31.946596 -291.93236)
				)
				(arc
					(start 31.946596 -291.437822)
					(mid 31.950316 -291.428842)
					(end 31.959296 -291.425122)
				)
				(arc
					(start 33.432496 -291.425122)
					(mid 33.441476 -291.428842)
					(end 33.445196 -291.437822)
				)
			)
		)
	)
	(zone
		(layer "In1.Cu")
		(hatch none 0.5)
		(connect_pads
			(clearance 0)
		)
		(min_thickness 0.25)
		(keepout
			(tracks not_allowed)
			(vias allowed)
			(pads allowed)
			(copperpour not_allowed)
			(footprints allowed)
		)
		(placement
			(enabled no)
			(sheetname "")
		)
		(fill
			(thermal_gap 0.5)
			(thermal_bridge_width 0.5)
			(island_removal_mode 0)
		)
		(polygon
			(pts
				(arc
					(start 156.218636 -391.319258)
					(mid 156.345636 -391.446258)
					(end 156.472636 -391.319258)
				)
				(arc
					(start 156.472636 -391.243058)
					(mid 156.345636 -391.116058)
					(end 156.218636 -391.243058)
				)
			)
		)
	)
	(zone
		(layer "In1.Cu")
		(hatch none 0.5)
		(connect_pads
			(clearance 0)
		)
		(min_thickness 0.25)
		(keepout
			(tracks not_allowed)
			(vias allowed)
			(pads allowed)
			(copperpour not_allowed)
			(footprints allowed)
		)
		(placement
			(enabled no)
			(sheetname "")
		)
		(fill
			(thermal_gap 0.5)
			(thermal_bridge_width 0.5)
			(island_removal_mode 0)
		)
		(polygon
			(pts
				(arc
					(start 45.089318 -285.132526)
					(mid 45.085598 -285.141506)
					(end 45.076618 -285.145226)
				)
				(arc
					(start 43.603418 -285.145226)
					(mid 43.594438 -285.141506)
					(end 43.590718 -285.132526)
				)
				(arc
					(start 43.590718 -284.637988)
					(mid 43.594438 -284.629008)
					(end 43.603418 -284.625288)
				)
				(arc
					(start 45.076618 -284.625288)
					(mid 45.085598 -284.629008)
					(end 45.089318 -284.637988)
				)
			)
		)
	)
	(zone
		(layer "In1.Cu")
		(hatch none 0.5)
		(connect_pads
			(clearance 0)
		)
		(min_thickness 0.25)
		(keepout
			(tracks not_allowed)
			(vias allowed)
			(pads allowed)
			(copperpour not_allowed)
			(footprints allowed)
		)
		(placement
			(enabled no)
			(sheetname "")
		)
		(fill
			(thermal_gap 0.5)
			(thermal_bridge_width 0.5)
			(island_removal_mode 0)
		)
		(polygon
			(pts
				(arc
					(start 57.17032 -390.761474)
					(mid 56.86552 -390.761474)
					(end 57.17032 -390.761474)
				)
			)
		)
	)
	(zone
		(layer "In1.Cu")
		(hatch none 0.5)
		(connect_pads
			(clearance 0)
		)
		(min_thickness 0.25)
		(keepout
			(tracks not_allowed)
			(vias allowed)
			(pads allowed)
			(copperpour not_allowed)
			(footprints allowed)
		)
		(placement
			(enabled no)
			(sheetname "")
		)
		(fill
			(thermal_gap 0.5)
			(thermal_bridge_width 0.5)
			(island_removal_mode 0)
		)
		(polygon
			(pts
				(arc
					(start 308.117494 -223.932242)
					(mid 308.113774 -223.941222)
					(end 308.104794 -223.944942)
				)
				(arc
					(start 306.631594 -223.944942)
					(mid 306.622614 -223.941222)
					(end 306.618894 -223.932242)
				)
				(arc
					(start 306.618894 -223.437704)
					(mid 306.622614 -223.428724)
					(end 306.631594 -223.425004)
				)
				(arc
					(start 308.104794 -223.425004)
					(mid 308.113774 -223.428724)
					(end 308.117494 -223.437704)
				)
			)
		)
	)
	(zone
		(layer "In1.Cu")
		(hatch none 0.5)
		(connect_pads
			(clearance 0)
		)
		(min_thickness 0.25)
		(keepout
			(tracks not_allowed)
			(vias allowed)
			(pads allowed)
			(copperpour not_allowed)
			(footprints allowed)
		)
		(placement
			(enabled no)
			(sheetname "")
		)
		(fill
			(thermal_gap 0.5)
			(thermal_bridge_width 0.5)
			(island_removal_mode 0)
		)
		(polygon
			(pts
				(arc
					(start 54.191154 -391.319258)
					(mid 54.318154 -391.446258)
					(end 54.445154 -391.319258)
				)
				(arc
					(start 54.445154 -391.243058)
					(mid 54.318154 -391.116058)
					(end 54.191154 -391.243058)
				)
			)
		)
	)
	(zone
		(layer "In1.Cu")
		(hatch none 0.5)
		(connect_pads
			(clearance 0)
		)
		(min_thickness 0.25)
		(keepout
			(tracks not_allowed)
			(vias allowed)
			(pads allowed)
			(copperpour not_allowed)
			(footprints allowed)
		)
		(placement
			(enabled no)
			(sheetname "")
		)
		(fill
			(thermal_gap 0.5)
			(thermal_bridge_width 0.5)
			(island_removal_mode 0)
		)
		(polygon
			(pts
				(arc
					(start 454.937368 -269.832328)
					(mid 454.933648 -269.841308)
					(end 454.924668 -269.845028)
				)
				(arc
					(start 453.451468 -269.845028)
					(mid 453.442488 -269.841308)
					(end 453.438768 -269.832328)
				)
				(arc
					(start 453.438768 -269.33779)
					(mid 453.442488 -269.32881)
					(end 453.451468 -269.32509)
				)
				(arc
					(start 454.924668 -269.32509)
					(mid 454.933648 -269.32881)
					(end 454.937368 -269.33779)
				)
			)
		)
	)
	(zone
		(layer "In1.Cu")
		(hatch none 0.5)
		(connect_pads
			(clearance 0)
		)
		(min_thickness 0.25)
		(keepout
			(tracks not_allowed)
			(vias allowed)
			(pads allowed)
			(copperpour not_allowed)
			(footprints allowed)
		)
		(placement
			(enabled no)
			(sheetname "")
		)
		(fill
			(thermal_gap 0.5)
			(thermal_bridge_width 0.5)
			(island_removal_mode 0)
		)
		(polygon
			(pts
				(arc
					(start 285.485332 -212.882226)
					(mid 285.481612 -212.891206)
					(end 285.472632 -212.894926)
				)
				(arc
					(start 283.999432 -212.894926)
					(mid 283.990452 -212.891206)
					(end 283.986732 -212.882226)
				)
				(arc
					(start 283.986732 -212.387688)
					(mid 283.990452 -212.378708)
					(end 283.999432 -212.374988)
				)
				(arc
					(start 285.472632 -212.374988)
					(mid 285.481612 -212.378708)
					(end 285.485332 -212.387688)
				)
			)
		)
	)
	(zone
		(layer "In1.Cu")
		(hatch none 0.5)
		(connect_pads
			(clearance 0)
		)
		(min_thickness 0.25)
		(keepout
			(tracks not_allowed)
			(vias allowed)
			(pads allowed)
			(copperpour not_allowed)
			(footprints allowed)
		)
		(placement
			(enabled no)
			(sheetname "")
		)
		(fill
			(thermal_gap 0.5)
			(thermal_bridge_width 0.5)
			(island_removal_mode 0)
		)
		(polygon
			(pts
				(arc
					(start 30.001464 -229.032562)
					(mid 29.997744 -229.041542)
					(end 29.988764 -229.045262)
				)
				(arc
					(start 28.515564 -229.045262)
					(mid 28.506584 -229.041542)
					(end 28.502864 -229.032562)
				)
				(arc
					(start 28.502864 -228.538024)
					(mid 28.506584 -228.529044)
					(end 28.515564 -228.525324)
				)
				(arc
					(start 29.988764 -228.525324)
					(mid 29.997744 -228.529044)
					(end 30.001464 -228.538024)
				)
			)
		)
	)
	(zone
		(layer "In1.Cu")
		(hatch none 0.5)
		(connect_pads
			(clearance 0)
		)
		(min_thickness 0.25)
		(keepout
			(tracks not_allowed)
			(vias allowed)
			(pads allowed)
			(copperpour not_allowed)
			(footprints allowed)
		)
		(placement
			(enabled no)
			(sheetname "")
		)
		(fill
			(thermal_gap 0.5)
			(thermal_bridge_width 0.5)
			(island_removal_mode 0)
		)
		(polygon
			(pts
				(arc
					(start 53.461412 -388.774432)
					(mid 53.080412 -388.774432)
					(end 53.461412 -388.774432)
				)
			)
		)
	)
	(zone
		(layer "In1.Cu")
		(hatch none 0.5)
		(connect_pads
			(clearance 0)
		)
		(min_thickness 0.25)
		(keepout
			(tracks not_allowed)
			(vias allowed)
			(pads allowed)
			(copperpour not_allowed)
			(footprints allowed)
		)
		(placement
			(enabled no)
			(sheetname "")
		)
		(fill
			(thermal_gap 0.5)
			(thermal_bridge_width 0.5)
			(island_removal_mode 0)
		)
		(polygon
			(pts
				(arc
					(start 313.790838 -399.701258)
					(mid 313.917838 -399.828258)
					(end 314.044838 -399.701258)
				)
				(arc
					(start 314.044838 -399.625058)
					(mid 313.917838 -399.498058)
					(end 313.790838 -399.625058)
				)
			)
		)
	)
	(zone
		(layer "In1.Cu")
		(hatch none 0.5)
		(connect_pads
			(clearance 0)
		)
		(min_thickness 0.25)
		(keepout
			(tracks not_allowed)
			(vias allowed)
			(pads allowed)
			(copperpour not_allowed)
			(footprints allowed)
		)
		(placement
			(enabled no)
			(sheetname "")
		)
		(fill
			(thermal_gap 0.5)
			(thermal_bridge_width 0.5)
			(island_removal_mode 0)
		)
		(polygon
			(pts
				(arc
					(start 195.353432 -291.93236)
					(mid 195.349712 -291.94134)
					(end 195.340732 -291.94506)
				)
				(arc
					(start 193.867532 -291.94506)
					(mid 193.858552 -291.94134)
					(end 193.854832 -291.93236)
				)
				(arc
					(start 193.854832 -291.437822)
					(mid 193.858552 -291.428842)
					(end 193.867532 -291.425122)
				)
				(arc
					(start 195.340732 -291.425122)
					(mid 195.349712 -291.428842)
					(end 195.353432 -291.437822)
				)
			)
		)
	)
	(zone
		(layer "In1.Cu")
		(hatch none 0.5)
		(connect_pads
			(clearance 0)
		)
		(min_thickness 0.25)
		(keepout
			(tracks not_allowed)
			(vias allowed)
			(pads allowed)
			(copperpour not_allowed)
			(footprints allowed)
		)
		(placement
			(enabled no)
			(sheetname "")
		)
		(fill
			(thermal_gap 0.5)
			(thermal_bridge_width 0.5)
			(island_removal_mode 0)
		)
		(polygon
			(pts
				(arc
					(start 450.8373 -302.982122)
					(mid 450.83358 -302.991102)
					(end 450.8246 -302.994822)
				)
				(arc
					(start 449.3514 -302.994822)
					(mid 449.34242 -302.991102)
					(end 449.3387 -302.982122)
				)
				(arc
					(start 449.3387 -302.487584)
					(mid 449.34242 -302.478604)
					(end 449.3514 -302.474884)
				)
				(arc
					(start 450.8246 -302.474884)
					(mid 450.83358 -302.478604)
					(end 450.8373 -302.487584)
				)
			)
		)
	)
	(zone
		(layer "In1.Cu")
		(hatch none 0.5)
		(connect_pads
			(clearance 0)
		)
		(min_thickness 0.25)
		(keepout
			(tracks not_allowed)
			(vias allowed)
			(pads allowed)
			(copperpour not_allowed)
			(footprints allowed)
		)
		(placement
			(enabled no)
			(sheetname "")
		)
		(fill
			(thermal_gap 0.5)
			(thermal_bridge_width 0.5)
			(island_removal_mode 0)
		)
		(polygon
			(pts
				(arc
					(start 52.633372 -197.582536)
					(mid 52.629652 -197.591516)
					(end 52.620672 -197.595236)
				)
				(arc
					(start 51.147472 -197.595236)
					(mid 51.138492 -197.591516)
					(end 51.134772 -197.582536)
				)
				(arc
					(start 51.134772 -197.087998)
					(mid 51.138492 -197.079018)
					(end 51.147472 -197.075298)
				)
				(arc
					(start 52.620672 -197.075298)
					(mid 52.629652 -197.079018)
					(end 52.633372 -197.087998)
				)
			)
		)
	)
	(zone
		(layer "In1.Cu")
		(hatch none 0.5)
		(connect_pads
			(clearance 0)
		)
		(min_thickness 0.25)
		(keepout
			(tracks not_allowed)
			(vias allowed)
			(pads allowed)
			(copperpour not_allowed)
			(footprints allowed)
		)
		(placement
			(enabled no)
			(sheetname "")
		)
		(fill
			(thermal_gap 0.5)
			(thermal_bridge_width 0.5)
			(island_removal_mode 0)
		)
		(polygon
			(pts
				(arc
					(start 443.2935 -232.432098)
					(mid 443.28978 -232.441078)
					(end 443.2808 -232.444798)
				)
				(arc
					(start 441.8076 -232.444798)
					(mid 441.79862 -232.441078)
					(end 441.7949 -232.432098)
				)
				(arc
					(start 441.7949 -231.93756)
					(mid 441.79862 -231.92858)
					(end 441.8076 -231.92486)
				)
				(arc
					(start 443.2808 -231.92486)
					(mid 443.28978 -231.92858)
					(end 443.2935 -231.93756)
				)
			)
		)
	)
	(zone
		(layer "In1.Cu")
		(hatch none 0.5)
		(connect_pads
			(clearance 0)
		)
		(min_thickness 0.25)
		(keepout
			(tracks not_allowed)
			(vias allowed)
			(pads allowed)
			(copperpour not_allowed)
			(footprints allowed)
		)
		(placement
			(enabled no)
			(sheetname "")
		)
		(fill
			(thermal_gap 0.5)
			(thermal_bridge_width 0.5)
			(island_removal_mode 0)
		)
		(polygon
			(pts
				(arc
					(start 277.941532 -244.332252)
					(mid 277.937812 -244.341232)
					(end 277.928832 -244.344952)
				)
				(arc
					(start 276.455632 -244.344952)
					(mid 276.446652 -244.341232)
					(end 276.442932 -244.332252)
				)
				(arc
					(start 276.442932 -243.837714)
					(mid 276.446652 -243.828734)
					(end 276.455632 -243.825014)
				)
				(arc
					(start 277.928832 -243.825014)
					(mid 277.937812 -243.828734)
					(end 277.941532 -243.837714)
				)
			)
		)
	)
	(zone
		(layer "In1.Cu")
		(hatch none 0.5)
		(connect_pads
			(clearance 0)
		)
		(min_thickness 0.25)
		(keepout
			(tracks not_allowed)
			(vias allowed)
			(pads allowed)
			(copperpour not_allowed)
			(footprints allowed)
		)
		(placement
			(enabled no)
			(sheetname "")
		)
		(fill
			(thermal_gap 0.5)
			(thermal_bridge_width 0.5)
			(island_removal_mode 0)
		)
		(polygon
			(pts
				(arc
					(start 310.190896 -391.822686)
					(mid 310.317896 -391.949686)
					(end 310.444896 -391.822686)
				)
				(arc
					(start 310.444896 -391.746486)
					(mid 310.317896 -391.619486)
					(end 310.190896 -391.746486)
				)
			)
		)
	)
	(zone
		(layer "In1.Cu")
		(hatch none 0.5)
		(connect_pads
			(clearance 0)
		)
		(min_thickness 0.25)
		(keepout
			(tracks not_allowed)
			(vias allowed)
			(pads allowed)
			(copperpour not_allowed)
			(footprints allowed)
		)
		(placement
			(enabled no)
			(sheetname "")
		)
		(fill
			(thermal_gap 0.5)
			(thermal_bridge_width 0.5)
			(island_removal_mode 0)
		)
		(polygon
			(pts
				(arc
					(start 300.57344 -200.982326)
					(mid 300.56972 -200.991306)
					(end 300.56074 -200.995026)
				)
				(arc
					(start 299.08754 -200.995026)
					(mid 299.07856 -200.991306)
					(end 299.07484 -200.982326)
				)
				(arc
					(start 299.07484 -200.487788)
					(mid 299.07856 -200.478808)
					(end 299.08754 -200.475088)
				)
				(arc
					(start 300.56074 -200.475088)
					(mid 300.56972 -200.478808)
					(end 300.57344 -200.487788)
				)
			)
		)
	)
	(zone
		(layer "In1.Cu")
		(hatch none 0.5)
		(connect_pads
			(clearance 0)
		)
		(min_thickness 0.25)
		(keepout
			(tracks not_allowed)
			(vias allowed)
			(pads allowed)
			(copperpour not_allowed)
			(footprints allowed)
		)
		(placement
			(enabled no)
			(sheetname "")
		)
		(fill
			(thermal_gap 0.5)
			(thermal_bridge_width 0.5)
			(island_removal_mode 0)
		)
		(polygon
			(pts
				(arc
					(start 139.77112 -32.17926)
					(mid 139.793438 -32.233142)
					(end 139.84732 -32.25546)
				)
				(arc
					(start 140.20292 -32.25546)
					(mid 140.256802 -32.233142)
					(end 140.27912 -32.17926)
				)
				(arc
					(start 140.27912 -30.27426)
					(mid 140.256802 -30.220378)
					(end 140.20292 -30.19806)
				)
				(arc
					(start 139.84732 -30.19806)
					(mid 139.793438 -30.220378)
					(end 139.77112 -30.27426)
				)
			)
		)
	)
	(zone
		(layer "In1.Cu")
		(hatch none 0.5)
		(connect_pads
			(clearance 0)
		)
		(min_thickness 0.25)
		(keepout
			(tracks not_allowed)
			(vias allowed)
			(pads allowed)
			(copperpour not_allowed)
			(footprints allowed)
		)
		(placement
			(enabled no)
			(sheetname "")
		)
		(fill
			(thermal_gap 0.5)
			(thermal_bridge_width 0.5)
			(island_removal_mode 0)
		)
		(polygon
			(pts
				(arc
					(start 18.357342 -237.532418)
					(mid 18.353622 -237.541398)
					(end 18.344642 -237.545118)
				)
				(arc
					(start 16.871442 -237.545118)
					(mid 16.862462 -237.541398)
					(end 16.858742 -237.532418)
				)
				(arc
					(start 16.858742 -237.03788)
					(mid 16.862462 -237.0289)
					(end 16.871442 -237.02518)
				)
				(arc
					(start 18.344642 -237.02518)
					(mid 18.353622 -237.0289)
					(end 18.357342 -237.03788)
				)
			)
		)
	)
	(zone
		(layer "In1.Cu")
		(hatch none 0.5)
		(connect_pads
			(clearance 0)
		)
		(min_thickness 0.25)
		(keepout
			(tracks not_allowed)
			(vias allowed)
			(pads allowed)
			(copperpour not_allowed)
			(footprints allowed)
		)
		(placement
			(enabled no)
			(sheetname "")
		)
		(fill
			(thermal_gap 0.5)
			(thermal_bridge_width 0.5)
			(island_removal_mode 0)
		)
		(polygon
			(pts
				(arc
					(start 447.393568 -233.282236)
					(mid 447.389848 -233.291216)
					(end 447.380868 -233.294936)
				)
				(arc
					(start 445.907668 -233.294936)
					(mid 445.898688 -233.291216)
					(end 445.894968 -233.282236)
				)
				(arc
					(start 445.894968 -232.787698)
					(mid 445.898688 -232.778718)
					(end 445.907668 -232.774998)
				)
				(arc
					(start 447.380868 -232.774998)
					(mid 447.389848 -232.778718)
					(end 447.393568 -232.787698)
				)
			)
		)
	)
	(zone
		(layer "In1.Cu")
		(hatch none 0.5)
		(connect_pads
			(clearance 0)
		)
		(min_thickness 0.25)
		(keepout
			(tracks not_allowed)
			(vias allowed)
			(pads allowed)
			(copperpour not_allowed)
			(footprints allowed)
		)
		(placement
			(enabled no)
			(sheetname "")
		)
		(fill
			(thermal_gap 0.5)
			(thermal_bridge_width 0.5)
			(island_removal_mode 0)
		)
		(polygon
			(pts
				(arc
					(start 311.970166 -399.143474)
					(mid 311.665366 -399.143474)
					(end 311.970166 -399.143474)
				)
			)
		)
	)
	(zone
		(layer "In1.Cu")
		(hatch none 0.5)
		(connect_pads
			(clearance 0)
		)
		(min_thickness 0.25)
		(keepout
			(tracks not_allowed)
			(vias allowed)
			(pads allowed)
			(copperpour not_allowed)
			(footprints allowed)
		)
		(placement
			(enabled no)
			(sheetname "")
		)
		(fill
			(thermal_gap 0.5)
			(thermal_bridge_width 0.5)
			(island_removal_mode 0)
		)
		(polygon
			(pts
				(arc
					(start 335.518506 -399.701258)
					(mid 335.645506 -399.828258)
					(end 335.772506 -399.701258)
				)
				(arc
					(start 335.772506 -399.625058)
					(mid 335.645506 -399.498058)
					(end 335.518506 -399.625058)
				)
			)
		)
	)
	(zone
		(layer "In1.Cu")
		(hatch none 0.5)
		(connect_pads
			(clearance 0)
		)
		(min_thickness 0.25)
		(keepout
			(tracks not_allowed)
			(vias allowed)
			(pads allowed)
			(copperpour not_allowed)
			(footprints allowed)
		)
		(placement
			(enabled no)
			(sheetname "")
		)
		(fill
			(thermal_gap 0.5)
			(thermal_bridge_width 0.5)
			(island_removal_mode 0)
		)
		(polygon
			(pts
				(arc
					(start 45.089318 -254.532384)
					(mid 45.085598 -254.541364)
					(end 45.076618 -254.545084)
				)
				(arc
					(start 43.603418 -254.545084)
					(mid 43.594438 -254.541364)
					(end 43.590718 -254.532384)
				)
				(arc
					(start 43.590718 -254.037846)
					(mid 43.594438 -254.028866)
					(end 43.603418 -254.025146)
				)
				(arc
					(start 45.076618 -254.025146)
					(mid 45.085598 -254.028866)
					(end 45.089318 -254.037846)
				)
			)
		)
	)
	(zone
		(layer "In1.Cu")
		(hatch none 0.5)
		(connect_pads
			(clearance 0)
		)
		(min_thickness 0.25)
		(keepout
			(tracks not_allowed)
			(vias allowed)
			(pads allowed)
			(copperpour not_allowed)
			(footprints allowed)
		)
		(placement
			(enabled no)
			(sheetname "")
		)
		(fill
			(thermal_gap 0.5)
			(thermal_bridge_width 0.5)
			(island_removal_mode 0)
		)
		(polygon
			(pts
				(arc
					(start 277.941532 -266.432284)
					(mid 277.937812 -266.441264)
					(end 277.928832 -266.444984)
				)
				(arc
					(start 276.455632 -266.444984)
					(mid 276.446652 -266.441264)
					(end 276.442932 -266.432284)
				)
				(arc
					(start 276.442932 -265.937746)
					(mid 276.446652 -265.928766)
					(end 276.455632 -265.925046)
				)
				(arc
					(start 277.928832 -265.925046)
					(mid 277.937812 -265.928766)
					(end 277.941532 -265.937746)
				)
			)
		)
	)
	(zone
		(layer "In1.Cu")
		(hatch none 0.5)
		(connect_pads
			(clearance 0)
		)
		(min_thickness 0.25)
		(keepout
			(tracks not_allowed)
			(vias allowed)
			(pads allowed)
			(copperpour not_allowed)
			(footprints allowed)
		)
		(placement
			(enabled no)
			(sheetname "")
		)
		(fill
			(thermal_gap 0.5)
			(thermal_bridge_width 0.5)
			(island_removal_mode 0)
		)
		(polygon
			(pts
				(arc
					(start 304.017426 -201.83221)
					(mid 304.013706 -201.84119)
					(end 304.004726 -201.84491)
				)
				(arc
					(start 302.531526 -201.84491)
					(mid 302.522546 -201.84119)
					(end 302.518826 -201.83221)
				)
				(arc
					(start 302.518826 -201.337672)
					(mid 302.522546 -201.328692)
					(end 302.531526 -201.324972)
				)
				(arc
					(start 304.004726 -201.324972)
					(mid 304.013706 -201.328692)
					(end 304.017426 -201.337672)
				)
			)
		)
	)
	(zone
		(layer "In1.Cu")
		(hatch none 0.5)
		(connect_pads
			(clearance 0)
		)
		(min_thickness 0.25)
		(keepout
			(tracks not_allowed)
			(vias allowed)
			(pads allowed)
			(copperpour not_allowed)
			(footprints allowed)
		)
		(placement
			(enabled no)
			(sheetname "")
		)
		(fill
			(thermal_gap 0.5)
			(thermal_bridge_width 0.5)
			(island_removal_mode 0)
		)
		(polygon
			(pts
				(arc
					(start 265.87831 -226.235006)
					(mid 265.21791 -226.235006)
					(end 265.87831 -226.235006)
				)
			)
		)
	)
	(zone
		(layer "In1.Cu")
		(hatch none 0.5)
		(connect_pads
			(clearance 0)
		)
		(min_thickness 0.25)
		(keepout
			(tracks not_allowed)
			(vias allowed)
			(pads allowed)
			(copperpour not_allowed)
			(footprints allowed)
		)
		(placement
			(enabled no)
			(sheetname "")
		)
		(fill
			(thermal_gap 0.5)
			(thermal_bridge_width 0.5)
			(island_removal_mode 0)
		)
		(polygon
			(pts
				(arc
					(start 20.903692 -16.443198)
					(mid 20.92601 -16.49708)
					(end 20.979892 -16.519398)
				)
				(arc
					(start 21.175472 -16.519398)
					(mid 21.197348 -16.516266)
					(end 21.217382 -16.506952)
				)
				(arc
					(start 21.511006 -16.31442)
					(mid 21.552662 -16.302018)
					(end 21.594318 -16.31442)
				)
				(arc
					(start 21.889212 -16.506952)
					(mid 21.909136 -16.516188)
					(end 21.930868 -16.519398)
				)
				(arc
					(start 22.125432 -16.519398)
					(mid 22.179314 -16.49708)
					(end 22.201632 -16.443198)
				)
				(arc
					(start 22.201632 -15.757398)
					(mid 22.179314 -15.703516)
					(end 22.125432 -15.681198)
				)
				(arc
					(start 21.930868 -15.681198)
					(mid 21.909124 -15.684366)
					(end 21.889212 -15.693644)
				)
				(arc
					(start 21.593048 -15.88643)
					(mid 21.551364 -15.898652)
					(end 21.509736 -15.886176)
				)
				(arc
					(start 21.216112 -15.693644)
					(mid 21.196188 -15.684408)
					(end 21.174456 -15.681198)
				)
				(arc
					(start 20.979892 -15.681198)
					(mid 20.92601 -15.703516)
					(end 20.903692 -15.757398)
				)
			)
		)
	)
	(zone
		(layer "In1.Cu")
		(hatch none 0.5)
		(connect_pads
			(clearance 0)
		)
		(min_thickness 0.25)
		(keepout
			(tracks not_allowed)
			(vias allowed)
			(pads allowed)
			(copperpour not_allowed)
			(footprints allowed)
		)
		(placement
			(enabled no)
			(sheetname "")
		)
		(fill
			(thermal_gap 0.5)
			(thermal_bridge_width 0.5)
			(island_removal_mode 0)
		)
		(polygon
			(pts
				(arc
					(start 439.849514 -269.832328)
					(mid 439.845794 -269.841308)
					(end 439.836814 -269.845028)
				)
				(arc
					(start 438.363614 -269.845028)
					(mid 438.354634 -269.841308)
					(end 438.350914 -269.832328)
				)
				(arc
					(start 438.350914 -269.33779)
					(mid 438.354634 -269.32881)
					(end 438.363614 -269.32509)
				)
				(arc
					(start 439.836814 -269.32509)
					(mid 439.845794 -269.32881)
					(end 439.849514 -269.33779)
				)
			)
		)
	)
	(zone
		(layer "In1.Cu")
		(hatch none 0.5)
		(connect_pads
			(clearance 0)
		)
		(min_thickness 0.25)
		(keepout
			(tracks not_allowed)
			(vias allowed)
			(pads allowed)
			(copperpour not_allowed)
			(footprints allowed)
		)
		(placement
			(enabled no)
			(sheetname "")
		)
		(fill
			(thermal_gap 0.5)
			(thermal_bridge_width 0.5)
			(island_removal_mode 0)
		)
		(polygon
			(pts
				(arc
					(start 281.385264 -204.382116)
					(mid 281.381544 -204.391096)
					(end 281.372564 -204.394816)
				)
				(arc
					(start 279.899364 -204.394816)
					(mid 279.890384 -204.391096)
					(end 279.886664 -204.382116)
				)
				(arc
					(start 279.886664 -203.887578)
					(mid 279.890384 -203.878598)
					(end 279.899364 -203.874878)
				)
				(arc
					(start 281.372564 -203.874878)
					(mid 281.381544 -203.878598)
					(end 281.385264 -203.887578)
				)
			)
		)
	)
	(zone
		(layer "In1.Cu")
		(hatch none 0.5)
		(connect_pads
			(clearance 0)
		)
		(min_thickness 0.25)
		(keepout
			(tracks not_allowed)
			(vias allowed)
			(pads allowed)
			(copperpour not_allowed)
			(footprints allowed)
		)
		(placement
			(enabled no)
			(sheetname "")
		)
		(fill
			(thermal_gap 0.5)
			(thermal_bridge_width 0.5)
			(island_removal_mode 0)
		)
		(polygon
			(pts
				(arc
					(start 413.117284 -235.832142)
					(mid 413.113564 -235.841122)
					(end 413.104584 -235.844842)
				)
				(arc
					(start 411.631384 -235.844842)
					(mid 411.622404 -235.841122)
					(end 411.618684 -235.832142)
				)
				(arc
					(start 411.618684 -235.337604)
					(mid 411.622404 -235.328624)
					(end 411.631384 -235.324904)
				)
				(arc
					(start 413.104584 -235.324904)
					(mid 413.113564 -235.328624)
					(end 413.117284 -235.337604)
				)
			)
		)
	)
	(zone
		(layer "In1.Cu")
		(hatch none 0.5)
		(connect_pads
			(clearance 0)
		)
		(min_thickness 0.25)
		(keepout
			(tracks not_allowed)
			(vias allowed)
			(pads allowed)
			(copperpour not_allowed)
			(footprints allowed)
		)
		(placement
			(enabled no)
			(sheetname "")
		)
		(fill
			(thermal_gap 0.5)
			(thermal_bridge_width 0.5)
			(island_removal_mode 0)
		)
		(polygon
			(pts
				(arc
					(start 191.909446 -298.732448)
					(mid 191.905726 -298.741428)
					(end 191.896746 -298.745148)
				)
				(arc
					(start 190.423546 -298.745148)
					(mid 190.414566 -298.741428)
					(end 190.410846 -298.732448)
				)
				(arc
					(start 190.410846 -298.23791)
					(mid 190.414566 -298.22893)
					(end 190.423546 -298.22521)
				)
				(arc
					(start 191.896746 -298.22521)
					(mid 191.905726 -298.22893)
					(end 191.909446 -298.23791)
				)
			)
		)
	)
	(zone
		(layer "In1.Cu")
		(hatch none 0.5)
		(connect_pads
			(clearance 0)
		)
		(min_thickness 0.25)
		(keepout
			(tracks not_allowed)
			(vias allowed)
			(pads allowed)
			(copperpour not_allowed)
			(footprints allowed)
		)
		(placement
			(enabled no)
			(sheetname "")
		)
		(fill
			(thermal_gap 0.5)
			(thermal_bridge_width 0.5)
			(island_removal_mode 0)
		)
		(polygon
			(pts
				(arc
					(start 424.761406 -229.032308)
					(mid 424.757686 -229.041288)
					(end 424.748706 -229.045008)
				)
				(arc
					(start 423.275506 -229.045008)
					(mid 423.266526 -229.041288)
					(end 423.262806 -229.032308)
				)
				(arc
					(start 423.262806 -228.53777)
					(mid 423.266526 -228.52879)
					(end 423.275506 -228.52507)
				)
				(arc
					(start 424.748706 -228.52507)
					(mid 424.757686 -228.52879)
					(end 424.761406 -228.53777)
				)
			)
		)
	)
	(zone
		(layer "In1.Cu")
		(hatch none 0.5)
		(connect_pads
			(clearance 0)
		)
		(min_thickness 0.25)
		(keepout
			(tracks not_allowed)
			(vias allowed)
			(pads allowed)
			(copperpour not_allowed)
			(footprints allowed)
		)
		(placement
			(enabled no)
			(sheetname "")
		)
		(fill
			(thermal_gap 0.5)
			(thermal_bridge_width 0.5)
			(island_removal_mode 0)
		)
		(polygon
			(pts
				(arc
					(start 428.205392 -285.982156)
					(mid 428.201672 -285.991136)
					(end 428.192692 -285.994856)
				)
				(arc
					(start 426.719492 -285.994856)
					(mid 426.710512 -285.991136)
					(end 426.706792 -285.982156)
				)
				(arc
					(start 426.706792 -285.487618)
					(mid 426.710512 -285.478638)
					(end 426.719492 -285.474918)
				)
				(arc
					(start 428.192692 -285.474918)
					(mid 428.201672 -285.478638)
					(end 428.205392 -285.487618)
				)
			)
		)
	)
	(zone
		(layer "In1.Cu")
		(hatch none 0.5)
		(connect_pads
			(clearance 0)
		)
		(min_thickness 0.25)
		(keepout
			(tracks not_allowed)
			(vias allowed)
			(pads allowed)
			(copperpour not_allowed)
			(footprints allowed)
		)
		(placement
			(enabled no)
			(sheetname "")
		)
		(fill
			(thermal_gap 0.5)
			(thermal_bridge_width 0.5)
			(island_removal_mode 0)
		)
		(polygon
			(pts
				(arc
					(start 37.545264 -285.132526)
					(mid 37.541544 -285.141506)
					(end 37.532564 -285.145226)
				)
				(arc
					(start 36.059364 -285.145226)
					(mid 36.050384 -285.141506)
					(end 36.046664 -285.132526)
				)
				(arc
					(start 36.046664 -284.637988)
					(mid 36.050384 -284.629008)
					(end 36.059364 -284.625288)
				)
				(arc
					(start 37.532564 -284.625288)
					(mid 37.541544 -284.629008)
					(end 37.545264 -284.637988)
				)
			)
		)
	)
	(zone
		(layer "In1.Cu")
		(hatch none 0.5)
		(connect_pads
			(clearance 0)
		)
		(min_thickness 0.25)
		(keepout
			(tracks not_allowed)
			(vias allowed)
			(pads allowed)
			(copperpour not_allowed)
			(footprints allowed)
		)
		(placement
			(enabled no)
			(sheetname "")
		)
		(fill
			(thermal_gap 0.5)
			(thermal_bridge_width 0.5)
			(island_removal_mode 0)
		)
		(polygon
			(pts
				(arc
					(start 157.418786 -391.319258)
					(mid 157.545786 -391.446258)
					(end 157.672786 -391.319258)
				)
				(arc
					(start 157.672786 -391.243058)
					(mid 157.545786 -391.116058)
					(end 157.418786 -391.243058)
				)
			)
		)
	)
	(zone
		(layer "In1.Cu")
		(hatch none 0.5)
		(connect_pads
			(clearance 0)
		)
		(min_thickness 0.25)
		(keepout
			(tracks not_allowed)
			(vias allowed)
			(pads allowed)
			(copperpour not_allowed)
			(footprints allowed)
		)
		(placement
			(enabled no)
			(sheetname "")
		)
		(fill
			(thermal_gap 0.5)
			(thermal_bridge_width 0.5)
			(island_removal_mode 0)
		)
		(polygon
			(pts
				(arc
					(start 176.821338 -261.332472)
					(mid 176.817618 -261.341452)
					(end 176.808638 -261.345172)
				)
				(arc
					(start 175.335438 -261.345172)
					(mid 175.326458 -261.341452)
					(end 175.322738 -261.332472)
				)
				(arc
					(start 175.322738 -260.837934)
					(mid 175.326458 -260.828954)
					(end 175.335438 -260.825234)
				)
				(arc
					(start 176.808638 -260.825234)
					(mid 176.817618 -260.828954)
					(end 176.821338 -260.837934)
				)
			)
		)
	)
	(zone
		(layer "In1.Cu")
		(hatch none 0.5)
		(connect_pads
			(clearance 0)
		)
		(min_thickness 0.25)
		(keepout
			(tracks not_allowed)
			(vias allowed)
			(pads allowed)
			(copperpour not_allowed)
			(footprints allowed)
		)
		(placement
			(enabled no)
			(sheetname "")
		)
		(fill
			(thermal_gap 0.5)
			(thermal_bridge_width 0.5)
			(island_removal_mode 0)
		)
		(polygon
			(pts
				(arc
					(start 273.841464 -291.932106)
					(mid 273.837744 -291.941086)
					(end 273.828764 -291.944806)
				)
				(arc
					(start 272.355564 -291.944806)
					(mid 272.346584 -291.941086)
					(end 272.342864 -291.932106)
				)
				(arc
					(start 272.342864 -291.437568)
					(mid 272.346584 -291.428588)
					(end 272.355564 -291.424868)
				)
				(arc
					(start 273.828764 -291.424868)
					(mid 273.837744 -291.428588)
					(end 273.841464 -291.437568)
				)
			)
		)
	)
	(zone
		(layer "In1.Cu")
		(hatch none 0.5)
		(connect_pads
			(clearance 0)
		)
		(min_thickness 0.25)
		(keepout
			(tracks not_allowed)
			(vias allowed)
			(pads allowed)
			(copperpour not_allowed)
			(footprints allowed)
		)
		(placement
			(enabled no)
			(sheetname "")
		)
		(fill
			(thermal_gap 0.5)
			(thermal_bridge_width 0.5)
			(island_removal_mode 0)
		)
		(polygon
			(pts
				(arc
					(start 206.9973 -291.082476)
					(mid 206.99358 -291.091456)
					(end 206.9846 -291.095176)
				)
				(arc
					(start 205.5114 -291.095176)
					(mid 205.50242 -291.091456)
					(end 205.4987 -291.082476)
				)
				(arc
					(start 205.4987 -290.587938)
					(mid 205.50242 -290.578958)
					(end 205.5114 -290.575238)
				)
				(arc
					(start 206.9846 -290.575238)
					(mid 206.99358 -290.578958)
					(end 206.9973 -290.587938)
				)
			)
		)
	)
	(zone
		(layer "In1.Cu")
		(hatch none 0.5)
		(connect_pads
			(clearance 0)
		)
		(min_thickness 0.25)
		(keepout
			(tracks not_allowed)
			(vias allowed)
			(pads allowed)
			(copperpour not_allowed)
			(footprints allowed)
		)
		(placement
			(enabled no)
			(sheetname "")
		)
		(fill
			(thermal_gap 0.5)
			(thermal_bridge_width 0.5)
			(island_removal_mode 0)
		)
		(polygon
			(pts
				(arc
					(start 187.809378 -274.932394)
					(mid 187.805658 -274.941374)
					(end 187.796678 -274.945094)
				)
				(arc
					(start 186.323478 -274.945094)
					(mid 186.314498 -274.941374)
					(end 186.310778 -274.932394)
				)
				(arc
					(start 186.310778 -274.437856)
					(mid 186.314498 -274.428876)
					(end 186.323478 -274.425156)
				)
				(arc
					(start 187.796678 -274.425156)
					(mid 187.805658 -274.428876)
					(end 187.809378 -274.437856)
				)
			)
		)
	)
	(zone
		(layer "In1.Cu")
		(hatch none 0.5)
		(connect_pads
			(clearance 0)
		)
		(min_thickness 0.25)
		(keepout
			(tracks not_allowed)
			(vias allowed)
			(pads allowed)
			(copperpour not_allowed)
			(footprints allowed)
		)
		(placement
			(enabled no)
			(sheetname "")
		)
		(fill
			(thermal_gap 0.5)
			(thermal_bridge_width 0.5)
			(island_removal_mode 0)
		)
		(polygon
			(pts
				(arc
					(start 454.937368 -276.632162)
					(mid 454.933648 -276.641142)
					(end 454.924668 -276.644862)
				)
				(arc
					(start 453.451468 -276.644862)
					(mid 453.442488 -276.641142)
					(end 453.438768 -276.632162)
				)
				(arc
					(start 453.438768 -276.137624)
					(mid 453.442488 -276.128644)
					(end 453.451468 -276.124924)
				)
				(arc
					(start 454.924668 -276.124924)
					(mid 454.933648 -276.128644)
					(end 454.937368 -276.137624)
				)
			)
		)
	)
	(zone
		(layer "In1.Cu")
		(hatch none 0.5)
		(connect_pads
			(clearance 0)
		)
		(min_thickness 0.25)
		(keepout
			(tracks not_allowed)
			(vias allowed)
			(pads allowed)
			(copperpour not_allowed)
			(footprints allowed)
		)
		(placement
			(enabled no)
			(sheetname "")
		)
		(fill
			(thermal_gap 0.5)
			(thermal_bridge_width 0.5)
			(island_removal_mode 0)
		)
		(polygon
			(pts
				(arc
					(start 37.545264 -298.732448)
					(mid 37.541544 -298.741428)
					(end 37.532564 -298.745148)
				)
				(arc
					(start 36.059364 -298.745148)
					(mid 36.050384 -298.741428)
					(end 36.046664 -298.732448)
				)
				(arc
					(start 36.046664 -298.23791)
					(mid 36.050384 -298.22893)
					(end 36.059364 -298.22521)
				)
				(arc
					(start 37.532564 -298.22521)
					(mid 37.541544 -298.22893)
					(end 37.545264 -298.23791)
				)
			)
		)
	)
	(zone
		(layer "In1.Cu")
		(hatch none 0.5)
		(connect_pads
			(clearance 0)
		)
		(min_thickness 0.25)
		(keepout
			(tracks not_allowed)
			(vias allowed)
			(pads allowed)
			(copperpour not_allowed)
			(footprints allowed)
		)
		(placement
			(enabled no)
			(sheetname "")
		)
		(fill
			(thermal_gap 0.5)
			(thermal_bridge_width 0.5)
			(island_removal_mode 0)
		)
		(polygon
			(pts
				(arc
					(start 30.001464 -200.98258)
					(mid 29.997744 -200.99156)
					(end 29.988764 -200.99528)
				)
				(arc
					(start 28.515564 -200.99528)
					(mid 28.506584 -200.99156)
					(end 28.502864 -200.98258)
				)
				(arc
					(start 28.502864 -200.488042)
					(mid 28.506584 -200.479062)
					(end 28.515564 -200.475342)
				)
				(arc
					(start 29.988764 -200.475342)
					(mid 29.997744 -200.479062)
					(end 30.001464 -200.488042)
				)
			)
		)
	)
	(zone
		(layer "In1.Cu")
		(hatch none 0.5)
		(connect_pads
			(clearance 0)
		)
		(min_thickness 0.25)
		(keepout
			(tracks not_allowed)
			(vias allowed)
			(pads allowed)
			(copperpour not_allowed)
			(footprints allowed)
		)
		(placement
			(enabled no)
			(sheetname "")
		)
		(fill
			(thermal_gap 0.5)
			(thermal_bridge_width 0.5)
			(island_removal_mode 0)
		)
		(polygon
			(pts
				(arc
					(start 407.418794 -391.822686)
					(mid 407.545794 -391.949686)
					(end 407.672794 -391.822686)
				)
				(arc
					(start 407.672794 -391.746486)
					(mid 407.545794 -391.619486)
					(end 407.418794 -391.746486)
				)
			)
		)
	)
	(zone
		(layer "In1.Cu")
		(hatch none 0.5)
		(connect_pads
			(clearance 0)
		)
		(min_thickness 0.25)
		(keepout
			(tracks not_allowed)
			(vias allowed)
			(pads allowed)
			(copperpour not_allowed)
			(footprints allowed)
		)
		(placement
			(enabled no)
			(sheetname "")
		)
		(fill
			(thermal_gap 0.5)
			(thermal_bridge_width 0.5)
			(island_removal_mode 0)
		)
		(polygon
			(pts
				(arc
					(start 56.077358 -314.032392)
					(mid 56.073638 -314.041372)
					(end 56.064658 -314.045092)
				)
				(arc
					(start 54.591458 -314.045092)
					(mid 54.582478 -314.041372)
					(end 54.578758 -314.032392)
				)
				(arc
					(start 54.578758 -313.537854)
					(mid 54.582478 -313.528874)
					(end 54.591458 -313.525154)
				)
				(arc
					(start 56.064658 -313.525154)
					(mid 56.073638 -313.528874)
					(end 56.077358 -313.537854)
				)
			)
		)
	)
	(zone
		(layer "In1.Cu")
		(hatch none 0.5)
		(connect_pads
			(clearance 0)
		)
		(min_thickness 0.25)
		(keepout
			(tracks not_allowed)
			(vias allowed)
			(pads allowed)
			(copperpour not_allowed)
			(footprints allowed)
		)
		(placement
			(enabled no)
			(sheetname "")
		)
		(fill
			(thermal_gap 0.5)
			(thermal_bridge_width 0.5)
			(island_removal_mode 0)
		)
		(polygon
			(pts
				(arc
					(start 176.821338 -233.28249)
					(mid 176.817618 -233.29147)
					(end 176.808638 -233.29519)
				)
				(arc
					(start 175.335438 -233.29519)
					(mid 175.326458 -233.29147)
					(end 175.322738 -233.28249)
				)
				(arc
					(start 175.322738 -232.787952)
					(mid 175.326458 -232.778972)
					(end 175.335438 -232.775252)
				)
				(arc
					(start 176.808638 -232.775252)
					(mid 176.817618 -232.778972)
					(end 176.821338 -232.787952)
				)
			)
		)
	)
	(zone
		(layer "In1.Cu")
		(hatch none 0.5)
		(connect_pads
			(clearance 0)
		)
		(min_thickness 0.25)
		(keepout
			(tracks not_allowed)
			(vias allowed)
			(pads allowed)
			(copperpour not_allowed)
			(footprints allowed)
		)
		(placement
			(enabled no)
			(sheetname "")
		)
		(fill
			(thermal_gap 0.5)
			(thermal_bridge_width 0.5)
			(island_removal_mode 0)
		)
		(polygon
			(pts
				(arc
					(start 281.385264 -312.332116)
					(mid 281.381544 -312.341096)
					(end 281.372564 -312.344816)
				)
				(arc
					(start 279.899364 -312.344816)
					(mid 279.890384 -312.341096)
					(end 279.886664 -312.332116)
				)
				(arc
					(start 279.886664 -311.837578)
					(mid 279.890384 -311.828598)
					(end 279.899364 -311.824878)
				)
				(arc
					(start 281.372564 -311.824878)
					(mid 281.381544 -311.828598)
					(end 281.385264 -311.837578)
				)
			)
		)
	)
	(zone
		(layer "In1.Cu")
		(hatch none 0.5)
		(connect_pads
			(clearance 0)
		)
		(min_thickness 0.25)
		(keepout
			(tracks not_allowed)
			(vias allowed)
			(pads allowed)
			(copperpour not_allowed)
			(footprints allowed)
		)
		(placement
			(enabled no)
			(sheetname "")
		)
		(fill
			(thermal_gap 0.5)
			(thermal_bridge_width 0.5)
			(island_removal_mode 0)
		)
		(polygon
			(pts
				(arc
					(start 176.821338 -292.782498)
					(mid 176.817618 -292.791478)
					(end 176.808638 -292.795198)
				)
				(arc
					(start 175.335438 -292.795198)
					(mid 175.326458 -292.791478)
					(end 175.322738 -292.782498)
				)
				(arc
					(start 175.322738 -292.28796)
					(mid 175.326458 -292.27898)
					(end 175.335438 -292.27526)
				)
				(arc
					(start 176.808638 -292.27526)
					(mid 176.817618 -292.27898)
					(end 176.821338 -292.28796)
				)
			)
		)
	)
	(zone
		(layer "In1.Cu")
		(hatch none 0.5)
		(connect_pads
			(clearance 0)
		)
		(min_thickness 0.25)
		(keepout
			(tracks not_allowed)
			(vias allowed)
			(pads allowed)
			(copperpour not_allowed)
			(footprints allowed)
		)
		(placement
			(enabled no)
			(sheetname "")
		)
		(fill
			(thermal_gap 0.5)
			(thermal_bridge_width 0.5)
			(island_removal_mode 0)
		)
		(polygon
			(pts
				(arc
					(start 165.177216 -229.882446)
					(mid 165.173496 -229.891426)
					(end 165.164516 -229.895146)
				)
				(arc
					(start 163.691316 -229.895146)
					(mid 163.682336 -229.891426)
					(end 163.678616 -229.882446)
				)
				(arc
					(start 163.678616 -229.387908)
					(mid 163.682336 -229.378928)
					(end 163.691316 -229.375208)
				)
				(arc
					(start 165.164516 -229.375208)
					(mid 165.173496 -229.378928)
					(end 165.177216 -229.387908)
				)
			)
		)
	)
	(zone
		(layer "In1.Cu")
		(hatch none 0.5)
		(connect_pads
			(clearance 0)
		)
		(min_thickness 0.25)
		(keepout
			(tracks not_allowed)
			(vias allowed)
			(pads allowed)
			(copperpour not_allowed)
			(footprints allowed)
		)
		(placement
			(enabled no)
			(sheetname "")
		)
		(fill
			(thermal_gap 0.5)
			(thermal_bridge_width 0.5)
			(island_removal_mode 0)
		)
		(polygon
			(pts
				(arc
					(start 316.770258 -392.30427)
					(mid 316.465458 -392.30427)
					(end 316.770258 -392.30427)
				)
			)
		)
	)
	(zone
		(layer "In1.Cu")
		(hatch none 0.5)
		(connect_pads
			(clearance 0)
		)
		(min_thickness 0.25)
		(keepout
			(tracks not_allowed)
			(vias allowed)
			(pads allowed)
			(copperpour not_allowed)
			(footprints allowed)
		)
		(placement
			(enabled no)
			(sheetname "")
		)
		(fill
			(thermal_gap 0.5)
			(thermal_bridge_width 0.5)
			(island_removal_mode 0)
		)
		(polygon
			(pts
				(arc
					(start 314.990734 -391.822686)
					(mid 315.117734 -391.949686)
					(end 315.244734 -391.822686)
				)
				(arc
					(start 315.244734 -391.746486)
					(mid 315.117734 -391.619486)
					(end 314.990734 -391.746486)
				)
			)
		)
	)
	(zone
		(layer "In1.Cu")
		(hatch none 0.5)
		(connect_pads
			(clearance 0)
		)
		(min_thickness 0.25)
		(keepout
			(tracks not_allowed)
			(vias allowed)
			(pads allowed)
			(copperpour not_allowed)
			(footprints allowed)
		)
		(placement
			(enabled no)
			(sheetname "")
		)
		(fill
			(thermal_gap 0.5)
			(thermal_bridge_width 0.5)
			(island_removal_mode 0)
		)
		(polygon
			(pts
				(arc
					(start 202.897232 -250.282456)
					(mid 202.893512 -250.291436)
					(end 202.884532 -250.295156)
				)
				(arc
					(start 201.411332 -250.295156)
					(mid 201.402352 -250.291436)
					(end 201.398632 -250.282456)
				)
				(arc
					(start 201.398632 -249.787918)
					(mid 201.402352 -249.778938)
					(end 201.411332 -249.775218)
				)
				(arc
					(start 202.884532 -249.775218)
					(mid 202.893512 -249.778938)
					(end 202.897232 -249.787918)
				)
			)
		)
	)
	(zone
		(layer "In1.Cu")
		(hatch none 0.5)
		(connect_pads
			(clearance 0)
		)
		(min_thickness 0.25)
		(keepout
			(tracks not_allowed)
			(vias allowed)
			(pads allowed)
			(copperpour not_allowed)
			(footprints allowed)
		)
		(placement
			(enabled no)
			(sheetname "")
		)
		(fill
			(thermal_gap 0.5)
			(thermal_bridge_width 0.5)
			(island_removal_mode 0)
		)
		(polygon
			(pts
				(arc
					(start 439.849514 -247.732296)
					(mid 439.845794 -247.741276)
					(end 439.836814 -247.744996)
				)
				(arc
					(start 438.363614 -247.744996)
					(mid 438.354634 -247.741276)
					(end 438.350914 -247.732296)
				)
				(arc
					(start 438.350914 -247.237758)
					(mid 438.354634 -247.228778)
					(end 438.363614 -247.225058)
				)
				(arc
					(start 439.836814 -247.225058)
					(mid 439.845794 -247.228778)
					(end 439.849514 -247.237758)
				)
			)
		)
	)
	(zone
		(layer "In1.Cu")
		(hatch none 0.5)
		(connect_pads
			(clearance 0)
		)
		(min_thickness 0.25)
		(keepout
			(tracks not_allowed)
			(vias allowed)
			(pads allowed)
			(copperpour not_allowed)
			(footprints allowed)
		)
		(placement
			(enabled no)
			(sheetname "")
		)
		(fill
			(thermal_gap 0.5)
			(thermal_bridge_width 0.5)
			(island_removal_mode 0)
		)
		(polygon
			(pts
				(arc
					(start 56.077358 -213.732364)
					(mid 56.073638 -213.741344)
					(end 56.064658 -213.745064)
				)
				(arc
					(start 54.591458 -213.745064)
					(mid 54.582478 -213.741344)
					(end 54.578758 -213.732364)
				)
				(arc
					(start 54.578758 -213.237826)
					(mid 54.582478 -213.228846)
					(end 54.591458 -213.225126)
				)
				(arc
					(start 56.064658 -213.225126)
					(mid 56.073638 -213.228846)
					(end 56.077358 -213.237826)
				)
			)
		)
	)
	(zone
		(layer "In1.Cu")
		(hatch none 0.5)
		(connect_pads
			(clearance 0)
		)
		(min_thickness 0.25)
		(keepout
			(tracks not_allowed)
			(vias allowed)
			(pads allowed)
			(copperpour not_allowed)
			(footprints allowed)
		)
		(placement
			(enabled no)
			(sheetname "")
		)
		(fill
			(thermal_gap 0.5)
			(thermal_bridge_width 0.5)
			(island_removal_mode 0)
		)
		(polygon
			(pts
				(arc
					(start 378.961142 -397.156432)
					(mid 378.580142 -397.156432)
					(end 378.961142 -397.156432)
				)
			)
		)
	)
	(zone
		(layer "In1.Cu")
		(hatch none 0.5)
		(connect_pads
			(clearance 0)
		)
		(min_thickness 0.25)
		(keepout
			(tracks not_allowed)
			(vias allowed)
			(pads allowed)
			(copperpour not_allowed)
			(footprints allowed)
		)
		(placement
			(enabled no)
			(sheetname "")
		)
		(fill
			(thermal_gap 0.5)
			(thermal_bridge_width 0.5)
			(island_removal_mode 0)
		)
		(polygon
			(pts
				(arc
					(start 347.98889 -397.156432)
					(mid 347.60789 -397.156432)
					(end 347.98889 -397.156432)
				)
			)
		)
	)
	(zone
		(layer "In1.Cu")
		(hatch none 0.5)
		(connect_pads
			(clearance 0)
		)
		(min_thickness 0.25)
		(keepout
			(tracks not_allowed)
			(vias allowed)
			(pads allowed)
			(copperpour not_allowed)
			(footprints allowed)
		)
		(placement
			(enabled no)
			(sheetname "")
		)
		(fill
			(thermal_gap 0.5)
			(thermal_bridge_width 0.5)
			(island_removal_mode 0)
		)
		(polygon
			(pts
				(arc
					(start 33.445196 -245.18239)
					(mid 33.441476 -245.19137)
					(end 33.432496 -245.19509)
				)
				(arc
					(start 31.959296 -245.19509)
					(mid 31.950316 -245.19137)
					(end 31.946596 -245.18239)
				)
				(arc
					(start 31.946596 -244.687852)
					(mid 31.950316 -244.678872)
					(end 31.959296 -244.675152)
				)
				(arc
					(start 33.432496 -244.675152)
					(mid 33.441476 -244.678872)
					(end 33.445196 -244.687852)
				)
			)
		)
	)
	(zone
		(layer "In1.Cu")
		(hatch none 0.5)
		(connect_pads
			(clearance 0)
		)
		(min_thickness 0.25)
		(keepout
			(tracks not_allowed)
			(vias allowed)
			(pads allowed)
			(copperpour not_allowed)
			(footprints allowed)
		)
		(placement
			(enabled no)
			(sheetname "")
		)
		(fill
			(thermal_gap 0.5)
			(thermal_bridge_width 0.5)
			(island_removal_mode 0)
		)
		(polygon
			(pts
				(arc
					(start 30.001464 -216.282524)
					(mid 29.997744 -216.291504)
					(end 29.988764 -216.295224)
				)
				(arc
					(start 28.515564 -216.295224)
					(mid 28.506584 -216.291504)
					(end 28.502864 -216.282524)
				)
				(arc
					(start 28.502864 -215.787986)
					(mid 28.506584 -215.779006)
					(end 28.515564 -215.775286)
				)
				(arc
					(start 29.988764 -215.775286)
					(mid 29.997744 -215.779006)
					(end 30.001464 -215.787986)
				)
			)
		)
	)
	(zone
		(layer "In1.Cu")
		(hatch none 0.5)
		(connect_pads
			(clearance 0)
		)
		(min_thickness 0.25)
		(keepout
			(tracks not_allowed)
			(vias allowed)
			(pads allowed)
			(copperpour not_allowed)
			(footprints allowed)
		)
		(placement
			(enabled no)
			(sheetname "")
		)
		(fill
			(thermal_gap 0.5)
			(thermal_bridge_width 0.5)
			(island_removal_mode 0)
		)
		(polygon
			(pts
				(arc
					(start 172.72127 -240.082578)
					(mid 172.71755 -240.091558)
					(end 172.70857 -240.095278)
				)
				(arc
					(start 171.23537 -240.095278)
					(mid 171.22639 -240.091558)
					(end 171.22267 -240.082578)
				)
				(arc
					(start 171.22267 -239.58804)
					(mid 171.22639 -239.57906)
					(end 171.23537 -239.57534)
				)
				(arc
					(start 172.70857 -239.57534)
					(mid 172.71755 -239.57906)
					(end 172.72127 -239.58804)
				)
			)
		)
	)
	(zone
		(layer "In1.Cu")
		(hatch none 0.5)
		(connect_pads
			(clearance 0)
		)
		(min_thickness 0.25)
		(keepout
			(tracks not_allowed)
			(vias allowed)
			(pads allowed)
			(copperpour not_allowed)
			(footprints allowed)
		)
		(placement
			(enabled no)
			(sheetname "")
		)
		(fill
			(thermal_gap 0.5)
			(thermal_bridge_width 0.5)
			(island_removal_mode 0)
		)
		(polygon
			(pts
				(arc
					(start 187.809378 -297.882564)
					(mid 187.805658 -297.891544)
					(end 187.796678 -297.895264)
				)
				(arc
					(start 186.323478 -297.895264)
					(mid 186.314498 -297.891544)
					(end 186.310778 -297.882564)
				)
				(arc
					(start 186.310778 -297.388026)
					(mid 186.314498 -297.379046)
					(end 186.323478 -297.375326)
				)
				(arc
					(start 187.796678 -297.375326)
					(mid 187.805658 -297.379046)
					(end 187.809378 -297.388026)
				)
			)
		)
	)
	(zone
		(layer "In1.Cu")
		(hatch none 0.5)
		(connect_pads
			(clearance 0)
		)
		(min_thickness 0.25)
		(keepout
			(tracks not_allowed)
			(vias allowed)
			(pads allowed)
			(copperpour not_allowed)
			(footprints allowed)
		)
		(placement
			(enabled no)
			(sheetname "")
		)
		(fill
			(thermal_gap 0.5)
			(thermal_bridge_width 0.5)
			(island_removal_mode 0)
		)
		(polygon
			(pts
				(arc
					(start 454.937368 -211.182204)
					(mid 454.933648 -211.191184)
					(end 454.924668 -211.194904)
				)
				(arc
					(start 453.451468 -211.194904)
					(mid 453.442488 -211.191184)
					(end 453.438768 -211.182204)
				)
				(arc
					(start 453.438768 -210.687666)
					(mid 453.442488 -210.678686)
					(end 453.451468 -210.674966)
				)
				(arc
					(start 454.924668 -210.674966)
					(mid 454.933648 -210.678686)
					(end 454.937368 -210.687666)
				)
			)
		)
	)
	(zone
		(layer "In1.Cu")
		(hatch none 0.5)
		(connect_pads
			(clearance 0)
		)
		(min_thickness 0.25)
		(keepout
			(tracks not_allowed)
			(vias allowed)
			(pads allowed)
			(copperpour not_allowed)
			(footprints allowed)
		)
		(placement
			(enabled no)
			(sheetname "")
		)
		(fill
			(thermal_gap 0.5)
			(thermal_bridge_width 0.5)
			(island_removal_mode 0)
		)
		(polygon
			(pts
				(arc
					(start 18.357342 -251.982478)
					(mid 18.353622 -251.991458)
					(end 18.344642 -251.995178)
				)
				(arc
					(start 16.871442 -251.995178)
					(mid 16.862462 -251.991458)
					(end 16.858742 -251.982478)
				)
				(arc
					(start 16.858742 -251.48794)
					(mid 16.862462 -251.47896)
					(end 16.871442 -251.47524)
				)
				(arc
					(start 18.344642 -251.47524)
					(mid 18.353622 -251.47896)
					(end 18.357342 -251.48794)
				)
			)
		)
	)
	(zone
		(layer "In1.Cu")
		(hatch none 0.5)
		(connect_pads
			(clearance 0)
		)
		(min_thickness 0.25)
		(keepout
			(tracks not_allowed)
			(vias allowed)
			(pads allowed)
			(copperpour not_allowed)
			(footprints allowed)
		)
		(placement
			(enabled no)
			(sheetname "")
		)
		(fill
			(thermal_gap 0.5)
			(thermal_bridge_width 0.5)
			(island_removal_mode 0)
		)
		(polygon
			(pts
				(arc
					(start 187.809378 -228.182424)
					(mid 187.805658 -228.191404)
					(end 187.796678 -228.195124)
				)
				(arc
					(start 186.323478 -228.195124)
					(mid 186.314498 -228.191404)
					(end 186.310778 -228.182424)
				)
				(arc
					(start 186.310778 -227.687886)
					(mid 186.314498 -227.678906)
					(end 186.323478 -227.675186)
				)
				(arc
					(start 187.796678 -227.675186)
					(mid 187.805658 -227.678906)
					(end 187.809378 -227.687886)
				)
			)
		)
	)
	(zone
		(layer "In1.Cu")
		(hatch none 0.5)
		(connect_pads
			(clearance 0)
		)
		(min_thickness 0.25)
		(keepout
			(tracks not_allowed)
			(vias allowed)
			(pads allowed)
			(copperpour not_allowed)
			(footprints allowed)
		)
		(placement
			(enabled no)
			(sheetname "")
		)
		(fill
			(thermal_gap 0.5)
			(thermal_bridge_width 0.5)
			(island_removal_mode 0)
		)
		(polygon
			(pts
				(arc
					(start 195.353432 -276.632416)
					(mid 195.349712 -276.641396)
					(end 195.340732 -276.645116)
				)
				(arc
					(start 193.867532 -276.645116)
					(mid 193.858552 -276.641396)
					(end 193.854832 -276.632416)
				)
				(arc
					(start 193.854832 -276.137878)
					(mid 193.858552 -276.128898)
					(end 193.867532 -276.125178)
				)
				(arc
					(start 195.340732 -276.125178)
					(mid 195.349712 -276.128898)
					(end 195.353432 -276.137878)
				)
			)
		)
	)
	(zone
		(layer "In1.Cu")
		(hatch none 0.5)
		(connect_pads
			(clearance 0)
		)
		(min_thickness 0.25)
		(keepout
			(tracks not_allowed)
			(vias allowed)
			(pads allowed)
			(copperpour not_allowed)
			(footprints allowed)
		)
		(placement
			(enabled no)
			(sheetname "")
		)
		(fill
			(thermal_gap 0.5)
			(thermal_bridge_width 0.5)
			(island_removal_mode 0)
		)
		(polygon
			(pts
				(arc
					(start 191.909446 -269.832582)
					(mid 191.905726 -269.841562)
					(end 191.896746 -269.845282)
				)
				(arc
					(start 190.423546 -269.845282)
					(mid 190.414566 -269.841562)
					(end 190.410846 -269.832582)
				)
				(arc
					(start 190.410846 -269.338044)
					(mid 190.414566 -269.329064)
					(end 190.423546 -269.325344)
				)
				(arc
					(start 191.896746 -269.325344)
					(mid 191.905726 -269.329064)
					(end 191.909446 -269.338044)
				)
			)
		)
	)
	(zone
		(layer "In1.Cu")
		(hatch none 0.5)
		(connect_pads
			(clearance 0)
		)
		(min_thickness 0.25)
		(keepout
			(tracks not_allowed)
			(vias allowed)
			(pads allowed)
			(copperpour not_allowed)
			(footprints allowed)
		)
		(placement
			(enabled no)
			(sheetname "")
		)
		(fill
			(thermal_gap 0.5)
			(thermal_bridge_width 0.5)
			(island_removal_mode 0)
		)
		(polygon
			(pts
				(arc
					(start 450.8373 -213.73211)
					(mid 450.83358 -213.74109)
					(end 450.8246 -213.74481)
				)
				(arc
					(start 449.3514 -213.74481)
					(mid 449.34242 -213.74109)
					(end 449.3387 -213.73211)
				)
				(arc
					(start 449.3387 -213.237572)
					(mid 449.34242 -213.228592)
					(end 449.3514 -213.224872)
				)
				(arc
					(start 450.8246 -213.224872)
					(mid 450.83358 -213.228592)
					(end 450.8373 -213.237572)
				)
			)
		)
	)
	(zone
		(layer "In1.Cu")
		(hatch none 0.5)
		(connect_pads
			(clearance 0)
		)
		(min_thickness 0.25)
		(keepout
			(tracks not_allowed)
			(vias allowed)
			(pads allowed)
			(copperpour not_allowed)
			(footprints allowed)
		)
		(placement
			(enabled no)
			(sheetname "")
		)
		(fill
			(thermal_gap 0.5)
			(thermal_bridge_width 0.5)
			(island_removal_mode 0)
		)
		(polygon
			(pts
				(arc
					(start 52.633372 -239.23244)
					(mid 52.629652 -239.24142)
					(end 52.620672 -239.24514)
				)
				(arc
					(start 51.147472 -239.24514)
					(mid 51.138492 -239.24142)
					(end 51.134772 -239.23244)
				)
				(arc
					(start 51.134772 -238.737902)
					(mid 51.138492 -238.728922)
					(end 51.147472 -238.725202)
				)
				(arc
					(start 52.620672 -238.725202)
					(mid 52.629652 -238.728922)
					(end 52.633372 -238.737902)
				)
			)
		)
	)
	(zone
		(layer "In1.Cu")
		(hatch none 0.5)
		(connect_pads
			(clearance 0)
		)
		(min_thickness 0.25)
		(keepout
			(tracks not_allowed)
			(vias allowed)
			(pads allowed)
			(copperpour not_allowed)
			(footprints allowed)
		)
		(placement
			(enabled no)
			(sheetname "")
		)
		(fill
			(thermal_gap 0.5)
			(thermal_bridge_width 0.5)
			(island_removal_mode 0)
		)
		(polygon
			(pts
				(arc
					(start 317.970154 -399.143474)
					(mid 317.665354 -399.143474)
					(end 317.970154 -399.143474)
				)
			)
		)
	)
	(zone
		(layer "In1.Cu")
		(hatch none 0.5)
		(connect_pads
			(clearance 0)
		)
		(min_thickness 0.25)
		(keepout
			(tracks not_allowed)
			(vias allowed)
			(pads allowed)
			(copperpour not_allowed)
			(footprints allowed)
		)
		(placement
			(enabled no)
			(sheetname "")
		)
		(fill
			(thermal_gap 0.5)
			(thermal_bridge_width 0.5)
			(island_removal_mode 0)
		)
		(polygon
			(pts
				(arc
					(start 300.57344 -227.332286)
					(mid 300.56972 -227.341266)
					(end 300.56074 -227.344986)
				)
				(arc
					(start 299.08754 -227.344986)
					(mid 299.07856 -227.341266)
					(end 299.07484 -227.332286)
				)
				(arc
					(start 299.07484 -226.837748)
					(mid 299.07856 -226.828768)
					(end 299.08754 -226.825048)
				)
				(arc
					(start 300.56074 -226.825048)
					(mid 300.56972 -226.828768)
					(end 300.57344 -226.837748)
				)
			)
		)
	)
	(zone
		(layer "In1.Cu")
		(hatch none 0.5)
		(connect_pads
			(clearance 0)
		)
		(min_thickness 0.25)
		(keepout
			(tracks not_allowed)
			(vias allowed)
			(pads allowed)
			(copperpour not_allowed)
			(footprints allowed)
		)
		(placement
			(enabled no)
			(sheetname "")
		)
		(fill
			(thermal_gap 0.5)
			(thermal_bridge_width 0.5)
			(island_removal_mode 0)
		)
		(polygon
			(pts
				(arc
					(start 187.809378 -229.882446)
					(mid 187.805658 -229.891426)
					(end 187.796678 -229.895146)
				)
				(arc
					(start 186.323478 -229.895146)
					(mid 186.314498 -229.891426)
					(end 186.310778 -229.882446)
				)
				(arc
					(start 186.310778 -229.387908)
					(mid 186.314498 -229.378928)
					(end 186.323478 -229.375208)
				)
				(arc
					(start 187.796678 -229.375208)
					(mid 187.805658 -229.378928)
					(end 187.809378 -229.387908)
				)
			)
		)
	)
	(zone
		(layer "In1.Cu")
		(hatch none 0.5)
		(connect_pads
			(clearance 0)
		)
		(min_thickness 0.25)
		(keepout
			(tracks not_allowed)
			(vias allowed)
			(pads allowed)
			(copperpour not_allowed)
			(footprints allowed)
		)
		(placement
			(enabled no)
			(sheetname "")
		)
		(fill
			(thermal_gap 0.5)
			(thermal_bridge_width 0.5)
			(island_removal_mode 0)
		)
		(polygon
			(pts
				(arc
					(start 388.961122 -397.849344)
					(mid 388.580122 -397.849344)
					(end 388.961122 -397.849344)
				)
			)
		)
	)
	(zone
		(layer "In1.Cu")
		(hatch none 0.5)
		(connect_pads
			(clearance 0)
		)
		(min_thickness 0.25)
		(keepout
			(tracks not_allowed)
			(vias allowed)
			(pads allowed)
			(copperpour not_allowed)
			(footprints allowed)
		)
		(placement
			(enabled no)
			(sheetname "")
		)
		(fill
			(thermal_gap 0.5)
			(thermal_bridge_width 0.5)
			(island_removal_mode 0)
		)
		(polygon
			(pts
				(arc
					(start 447.393568 -276.632162)
					(mid 447.389848 -276.641142)
					(end 447.380868 -276.644862)
				)
				(arc
					(start 445.907668 -276.644862)
					(mid 445.898688 -276.641142)
					(end 445.894968 -276.632162)
				)
				(arc
					(start 445.894968 -276.137624)
					(mid 445.898688 -276.128644)
					(end 445.907668 -276.124924)
				)
				(arc
					(start 447.380868 -276.124924)
					(mid 447.389848 -276.128644)
					(end 447.393568 -276.137624)
				)
			)
		)
	)
	(zone
		(layer "In1.Cu")
		(hatch none 0.5)
		(connect_pads
			(clearance 0)
		)
		(min_thickness 0.25)
		(keepout
			(tracks not_allowed)
			(vias allowed)
			(pads allowed)
			(copperpour not_allowed)
			(footprints allowed)
		)
		(placement
			(enabled no)
			(sheetname "")
		)
		(fill
			(thermal_gap 0.5)
			(thermal_bridge_width 0.5)
			(island_removal_mode 0)
		)
		(polygon
			(pts
				(arc
					(start 25.901396 -304.682398)
					(mid 25.897676 -304.691378)
					(end 25.888696 -304.695098)
				)
				(arc
					(start 24.415496 -304.695098)
					(mid 24.406516 -304.691378)
					(end 24.402796 -304.682398)
				)
				(arc
					(start 24.402796 -304.18786)
					(mid 24.406516 -304.17888)
					(end 24.415496 -304.17516)
				)
				(arc
					(start 25.888696 -304.17516)
					(mid 25.897676 -304.17888)
					(end 25.901396 -304.18786)
				)
			)
		)
	)
	(zone
		(layer "In1.Cu")
		(hatch none 0.5)
		(connect_pads
			(clearance 0)
		)
		(min_thickness 0.25)
		(keepout
			(tracks not_allowed)
			(vias allowed)
			(pads allowed)
			(copperpour not_allowed)
			(footprints allowed)
		)
		(placement
			(enabled no)
			(sheetname "")
		)
		(fill
			(thermal_gap 0.5)
			(thermal_bridge_width 0.5)
			(island_removal_mode 0)
		)
		(polygon
			(pts
				(arc
					(start 187.809378 -234.132374)
					(mid 187.805658 -234.141354)
					(end 187.796678 -234.145074)
				)
				(arc
					(start 186.323478 -234.145074)
					(mid 186.314498 -234.141354)
					(end 186.310778 -234.132374)
				)
				(arc
					(start 186.310778 -233.637836)
					(mid 186.314498 -233.628856)
					(end 186.323478 -233.625136)
				)
				(arc
					(start 187.796678 -233.625136)
					(mid 187.805658 -233.628856)
					(end 187.809378 -233.637836)
				)
			)
		)
	)
	(zone
		(layer "In1.Cu")
		(hatch none 0.5)
		(connect_pads
			(clearance 0)
		)
		(min_thickness 0.25)
		(keepout
			(tracks not_allowed)
			(vias allowed)
			(pads allowed)
			(copperpour not_allowed)
			(footprints allowed)
		)
		(placement
			(enabled no)
			(sheetname "")
		)
		(fill
			(thermal_gap 0.5)
			(thermal_bridge_width 0.5)
			(island_removal_mode 0)
		)
		(polygon
			(pts
				(arc
					(start 184.365392 -217.982546)
					(mid 184.361672 -217.991526)
					(end 184.352692 -217.995246)
				)
				(arc
					(start 182.879492 -217.995246)
					(mid 182.870512 -217.991526)
					(end 182.866792 -217.982546)
				)
				(arc
					(start 182.866792 -217.488008)
					(mid 182.870512 -217.479028)
					(end 182.879492 -217.475308)
				)
				(arc
					(start 184.352692 -217.475308)
					(mid 184.361672 -217.479028)
					(end 184.365392 -217.488008)
				)
			)
		)
	)
	(zone
		(layer "In1.Cu")
		(hatch none 0.5)
		(connect_pads
			(clearance 0)
		)
		(min_thickness 0.25)
		(keepout
			(tracks not_allowed)
			(vias allowed)
			(pads allowed)
			(copperpour not_allowed)
			(footprints allowed)
		)
		(placement
			(enabled no)
			(sheetname "")
		)
		(fill
			(thermal_gap 0.5)
			(thermal_bridge_width 0.5)
			(island_removal_mode 0)
		)
		(polygon
			(pts
				(arc
					(start 420.661338 -235.832142)
					(mid 420.657618 -235.841122)
					(end 420.648638 -235.844842)
				)
				(arc
					(start 419.175438 -235.844842)
					(mid 419.166458 -235.841122)
					(end 419.162738 -235.832142)
				)
				(arc
					(start 419.162738 -235.337604)
					(mid 419.166458 -235.328624)
					(end 419.175438 -235.324904)
				)
				(arc
					(start 420.648638 -235.324904)
					(mid 420.657618 -235.328624)
					(end 420.661338 -235.337604)
				)
			)
		)
	)
	(zone
		(layer "In1.Cu")
		(hatch none 0.5)
		(connect_pads
			(clearance 0)
		)
		(min_thickness 0.25)
		(keepout
			(tracks not_allowed)
			(vias allowed)
			(pads allowed)
			(copperpour not_allowed)
			(footprints allowed)
		)
		(placement
			(enabled no)
			(sheetname "")
		)
		(fill
			(thermal_gap 0.5)
			(thermal_bridge_width 0.5)
			(island_removal_mode 0)
		)
		(polygon
			(pts
				(arc
					(start 428.205392 -217.132154)
					(mid 428.201672 -217.141134)
					(end 428.192692 -217.144854)
				)
				(arc
					(start 426.719492 -217.144854)
					(mid 426.710512 -217.141134)
					(end 426.706792 -217.132154)
				)
				(arc
					(start 426.706792 -216.637616)
					(mid 426.710512 -216.628636)
					(end 426.719492 -216.624916)
				)
				(arc
					(start 428.192692 -216.624916)
					(mid 428.201672 -216.628636)
					(end 428.205392 -216.637616)
				)
			)
		)
	)
	(zone
		(layer "In1.Cu")
		(hatch none 0.5)
		(connect_pads
			(clearance 0)
		)
		(min_thickness 0.25)
		(keepout
			(tracks not_allowed)
			(vias allowed)
			(pads allowed)
			(copperpour not_allowed)
			(footprints allowed)
		)
		(placement
			(enabled no)
			(sheetname "")
		)
		(fill
			(thermal_gap 0.5)
			(thermal_bridge_width 0.5)
			(island_removal_mode 0)
		)
		(polygon
			(pts
				(arc
					(start 191.909446 -306.38242)
					(mid 191.905726 -306.3914)
					(end 191.896746 -306.39512)
				)
				(arc
					(start 190.423546 -306.39512)
					(mid 190.414566 -306.3914)
					(end 190.410846 -306.38242)
				)
				(arc
					(start 190.410846 -305.887882)
					(mid 190.414566 -305.878902)
					(end 190.423546 -305.875182)
				)
				(arc
					(start 191.896746 -305.875182)
					(mid 191.905726 -305.878902)
					(end 191.909446 -305.887882)
				)
			)
		)
	)
	(zone
		(layer "In1.Cu")
		(hatch none 0.5)
		(connect_pads
			(clearance 0)
		)
		(min_thickness 0.25)
		(keepout
			(tracks not_allowed)
			(vias allowed)
			(pads allowed)
			(copperpour not_allowed)
			(footprints allowed)
		)
		(placement
			(enabled no)
			(sheetname "")
		)
		(fill
			(thermal_gap 0.5)
			(thermal_bridge_width 0.5)
			(island_removal_mode 0)
		)
		(polygon
			(pts
				(arc
					(start 293.029386 -203.532232)
					(mid 293.025666 -203.541212)
					(end 293.016686 -203.544932)
				)
				(arc
					(start 291.543486 -203.544932)
					(mid 291.534506 -203.541212)
					(end 291.530786 -203.532232)
				)
				(arc
					(start 291.530786 -203.037694)
					(mid 291.534506 -203.028714)
					(end 291.543486 -203.024994)
				)
				(arc
					(start 293.016686 -203.024994)
					(mid 293.025666 -203.028714)
					(end 293.029386 -203.037694)
				)
			)
		)
	)
	(zone
		(layer "In1.Cu")
		(hatch none 0.5)
		(connect_pads
			(clearance 0)
		)
		(min_thickness 0.25)
		(keepout
			(tracks not_allowed)
			(vias allowed)
			(pads allowed)
			(copperpour not_allowed)
			(footprints allowed)
		)
		(placement
			(enabled no)
			(sheetname "")
		)
		(fill
			(thermal_gap 0.5)
			(thermal_bridge_width 0.5)
			(island_removal_mode 0)
		)
		(polygon
			(pts
				(arc
					(start 25.901396 -223.082358)
					(mid 25.897676 -223.091338)
					(end 25.888696 -223.095058)
				)
				(arc
					(start 24.415496 -223.095058)
					(mid 24.406516 -223.091338)
					(end 24.402796 -223.082358)
				)
				(arc
					(start 24.402796 -222.58782)
					(mid 24.406516 -222.57884)
					(end 24.415496 -222.57512)
				)
				(arc
					(start 25.888696 -222.57512)
					(mid 25.897676 -222.57884)
					(end 25.901396 -222.58782)
				)
			)
		)
	)
	(zone
		(layer "In1.Cu")
		(hatch none 0.5)
		(connect_pads
			(clearance 0)
		)
		(min_thickness 0.25)
		(keepout
			(tracks not_allowed)
			(vias allowed)
			(pads allowed)
			(copperpour not_allowed)
			(footprints allowed)
		)
		(placement
			(enabled no)
			(sheetname "")
		)
		(fill
			(thermal_gap 0.5)
			(thermal_bridge_width 0.5)
			(island_removal_mode 0)
		)
		(polygon
			(pts
				(arc
					(start 435.749446 -305.532282)
					(mid 435.745726 -305.541262)
					(end 435.736746 -305.544982)
				)
				(arc
					(start 434.263546 -305.544982)
					(mid 434.254566 -305.541262)
					(end 434.250846 -305.532282)
				)
				(arc
					(start 434.250846 -305.037744)
					(mid 434.254566 -305.028764)
					(end 434.263546 -305.025044)
				)
				(arc
					(start 435.736746 -305.025044)
					(mid 435.745726 -305.028764)
					(end 435.749446 -305.037744)
				)
			)
		)
	)
	(zone
		(layer "In1.Cu")
		(hatch none 0.5)
		(connect_pads
			(clearance 0)
		)
		(min_thickness 0.25)
		(keepout
			(tracks not_allowed)
			(vias allowed)
			(pads allowed)
			(copperpour not_allowed)
			(footprints allowed)
		)
		(placement
			(enabled no)
			(sheetname "")
		)
		(fill
			(thermal_gap 0.5)
			(thermal_bridge_width 0.5)
			(island_removal_mode 0)
		)
		(polygon
			(pts
				(arc
					(start 180.265324 -279.182576)
					(mid 180.261604 -279.191556)
					(end 180.252624 -279.195276)
				)
				(arc
					(start 178.779424 -279.195276)
					(mid 178.770444 -279.191556)
					(end 178.766724 -279.182576)
				)
				(arc
					(start 178.766724 -278.688038)
					(mid 178.770444 -278.679058)
					(end 178.779424 -278.675338)
				)
				(arc
					(start 180.252624 -278.675338)
					(mid 180.261604 -278.679058)
					(end 180.265324 -278.688038)
				)
			)
		)
	)
	(zone
		(layer "In1.Cu")
		(hatch none 0.5)
		(connect_pads
			(clearance 0)
		)
		(min_thickness 0.25)
		(keepout
			(tracks not_allowed)
			(vias allowed)
			(pads allowed)
			(copperpour not_allowed)
			(footprints allowed)
		)
		(placement
			(enabled no)
			(sheetname "")
		)
		(fill
			(thermal_gap 0.5)
			(thermal_bridge_width 0.5)
			(island_removal_mode 0)
		)
		(polygon
			(pts
				(arc
					(start 372.961154 -397.156432)
					(mid 372.580154 -397.156432)
					(end 372.961154 -397.156432)
				)
			)
		)
	)
	(zone
		(layer "In1.Cu")
		(hatch none 0.5)
		(connect_pads
			(clearance 0)
		)
		(min_thickness 0.25)
		(keepout
			(tracks not_allowed)
			(vias allowed)
			(pads allowed)
			(copperpour not_allowed)
			(footprints allowed)
		)
		(placement
			(enabled no)
			(sheetname "")
		)
		(fill
			(thermal_gap 0.5)
			(thermal_bridge_width 0.5)
			(island_removal_mode 0)
		)
		(polygon
			(pts
				(arc
					(start 309.86095 -394.385292)
					(mid 309.47995 -394.385292)
					(end 309.86095 -394.385292)
				)
			)
		)
	)
	(zone
		(layer "In1.Cu")
		(hatch none 0.5)
		(connect_pads
			(clearance 0)
		)
		(min_thickness 0.25)
		(keepout
			(tracks not_allowed)
			(vias allowed)
			(pads allowed)
			(copperpour not_allowed)
			(footprints allowed)
		)
		(placement
			(enabled no)
			(sheetname "")
		)
		(fill
			(thermal_gap 0.5)
			(thermal_bridge_width 0.5)
			(island_removal_mode 0)
		)
		(polygon
			(pts
				(arc
					(start 11.167618 -106.83494)
					(mid 11.189936 -106.888822)
					(end 11.243818 -106.91114)
				)
				(arc
					(start 11.599418 -106.91114)
					(mid 11.6533 -106.888822)
					(end 11.675618 -106.83494)
				)
				(arc
					(start 11.675618 -104.92994)
					(mid 11.6533 -104.876058)
					(end 11.599418 -104.85374)
				)
				(arc
					(start 11.243818 -104.85374)
					(mid 11.189936 -104.876058)
					(end 11.167618 -104.92994)
				)
			)
		)
	)
	(zone
		(layer "In1.Cu")
		(hatch none 0.5)
		(connect_pads
			(clearance 0)
		)
		(min_thickness 0.25)
		(keepout
			(tracks not_allowed)
			(vias allowed)
			(pads allowed)
			(copperpour not_allowed)
			(footprints allowed)
		)
		(placement
			(enabled no)
			(sheetname "")
		)
		(fill
			(thermal_gap 0.5)
			(thermal_bridge_width 0.5)
			(island_removal_mode 0)
		)
		(polygon
			(pts
				(arc
					(start 33.445196 -284.282388)
					(mid 33.441476 -284.291368)
					(end 33.432496 -284.295088)
				)
				(arc
					(start 31.959296 -284.295088)
					(mid 31.950316 -284.291368)
					(end 31.946596 -284.282388)
				)
				(arc
					(start 31.946596 -283.78785)
					(mid 31.950316 -283.77887)
					(end 31.959296 -283.77515)
				)
				(arc
					(start 33.432496 -283.77515)
					(mid 33.441476 -283.77887)
					(end 33.445196 -283.78785)
				)
			)
		)
	)
	(zone
		(layer "In1.Cu")
		(hatch none 0.5)
		(connect_pads
			(clearance 0)
		)
		(min_thickness 0.25)
		(keepout
			(tracks not_allowed)
			(vias allowed)
			(pads allowed)
			(copperpour not_allowed)
			(footprints allowed)
		)
		(placement
			(enabled no)
			(sheetname "")
		)
		(fill
			(thermal_gap 0.5)
			(thermal_bridge_width 0.5)
			(island_removal_mode 0)
		)
		(polygon
			(pts
				(arc
					(start 50.590958 -383.440686)
					(mid 50.717958 -383.567686)
					(end 50.844958 -383.440686)
				)
				(arc
					(start 50.844958 -383.364486)
					(mid 50.717958 -383.237486)
					(end 50.590958 -383.364486)
				)
			)
		)
	)
	(zone
		(layer "In1.Cu")
		(hatch none 0.5)
		(connect_pads
			(clearance 0)
		)
		(min_thickness 0.25)
		(keepout
			(tracks not_allowed)
			(vias allowed)
			(pads allowed)
			(copperpour not_allowed)
			(footprints allowed)
		)
		(placement
			(enabled no)
			(sheetname "")
		)
		(fill
			(thermal_gap 0.5)
			(thermal_bridge_width 0.5)
			(island_removal_mode 0)
		)
		(polygon
			(pts
				(arc
					(start 285.485332 -227.332286)
					(mid 285.481612 -227.341266)
					(end 285.472632 -227.344986)
				)
				(arc
					(start 283.999432 -227.344986)
					(mid 283.990452 -227.341266)
					(end 283.986732 -227.332286)
				)
				(arc
					(start 283.986732 -226.837748)
					(mid 283.990452 -226.828768)
					(end 283.999432 -226.825048)
				)
				(arc
					(start 285.472632 -226.825048)
					(mid 285.481612 -226.828768)
					(end 285.485332 -226.837748)
				)
			)
		)
	)
	(zone
		(layer "In1.Cu")
		(hatch none 0.5)
		(connect_pads
			(clearance 0)
		)
		(min_thickness 0.25)
		(keepout
			(tracks not_allowed)
			(vias allowed)
			(pads allowed)
			(copperpour not_allowed)
			(footprints allowed)
		)
		(placement
			(enabled no)
			(sheetname "")
		)
		(fill
			(thermal_gap 0.5)
			(thermal_bridge_width 0.5)
			(island_removal_mode 0)
		)
		(polygon
			(pts
				(arc
					(start 293.029386 -274.082256)
					(mid 293.025666 -274.091236)
					(end 293.016686 -274.094956)
				)
				(arc
					(start 291.543486 -274.094956)
					(mid 291.534506 -274.091236)
					(end 291.530786 -274.082256)
				)
				(arc
					(start 291.530786 -273.587718)
					(mid 291.534506 -273.578738)
					(end 291.543486 -273.575018)
				)
				(arc
					(start 293.016686 -273.575018)
					(mid 293.025666 -273.578738)
					(end 293.029386 -273.587718)
				)
			)
		)
	)
	(zone
		(layer "In1.Cu")
		(hatch none 0.5)
		(connect_pads
			(clearance 0)
		)
		(min_thickness 0.25)
		(keepout
			(tracks not_allowed)
			(vias allowed)
			(pads allowed)
			(copperpour not_allowed)
			(footprints allowed)
		)
		(placement
			(enabled no)
			(sheetname "")
		)
		(fill
			(thermal_gap 0.5)
			(thermal_bridge_width 0.5)
			(island_removal_mode 0)
		)
		(polygon
			(pts
				(arc
					(start 296.473372 -212.032088)
					(mid 296.469652 -212.041068)
					(end 296.460672 -212.044788)
				)
				(arc
					(start 294.987472 -212.044788)
					(mid 294.978492 -212.041068)
					(end 294.974772 -212.032088)
				)
				(arc
					(start 294.974772 -211.53755)
					(mid 294.978492 -211.52857)
					(end 294.987472 -211.52485)
				)
				(arc
					(start 296.460672 -211.52485)
					(mid 296.469652 -211.52857)
					(end 296.473372 -211.53755)
				)
			)
		)
	)
	(zone
		(layer "In1.Cu")
		(hatch none 0.5)
		(connect_pads
			(clearance 0)
		)
		(min_thickness 0.25)
		(keepout
			(tracks not_allowed)
			(vias allowed)
			(pads allowed)
			(copperpour not_allowed)
			(footprints allowed)
		)
		(placement
			(enabled no)
			(sheetname "")
		)
		(fill
			(thermal_gap 0.5)
			(thermal_bridge_width 0.5)
			(island_removal_mode 0)
		)
		(polygon
			(pts
				(arc
					(start 195.353432 -220.532452)
					(mid 195.349712 -220.541432)
					(end 195.340732 -220.545152)
				)
				(arc
					(start 193.867532 -220.545152)
					(mid 193.858552 -220.541432)
					(end 193.854832 -220.532452)
				)
				(arc
					(start 193.854832 -220.037914)
					(mid 193.858552 -220.028934)
					(end 193.867532 -220.025214)
				)
				(arc
					(start 195.340732 -220.025214)
					(mid 195.349712 -220.028934)
					(end 195.353432 -220.037914)
				)
			)
		)
	)
	(zone
		(layer "In1.Cu")
		(hatch none 0.5)
		(connect_pads
			(clearance 0)
		)
		(min_thickness 0.25)
		(keepout
			(tracks not_allowed)
			(vias allowed)
			(pads allowed)
			(copperpour not_allowed)
			(footprints allowed)
		)
		(placement
			(enabled no)
			(sheetname "")
		)
		(fill
			(thermal_gap 0.5)
			(thermal_bridge_width 0.5)
			(island_removal_mode 0)
		)
		(polygon
			(pts
				(arc
					(start 420.661338 -224.782126)
					(mid 420.657618 -224.791106)
					(end 420.648638 -224.794826)
				)
				(arc
					(start 419.175438 -224.794826)
					(mid 419.166458 -224.791106)
					(end 419.162738 -224.782126)
				)
				(arc
					(start 419.162738 -224.287588)
					(mid 419.166458 -224.278608)
					(end 419.175438 -224.274888)
				)
				(arc
					(start 420.648638 -224.274888)
					(mid 420.657618 -224.278608)
					(end 420.661338 -224.287588)
				)
			)
		)
	)
	(zone
		(layer "In1.Cu")
		(hatch none 0.5)
		(connect_pads
			(clearance 0)
		)
		(min_thickness 0.25)
		(keepout
			(tracks not_allowed)
			(vias allowed)
			(pads allowed)
			(copperpour not_allowed)
			(footprints allowed)
		)
		(placement
			(enabled no)
			(sheetname "")
		)
		(fill
			(thermal_gap 0.5)
			(thermal_bridge_width 0.5)
			(island_removal_mode 0)
		)
		(polygon
			(pts
				(arc
					(start 338.788502 -397.849344)
					(mid 338.407502 -397.849344)
					(end 338.788502 -397.849344)
				)
			)
		)
	)
	(zone
		(layer "In1.Cu")
		(hatch none 0.5)
		(connect_pads
			(clearance 0)
		)
		(min_thickness 0.25)
		(keepout
			(tracks not_allowed)
			(vias allowed)
			(pads allowed)
			(copperpour not_allowed)
			(footprints allowed)
		)
		(placement
			(enabled no)
			(sheetname "")
		)
		(fill
			(thermal_gap 0.5)
			(thermal_bridge_width 0.5)
			(island_removal_mode 0)
		)
		(polygon
			(pts
				(arc
					(start 45.089318 -268.13256)
					(mid 45.085598 -268.14154)
					(end 45.076618 -268.14526)
				)
				(arc
					(start 43.603418 -268.14526)
					(mid 43.594438 -268.14154)
					(end 43.590718 -268.13256)
				)
				(arc
					(start 43.590718 -267.638022)
					(mid 43.594438 -267.629042)
					(end 43.603418 -267.625322)
				)
				(arc
					(start 45.076618 -267.625322)
					(mid 45.085598 -267.629042)
					(end 45.089318 -267.638022)
				)
			)
		)
	)
	(zone
		(layer "In1.Cu")
		(hatch none 0.5)
		(connect_pads
			(clearance 0)
		)
		(min_thickness 0.25)
		(keepout
			(tracks not_allowed)
			(vias allowed)
			(pads allowed)
			(copperpour not_allowed)
			(footprints allowed)
		)
		(placement
			(enabled no)
			(sheetname "")
		)
		(fill
			(thermal_gap 0.5)
			(thermal_bridge_width 0.5)
			(island_removal_mode 0)
		)
		(polygon
			(pts
				(arc
					(start 447.393568 -304.682144)
					(mid 447.389848 -304.691124)
					(end 447.380868 -304.694844)
				)
				(arc
					(start 445.907668 -304.694844)
					(mid 445.898688 -304.691124)
					(end 445.894968 -304.682144)
				)
				(arc
					(start 445.894968 -304.187606)
					(mid 445.898688 -304.178626)
					(end 445.907668 -304.174906)
				)
				(arc
					(start 447.380868 -304.174906)
					(mid 447.389848 -304.178626)
					(end 447.393568 -304.187606)
				)
			)
		)
	)
	(zone
		(layer "In1.Cu")
		(hatch none 0.5)
		(connect_pads
			(clearance 0)
		)
		(min_thickness 0.25)
		(keepout
			(tracks not_allowed)
			(vias allowed)
			(pads allowed)
			(copperpour not_allowed)
			(footprints allowed)
		)
		(placement
			(enabled no)
			(sheetname "")
		)
		(fill
			(thermal_gap 0.5)
			(thermal_bridge_width 0.5)
			(island_removal_mode 0)
		)
		(polygon
			(pts
				(arc
					(start 404.688802 -394.385292)
					(mid 404.307802 -394.385292)
					(end 404.688802 -394.385292)
				)
			)
		)
	)
	(zone
		(layer "In1.Cu")
		(hatch none 0.5)
		(connect_pads
			(clearance 0)
		)
		(min_thickness 0.25)
		(keepout
			(tracks not_allowed)
			(vias allowed)
			(pads allowed)
			(copperpour not_allowed)
			(footprints allowed)
		)
		(placement
			(enabled no)
			(sheetname "")
		)
		(fill
			(thermal_gap 0.5)
			(thermal_bridge_width 0.5)
			(island_removal_mode 0)
		)
		(polygon
			(pts
				(arc
					(start 432.30546 -214.582248)
					(mid 432.30174 -214.591228)
					(end 432.29276 -214.594948)
				)
				(arc
					(start 430.81956 -214.594948)
					(mid 430.81058 -214.591228)
					(end 430.80686 -214.582248)
				)
				(arc
					(start 430.80686 -214.08771)
					(mid 430.81058 -214.07873)
					(end 430.81956 -214.07501)
				)
				(arc
					(start 432.29276 -214.07501)
					(mid 432.30174 -214.07873)
					(end 432.30546 -214.08771)
				)
			)
		)
	)
	(zone
		(layer "In1.Cu")
		(hatch none 0.5)
		(connect_pads
			(clearance 0)
		)
		(min_thickness 0.25)
		(keepout
			(tracks not_allowed)
			(vias allowed)
			(pads allowed)
			(copperpour not_allowed)
			(footprints allowed)
		)
		(placement
			(enabled no)
			(sheetname "")
		)
		(fill
			(thermal_gap 0.5)
			(thermal_bridge_width 0.5)
			(island_removal_mode 0)
		)
		(polygon
			(pts
				(arc
					(start 308.117494 -236.68228)
					(mid 308.113774 -236.69126)
					(end 308.104794 -236.69498)
				)
				(arc
					(start 306.631594 -236.69498)
					(mid 306.622614 -236.69126)
					(end 306.618894 -236.68228)
				)
				(arc
					(start 306.618894 -236.187742)
					(mid 306.622614 -236.178762)
					(end 306.631594 -236.175042)
				)
				(arc
					(start 308.104794 -236.175042)
					(mid 308.113774 -236.178762)
					(end 308.117494 -236.187742)
				)
			)
		)
	)
	(zone
		(layer "In1.Cu")
		(hatch none 0.5)
		(connect_pads
			(clearance 0)
		)
		(min_thickness 0.25)
		(keepout
			(tracks not_allowed)
			(vias allowed)
			(pads allowed)
			(copperpour not_allowed)
			(footprints allowed)
		)
		(placement
			(enabled no)
			(sheetname "")
		)
		(fill
			(thermal_gap 0.5)
			(thermal_bridge_width 0.5)
			(island_removal_mode 0)
		)
		(polygon
			(pts
				(arc
					(start 285.485332 -247.732296)
					(mid 285.481612 -247.741276)
					(end 285.472632 -247.744996)
				)
				(arc
					(start 283.999432 -247.744996)
					(mid 283.990452 -247.741276)
					(end 283.986732 -247.732296)
				)
				(arc
					(start 283.986732 -247.237758)
					(mid 283.990452 -247.228778)
					(end 283.999432 -247.225058)
				)
				(arc
					(start 285.472632 -247.225058)
					(mid 285.481612 -247.228778)
					(end 285.485332 -247.237758)
				)
			)
		)
	)
	(zone
		(layer "In1.Cu")
		(hatch none 0.5)
		(connect_pads
			(clearance 0)
		)
		(min_thickness 0.25)
		(keepout
			(tracks not_allowed)
			(vias allowed)
			(pads allowed)
			(copperpour not_allowed)
			(footprints allowed)
		)
		(placement
			(enabled no)
			(sheetname "")
		)
		(fill
			(thermal_gap 0.5)
			(thermal_bridge_width 0.5)
			(island_removal_mode 0)
		)
		(polygon
			(pts
				(arc
					(start 273.841464 -234.13212)
					(mid 273.837744 -234.1411)
					(end 273.828764 -234.14482)
				)
				(arc
					(start 272.355564 -234.14482)
					(mid 272.346584 -234.1411)
					(end 272.342864 -234.13212)
				)
				(arc
					(start 272.342864 -233.637582)
					(mid 272.346584 -233.628602)
					(end 272.355564 -233.624882)
				)
				(arc
					(start 273.828764 -233.624882)
					(mid 273.837744 -233.628602)
					(end 273.841464 -233.637582)
				)
			)
		)
	)
	(zone
		(layer "In1.Cu")
		(hatch none 0.5)
		(connect_pads
			(clearance 0)
		)
		(min_thickness 0.25)
		(keepout
			(tracks not_allowed)
			(vias allowed)
			(pads allowed)
			(copperpour not_allowed)
			(footprints allowed)
		)
		(placement
			(enabled no)
			(sheetname "")
		)
		(fill
			(thermal_gap 0.5)
			(thermal_bridge_width 0.5)
			(island_removal_mode 0)
		)
		(polygon
			(pts
				(arc
					(start 435.749446 -241.782092)
					(mid 435.745726 -241.791072)
					(end 435.736746 -241.794792)
				)
				(arc
					(start 434.263546 -241.794792)
					(mid 434.254566 -241.791072)
					(end 434.250846 -241.782092)
				)
				(arc
					(start 434.250846 -241.287554)
					(mid 434.254566 -241.278574)
					(end 434.263546 -241.274854)
				)
				(arc
					(start 435.736746 -241.274854)
					(mid 435.745726 -241.278574)
					(end 435.749446 -241.287554)
				)
			)
		)
	)
	(zone
		(layer "In1.Cu")
		(hatch none 0.5)
		(connect_pads
			(clearance 0)
		)
		(min_thickness 0.25)
		(keepout
			(tracks not_allowed)
			(vias allowed)
			(pads allowed)
			(copperpour not_allowed)
			(footprints allowed)
		)
		(placement
			(enabled no)
			(sheetname "")
		)
		(fill
			(thermal_gap 0.5)
			(thermal_bridge_width 0.5)
			(island_removal_mode 0)
		)
		(polygon
			(pts
				(arc
					(start 172.72127 -273.232372)
					(mid 172.71755 -273.241352)
					(end 172.70857 -273.245072)
				)
				(arc
					(start 171.23537 -273.245072)
					(mid 171.22639 -273.241352)
					(end 171.22267 -273.232372)
				)
				(arc
					(start 171.22267 -272.737834)
					(mid 171.22639 -272.728854)
					(end 171.23537 -272.725134)
				)
				(arc
					(start 172.70857 -272.725134)
					(mid 172.71755 -272.728854)
					(end 172.72127 -272.737834)
				)
			)
		)
	)
	(zone
		(layer "In1.Cu")
		(hatch none 0.5)
		(connect_pads
			(clearance 0)
		)
		(min_thickness 0.25)
		(keepout
			(tracks not_allowed)
			(vias allowed)
			(pads allowed)
			(copperpour not_allowed)
			(footprints allowed)
		)
		(placement
			(enabled no)
			(sheetname "")
		)
		(fill
			(thermal_gap 0.5)
			(thermal_bridge_width 0.5)
			(island_removal_mode 0)
		)
		(polygon
			(pts
				(arc
					(start 340.897972 -392.30427)
					(mid 340.593172 -392.30427)
					(end 340.897972 -392.30427)
				)
			)
		)
	)
	(zone
		(layer "In1.Cu")
		(hatch none 0.5)
		(connect_pads
			(clearance 0)
		)
		(min_thickness 0.25)
		(keepout
			(tracks not_allowed)
			(vias allowed)
			(pads allowed)
			(copperpour not_allowed)
			(footprints allowed)
		)
		(placement
			(enabled no)
			(sheetname "")
		)
		(fill
			(thermal_gap 0.5)
			(thermal_bridge_width 0.5)
			(island_removal_mode 0)
		)
		(polygon
			(pts
				(arc
					(start 30.001464 -236.682534)
					(mid 29.997744 -236.691514)
					(end 29.988764 -236.695234)
				)
				(arc
					(start 28.515564 -236.695234)
					(mid 28.506584 -236.691514)
					(end 28.502864 -236.682534)
				)
				(arc
					(start 28.502864 -236.187996)
					(mid 28.506584 -236.179016)
					(end 28.515564 -236.175296)
				)
				(arc
					(start 29.988764 -236.175296)
					(mid 29.997744 -236.179016)
					(end 30.001464 -236.187996)
				)
			)
		)
	)
	(zone
		(layer "In1.Cu")
		(hatch none 0.5)
		(connect_pads
			(clearance 0)
		)
		(min_thickness 0.25)
		(keepout
			(tracks not_allowed)
			(vias allowed)
			(pads allowed)
			(copperpour not_allowed)
			(footprints allowed)
		)
		(placement
			(enabled no)
			(sheetname "")
		)
		(fill
			(thermal_gap 0.5)
			(thermal_bridge_width 0.5)
			(island_removal_mode 0)
		)
		(polygon
			(pts
				(arc
					(start 313.170062 -392.30427)
					(mid 312.865262 -392.30427)
					(end 313.170062 -392.30427)
				)
			)
		)
	)
	(zone
		(layer "In1.Cu")
		(hatch none 0.5)
		(connect_pads
			(clearance 0)
		)
		(min_thickness 0.25)
		(keepout
			(tracks not_allowed)
			(vias allowed)
			(pads allowed)
			(copperpour not_allowed)
			(footprints allowed)
		)
		(placement
			(enabled no)
			(sheetname "")
		)
		(fill
			(thermal_gap 0.5)
			(thermal_bridge_width 0.5)
			(island_removal_mode 0)
		)
		(polygon
			(pts
				(arc
					(start 172.72127 -207.782414)
					(mid 172.71755 -207.791394)
					(end 172.70857 -207.795114)
				)
				(arc
					(start 171.23537 -207.795114)
					(mid 171.22639 -207.791394)
					(end 171.22267 -207.782414)
				)
				(arc
					(start 171.22267 -207.287876)
					(mid 171.22639 -207.278896)
					(end 171.23537 -207.275176)
				)
				(arc
					(start 172.70857 -207.275176)
					(mid 172.71755 -207.278896)
					(end 172.72127 -207.287876)
				)
			)
		)
	)
	(zone
		(layer "In1.Cu")
		(hatch none 0.5)
		(connect_pads
			(clearance 0)
		)
		(min_thickness 0.25)
		(keepout
			(tracks not_allowed)
			(vias allowed)
			(pads allowed)
			(copperpour not_allowed)
			(footprints allowed)
		)
		(placement
			(enabled no)
			(sheetname "")
		)
		(fill
			(thermal_gap 0.5)
			(thermal_bridge_width 0.5)
			(island_removal_mode 0)
		)
		(polygon
			(pts
				(arc
					(start 25.901396 -217.132408)
					(mid 25.897676 -217.141388)
					(end 25.888696 -217.145108)
				)
				(arc
					(start 24.415496 -217.145108)
					(mid 24.406516 -217.141388)
					(end 24.402796 -217.132408)
				)
				(arc
					(start 24.402796 -216.63787)
					(mid 24.406516 -216.62889)
					(end 24.415496 -216.62517)
				)
				(arc
					(start 25.888696 -216.62517)
					(mid 25.897676 -216.62889)
					(end 25.901396 -216.63787)
				)
			)
		)
	)
	(zone
		(layer "In1.Cu")
		(hatch none 0.5)
		(connect_pads
			(clearance 0)
		)
		(min_thickness 0.25)
		(keepout
			(tracks not_allowed)
			(vias allowed)
			(pads allowed)
			(copperpour not_allowed)
			(footprints allowed)
		)
		(placement
			(enabled no)
			(sheetname "")
		)
		(fill
			(thermal_gap 0.5)
			(thermal_bridge_width 0.5)
			(island_removal_mode 0)
		)
		(polygon
			(pts
				(arc
					(start 115.290854 -383.440686)
					(mid 115.417854 -383.567686)
					(end 115.544854 -383.440686)
				)
				(arc
					(start 115.544854 -383.364486)
					(mid 115.417854 -383.237486)
					(end 115.290854 -383.364486)
				)
			)
		)
	)
	(zone
		(layer "In1.Cu")
		(hatch none 0.5)
		(connect_pads
			(clearance 0)
		)
		(min_thickness 0.25)
		(keepout
			(tracks not_allowed)
			(vias allowed)
			(pads allowed)
			(copperpour not_allowed)
			(footprints allowed)
		)
		(placement
			(enabled no)
			(sheetname "")
		)
		(fill
			(thermal_gap 0.5)
			(thermal_bridge_width 0.5)
			(island_removal_mode 0)
		)
		(polygon
			(pts
				(arc
					(start 206.9973 -303.832514)
					(mid 206.99358 -303.841494)
					(end 206.9846 -303.845214)
				)
				(arc
					(start 205.5114 -303.845214)
					(mid 205.50242 -303.841494)
					(end 205.4987 -303.832514)
				)
				(arc
					(start 205.4987 -303.337976)
					(mid 205.50242 -303.328996)
					(end 205.5114 -303.325276)
				)
				(arc
					(start 206.9846 -303.325276)
					(mid 206.99358 -303.328996)
					(end 206.9973 -303.337976)
				)
			)
		)
	)
	(zone
		(layer "In1.Cu")
		(hatch none 0.5)
		(connect_pads
			(clearance 0)
		)
		(min_thickness 0.25)
		(keepout
			(tracks not_allowed)
			(vias allowed)
			(pads allowed)
			(copperpour not_allowed)
			(footprints allowed)
		)
		(placement
			(enabled no)
			(sheetname "")
		)
		(fill
			(thermal_gap 0.5)
			(thermal_bridge_width 0.5)
			(island_removal_mode 0)
		)
		(polygon
			(pts
				(arc
					(start 22.45741 -206.93253)
					(mid 22.45369 -206.94151)
					(end 22.44471 -206.94523)
				)
				(arc
					(start 20.97151 -206.94523)
					(mid 20.96253 -206.94151)
					(end 20.95881 -206.93253)
				)
				(arc
					(start 20.95881 -206.437992)
					(mid 20.96253 -206.429012)
					(end 20.97151 -206.425292)
				)
				(arc
					(start 22.44471 -206.425292)
					(mid 22.45369 -206.429012)
					(end 22.45741 -206.437992)
				)
			)
		)
	)
	(zone
		(layer "In1.Cu")
		(hatch none 0.5)
		(connect_pads
			(clearance 0)
		)
		(min_thickness 0.25)
		(keepout
			(tracks not_allowed)
			(vias allowed)
			(pads allowed)
			(copperpour not_allowed)
			(footprints allowed)
		)
		(placement
			(enabled no)
			(sheetname "")
		)
		(fill
			(thermal_gap 0.5)
			(thermal_bridge_width 0.5)
			(island_removal_mode 0)
		)
		(polygon
			(pts
				(arc
					(start 293.029386 -269.832328)
					(mid 293.025666 -269.841308)
					(end 293.016686 -269.845028)
				)
				(arc
					(start 291.543486 -269.845028)
					(mid 291.534506 -269.841308)
					(end 291.530786 -269.832328)
				)
				(arc
					(start 291.530786 -269.33779)
					(mid 291.534506 -269.32881)
					(end 291.543486 -269.32509)
				)
				(arc
					(start 293.016686 -269.32509)
					(mid 293.025666 -269.32881)
					(end 293.029386 -269.33779)
				)
			)
		)
	)
	(zone
		(layer "In1.Cu")
		(hatch none 0.5)
		(connect_pads
			(clearance 0)
		)
		(min_thickness 0.25)
		(keepout
			(tracks not_allowed)
			(vias allowed)
			(pads allowed)
			(copperpour not_allowed)
			(footprints allowed)
		)
		(placement
			(enabled no)
			(sheetname "")
		)
		(fill
			(thermal_gap 0.5)
			(thermal_bridge_width 0.5)
			(island_removal_mode 0)
		)
		(polygon
			(pts
				(arc
					(start 191.909446 -300.43247)
					(mid 191.905726 -300.44145)
					(end 191.896746 -300.44517)
				)
				(arc
					(start 190.423546 -300.44517)
					(mid 190.414566 -300.44145)
					(end 190.410846 -300.43247)
				)
				(arc
					(start 190.410846 -299.937932)
					(mid 190.414566 -299.928952)
					(end 190.423546 -299.925232)
				)
				(arc
					(start 191.896746 -299.925232)
					(mid 191.905726 -299.928952)
					(end 191.909446 -299.937932)
				)
			)
		)
	)
	(zone
		(layer "In1.Cu")
		(hatch none 0.5)
		(connect_pads
			(clearance 0)
		)
		(min_thickness 0.25)
		(keepout
			(tracks not_allowed)
			(vias allowed)
			(pads allowed)
			(copperpour not_allowed)
			(footprints allowed)
		)
		(placement
			(enabled no)
			(sheetname "")
		)
		(fill
			(thermal_gap 0.5)
			(thermal_bridge_width 0.5)
			(island_removal_mode 0)
		)
		(polygon
			(pts
				(arc
					(start 206.5782 -219.435426)
					(mid 205.9178 -219.435426)
					(end 206.5782 -219.435426)
				)
			)
		)
	)
	(zone
		(layer "In1.Cu")
		(hatch none 0.5)
		(connect_pads
			(clearance 0)
		)
		(min_thickness 0.25)
		(keepout
			(tracks not_allowed)
			(vias allowed)
			(pads allowed)
			(copperpour not_allowed)
			(footprints allowed)
		)
		(placement
			(enabled no)
			(sheetname "")
		)
		(fill
			(thermal_gap 0.5)
			(thermal_bridge_width 0.5)
			(island_removal_mode 0)
		)
		(polygon
			(pts
				(arc
					(start 265.87831 -253.435104)
					(mid 265.21791 -253.435104)
					(end 265.87831 -253.435104)
				)
			)
		)
	)
	(zone
		(layer "In1.Cu")
		(hatch none 0.5)
		(connect_pads
			(clearance 0)
		)
		(min_thickness 0.25)
		(keepout
			(tracks not_allowed)
			(vias allowed)
			(pads allowed)
			(copperpour not_allowed)
			(footprints allowed)
		)
		(placement
			(enabled no)
			(sheetname "")
		)
		(fill
			(thermal_gap 0.5)
			(thermal_bridge_width 0.5)
			(island_removal_mode 0)
		)
		(polygon
			(pts
				(arc
					(start 266.29741 -293.632128)
					(mid 266.29369 -293.641108)
					(end 266.28471 -293.644828)
				)
				(arc
					(start 264.81151 -293.644828)
					(mid 264.80253 -293.641108)
					(end 264.79881 -293.632128)
				)
				(arc
					(start 264.79881 -293.13759)
					(mid 264.80253 -293.12861)
					(end 264.81151 -293.12489)
				)
				(arc
					(start 266.28471 -293.12489)
					(mid 266.29369 -293.12861)
					(end 266.29741 -293.13759)
				)
			)
		)
	)
	(zone
		(layer "In1.Cu")
		(hatch none 0.5)
		(connect_pads
			(clearance 0)
		)
		(min_thickness 0.25)
		(keepout
			(tracks not_allowed)
			(vias allowed)
			(pads allowed)
			(copperpour not_allowed)
			(footprints allowed)
		)
		(placement
			(enabled no)
			(sheetname "")
		)
		(fill
			(thermal_gap 0.5)
			(thermal_bridge_width 0.5)
			(island_removal_mode 0)
		)
		(polygon
			(pts
				(arc
					(start 273.841464 -224.782126)
					(mid 273.837744 -224.791106)
					(end 273.828764 -224.794826)
				)
				(arc
					(start 272.355564 -224.794826)
					(mid 272.346584 -224.791106)
					(end 272.342864 -224.782126)
				)
				(arc
					(start 272.342864 -224.287588)
					(mid 272.346584 -224.278608)
					(end 272.355564 -224.274888)
				)
				(arc
					(start 273.828764 -224.274888)
					(mid 273.837744 -224.278608)
					(end 273.841464 -224.287588)
				)
			)
		)
	)
	(zone
		(layer "In1.Cu")
		(hatch none 0.5)
		(connect_pads
			(clearance 0)
		)
		(min_thickness 0.25)
		(keepout
			(tracks not_allowed)
			(vias allowed)
			(pads allowed)
			(copperpour not_allowed)
			(footprints allowed)
		)
		(placement
			(enabled no)
			(sheetname "")
		)
		(fill
			(thermal_gap 0.5)
			(thermal_bridge_width 0.5)
			(island_removal_mode 0)
		)
		(polygon
			(pts
				(arc
					(start 418.21862 -399.701258)
					(mid 418.34562 -399.828258)
					(end 418.47262 -399.701258)
				)
				(arc
					(start 418.47262 -399.625058)
					(mid 418.34562 -399.498058)
					(end 418.21862 -399.625058)
				)
			)
		)
	)
	(zone
		(layer "In1.Cu")
		(hatch none 0.5)
		(connect_pads
			(clearance 0)
		)
		(min_thickness 0.25)
		(keepout
			(tracks not_allowed)
			(vias allowed)
			(pads allowed)
			(copperpour not_allowed)
			(footprints allowed)
		)
		(placement
			(enabled no)
			(sheetname "")
		)
		(fill
			(thermal_gap 0.5)
			(thermal_bridge_width 0.5)
			(island_removal_mode 0)
		)
		(polygon
			(pts
				(arc
					(start 191.909446 -240.932462)
					(mid 191.905726 -240.941442)
					(end 191.896746 -240.945162)
				)
				(arc
					(start 190.423546 -240.945162)
					(mid 190.414566 -240.941442)
					(end 190.410846 -240.932462)
				)
				(arc
					(start 190.410846 -240.437924)
					(mid 190.414566 -240.428944)
					(end 190.423546 -240.425224)
				)
				(arc
					(start 191.896746 -240.425224)
					(mid 191.905726 -240.428944)
					(end 191.909446 -240.437924)
				)
			)
		)
	)
	(zone
		(layer "In1.Cu")
		(hatch none 0.5)
		(connect_pads
			(clearance 0)
		)
		(min_thickness 0.25)
		(keepout
			(tracks not_allowed)
			(vias allowed)
			(pads allowed)
			(copperpour not_allowed)
			(footprints allowed)
		)
		(placement
			(enabled no)
			(sheetname "")
		)
		(fill
			(thermal_gap 0.5)
			(thermal_bridge_width 0.5)
			(island_removal_mode 0)
		)
		(polygon
			(pts
				(arc
					(start 443.2935 -228.18217)
					(mid 443.28978 -228.19115)
					(end 443.2808 -228.19487)
				)
				(arc
					(start 441.8076 -228.19487)
					(mid 441.79862 -228.19115)
					(end 441.7949 -228.18217)
				)
				(arc
					(start 441.7949 -227.687632)
					(mid 441.79862 -227.678652)
					(end 441.8076 -227.674932)
				)
				(arc
					(start 443.2808 -227.674932)
					(mid 443.28978 -227.678652)
					(end 443.2935 -227.687632)
				)
			)
		)
	)
	(zone
		(layer "In1.Cu")
		(hatch none 0.5)
		(connect_pads
			(clearance 0)
		)
		(min_thickness 0.25)
		(keepout
			(tracks not_allowed)
			(vias allowed)
			(pads allowed)
			(copperpour not_allowed)
			(footprints allowed)
		)
		(placement
			(enabled no)
			(sheetname "")
		)
		(fill
			(thermal_gap 0.5)
			(thermal_bridge_width 0.5)
			(island_removal_mode 0)
		)
		(polygon
			(pts
				(arc
					(start 176.821338 -201.832464)
					(mid 176.817618 -201.841444)
					(end 176.808638 -201.845164)
				)
				(arc
					(start 175.335438 -201.845164)
					(mid 175.326458 -201.841444)
					(end 175.322738 -201.832464)
				)
				(arc
					(start 175.322738 -201.337926)
					(mid 175.326458 -201.328946)
					(end 175.335438 -201.325226)
				)
				(arc
					(start 176.808638 -201.325226)
					(mid 176.817618 -201.328946)
					(end 176.821338 -201.337926)
				)
			)
		)
	)
	(zone
		(layer "In1.Cu")
		(hatch none 0.5)
		(connect_pads
			(clearance 0)
		)
		(min_thickness 0.25)
		(keepout
			(tracks not_allowed)
			(vias allowed)
			(pads allowed)
			(copperpour not_allowed)
			(footprints allowed)
		)
		(placement
			(enabled no)
			(sheetname "")
		)
		(fill
			(thermal_gap 0.5)
			(thermal_bridge_width 0.5)
			(island_removal_mode 0)
		)
		(polygon
			(pts
				(arc
					(start 45.089318 -200.98258)
					(mid 45.085598 -200.99156)
					(end 45.076618 -200.99528)
				)
				(arc
					(start 43.603418 -200.99528)
					(mid 43.594438 -200.99156)
					(end 43.590718 -200.98258)
				)
				(arc
					(start 43.590718 -200.488042)
					(mid 43.594438 -200.479062)
					(end 43.603418 -200.475342)
				)
				(arc
					(start 45.076618 -200.475342)
					(mid 45.085598 -200.479062)
					(end 45.089318 -200.488042)
				)
			)
		)
	)
	(zone
		(layer "In1.Cu")
		(hatch none 0.5)
		(connect_pads
			(clearance 0)
		)
		(min_thickness 0.25)
		(keepout
			(tracks not_allowed)
			(vias allowed)
			(pads allowed)
			(copperpour not_allowed)
			(footprints allowed)
		)
		(placement
			(enabled no)
			(sheetname "")
		)
		(fill
			(thermal_gap 0.5)
			(thermal_bridge_width 0.5)
			(island_removal_mode 0)
		)
		(polygon
			(pts
				(arc
					(start 308.117494 -203.532232)
					(mid 308.113774 -203.541212)
					(end 308.104794 -203.544932)
				)
				(arc
					(start 306.631594 -203.544932)
					(mid 306.622614 -203.541212)
					(end 306.618894 -203.532232)
				)
				(arc
					(start 306.618894 -203.037694)
					(mid 306.622614 -203.028714)
					(end 306.631594 -203.024994)
				)
				(arc
					(start 308.104794 -203.024994)
					(mid 308.113774 -203.028714)
					(end 308.117494 -203.037694)
				)
			)
		)
	)
	(zone
		(layer "In1.Cu")
		(hatch none 0.5)
		(connect_pads
			(clearance 0)
		)
		(min_thickness 0.25)
		(keepout
			(tracks not_allowed)
			(vias allowed)
			(pads allowed)
			(copperpour not_allowed)
			(footprints allowed)
		)
		(placement
			(enabled no)
			(sheetname "")
		)
		(fill
			(thermal_gap 0.5)
			(thermal_bridge_width 0.5)
			(island_removal_mode 0)
		)
		(polygon
			(pts
				(arc
					(start 45.089318 -295.332404)
					(mid 45.085598 -295.341384)
					(end 45.076618 -295.345104)
				)
				(arc
					(start 43.603418 -295.345104)
					(mid 43.594438 -295.341384)
					(end 43.590718 -295.332404)
				)
				(arc
					(start 43.590718 -294.837866)
					(mid 43.594438 -294.828886)
					(end 43.603418 -294.825166)
				)
				(arc
					(start 45.076618 -294.825166)
					(mid 45.085598 -294.828886)
					(end 45.089318 -294.837866)
				)
			)
		)
	)
	(zone
		(layer "In1.Cu")
		(hatch none 0.5)
		(connect_pads
			(clearance 0)
		)
		(min_thickness 0.25)
		(keepout
			(tracks not_allowed)
			(vias allowed)
			(pads allowed)
			(copperpour not_allowed)
			(footprints allowed)
		)
		(placement
			(enabled no)
			(sheetname "")
		)
		(fill
			(thermal_gap 0.5)
			(thermal_bridge_width 0.5)
			(island_removal_mode 0)
		)
		(polygon
			(pts
				(arc
					(start 40.98925 -206.082392)
					(mid 40.98553 -206.091372)
					(end 40.97655 -206.095092)
				)
				(arc
					(start 39.50335 -206.095092)
					(mid 39.49437 -206.091372)
					(end 39.49065 -206.082392)
				)
				(arc
					(start 39.49065 -205.587854)
					(mid 39.49437 -205.578874)
					(end 39.50335 -205.575154)
				)
				(arc
					(start 40.97655 -205.575154)
					(mid 40.98553 -205.578874)
					(end 40.98925 -205.587854)
				)
			)
		)
	)
	(zone
		(layer "In1.Cu")
		(hatch none 0.5)
		(connect_pads
			(clearance 0)
		)
		(min_thickness 0.25)
		(keepout
			(tracks not_allowed)
			(vias allowed)
			(pads allowed)
			(copperpour not_allowed)
			(footprints allowed)
		)
		(placement
			(enabled no)
			(sheetname "")
		)
		(fill
			(thermal_gap 0.5)
			(thermal_bridge_width 0.5)
			(island_removal_mode 0)
		)
		(polygon
			(pts
				(arc
					(start 48.533304 -228.182424)
					(mid 48.529584 -228.191404)
					(end 48.520604 -228.195124)
				)
				(arc
					(start 47.047404 -228.195124)
					(mid 47.038424 -228.191404)
					(end 47.034704 -228.182424)
				)
				(arc
					(start 47.034704 -227.687886)
					(mid 47.038424 -227.678906)
					(end 47.047404 -227.675186)
				)
				(arc
					(start 48.520604 -227.675186)
					(mid 48.529584 -227.678906)
					(end 48.533304 -227.687886)
				)
			)
		)
	)
	(zone
		(layer "In1.Cu")
		(hatch none 0.5)
		(connect_pads
			(clearance 0)
		)
		(min_thickness 0.25)
		(keepout
			(tracks not_allowed)
			(vias allowed)
			(pads allowed)
			(copperpour not_allowed)
			(footprints allowed)
		)
		(placement
			(enabled no)
			(sheetname "")
		)
		(fill
			(thermal_gap 0.5)
			(thermal_bridge_width 0.5)
			(island_removal_mode 0)
		)
		(polygon
			(pts
				(arc
					(start 435.749446 -310.632094)
					(mid 435.745726 -310.641074)
					(end 435.736746 -310.644794)
				)
				(arc
					(start 434.263546 -310.644794)
					(mid 434.254566 -310.641074)
					(end 434.250846 -310.632094)
				)
				(arc
					(start 434.250846 -310.137556)
					(mid 434.254566 -310.128576)
					(end 434.263546 -310.124856)
				)
				(arc
					(start 435.736746 -310.124856)
					(mid 435.745726 -310.128576)
					(end 435.749446 -310.137556)
				)
			)
		)
	)
	(zone
		(layer "In1.Cu")
		(hatch none 0.5)
		(connect_pads
			(clearance 0)
		)
		(min_thickness 0.25)
		(keepout
			(tracks not_allowed)
			(vias allowed)
			(pads allowed)
			(copperpour not_allowed)
			(footprints allowed)
		)
		(placement
			(enabled no)
			(sheetname "")
		)
		(fill
			(thermal_gap 0.5)
			(thermal_bridge_width 0.5)
			(island_removal_mode 0)
		)
		(polygon
			(pts
				(arc
					(start 296.473372 -201.83221)
					(mid 296.469652 -201.84119)
					(end 296.460672 -201.84491)
				)
				(arc
					(start 294.987472 -201.84491)
					(mid 294.978492 -201.84119)
					(end 294.974772 -201.83221)
				)
				(arc
					(start 294.974772 -201.337672)
					(mid 294.978492 -201.328692)
					(end 294.987472 -201.324972)
				)
				(arc
					(start 296.460672 -201.324972)
					(mid 296.469652 -201.328692)
					(end 296.473372 -201.337672)
				)
			)
		)
	)
	(zone
		(layer "In1.Cu")
		(hatch none 0.5)
		(connect_pads
			(clearance 0)
		)
		(min_thickness 0.25)
		(keepout
			(tracks not_allowed)
			(vias allowed)
			(pads allowed)
			(copperpour not_allowed)
			(footprints allowed)
		)
		(placement
			(enabled no)
			(sheetname "")
		)
		(fill
			(thermal_gap 0.5)
			(thermal_bridge_width 0.5)
			(island_removal_mode 0)
		)
		(polygon
			(pts
				(arc
					(start 354.097844 -399.143474)
					(mid 353.793044 -399.143474)
					(end 354.097844 -399.143474)
				)
			)
		)
	)
	(zone
		(layer "In1.Cu")
		(hatch none 0.5)
		(connect_pads
			(clearance 0)
		)
		(min_thickness 0.25)
		(keepout
			(tracks not_allowed)
			(vias allowed)
			(pads allowed)
			(copperpour not_allowed)
			(footprints allowed)
		)
		(placement
			(enabled no)
			(sheetname "")
		)
		(fill
			(thermal_gap 0.5)
			(thermal_bridge_width 0.5)
			(island_removal_mode 0)
		)
		(polygon
			(pts
				(arc
					(start 202.897232 -220.532452)
					(mid 202.893512 -220.541432)
					(end 202.884532 -220.545152)
				)
				(arc
					(start 201.411332 -220.545152)
					(mid 201.402352 -220.541432)
					(end 201.398632 -220.532452)
				)
				(arc
					(start 201.398632 -220.037914)
					(mid 201.402352 -220.028934)
					(end 201.411332 -220.025214)
				)
				(arc
					(start 202.884532 -220.025214)
					(mid 202.893512 -220.028934)
					(end 202.897232 -220.037914)
				)
			)
		)
	)
	(zone
		(layer "In1.Cu")
		(hatch none 0.5)
		(connect_pads
			(clearance 0)
		)
		(min_thickness 0.25)
		(keepout
			(tracks not_allowed)
			(vias allowed)
			(pads allowed)
			(copperpour not_allowed)
			(footprints allowed)
		)
		(placement
			(enabled no)
			(sheetname "")
		)
		(fill
			(thermal_gap 0.5)
			(thermal_bridge_width 0.5)
			(island_removal_mode 0)
		)
		(polygon
			(pts
				(arc
					(start 169.277284 -201.832464)
					(mid 169.273564 -201.841444)
					(end 169.264584 -201.845164)
				)
				(arc
					(start 167.791384 -201.845164)
					(mid 167.782404 -201.841444)
					(end 167.778684 -201.832464)
				)
				(arc
					(start 167.778684 -201.337926)
					(mid 167.782404 -201.328946)
					(end 167.791384 -201.325226)
				)
				(arc
					(start 169.264584 -201.325226)
					(mid 169.273564 -201.328946)
					(end 169.277284 -201.337926)
				)
			)
		)
	)
	(zone
		(layer "In1.Cu")
		(hatch none 0.5)
		(connect_pads
			(clearance 0)
		)
		(min_thickness 0.25)
		(keepout
			(tracks not_allowed)
			(vias allowed)
			(pads allowed)
			(copperpour not_allowed)
			(footprints allowed)
		)
		(placement
			(enabled no)
			(sheetname "")
		)
		(fill
			(thermal_gap 0.5)
			(thermal_bridge_width 0.5)
			(island_removal_mode 0)
		)
		(polygon
			(pts
				(arc
					(start 45.089318 -291.082476)
					(mid 45.085598 -291.091456)
					(end 45.076618 -291.095176)
				)
				(arc
					(start 43.603418 -291.095176)
					(mid 43.594438 -291.091456)
					(end 43.590718 -291.082476)
				)
				(arc
					(start 43.590718 -290.587938)
					(mid 43.594438 -290.578958)
					(end 43.603418 -290.575238)
				)
				(arc
					(start 45.076618 -290.575238)
					(mid 45.085598 -290.578958)
					(end 45.089318 -290.587938)
				)
			)
		)
	)
	(zone
		(layer "In1.Cu")
		(hatch none 0.5)
		(connect_pads
			(clearance 0)
		)
		(min_thickness 0.25)
		(keepout
			(tracks not_allowed)
			(vias allowed)
			(pads allowed)
			(copperpour not_allowed)
			(footprints allowed)
		)
		(placement
			(enabled no)
			(sheetname "")
		)
		(fill
			(thermal_gap 0.5)
			(thermal_bridge_width 0.5)
			(island_removal_mode 0)
		)
		(polygon
			(pts
				(arc
					(start 266.29741 -316.582298)
					(mid 266.29369 -316.591278)
					(end 266.28471 -316.594998)
				)
				(arc
					(start 264.81151 -316.594998)
					(mid 264.80253 -316.591278)
					(end 264.79881 -316.582298)
				)
				(arc
					(start 264.79881 -316.08776)
					(mid 264.80253 -316.07878)
					(end 264.81151 -316.07506)
				)
				(arc
					(start 266.28471 -316.07506)
					(mid 266.29369 -316.07878)
					(end 266.29741 -316.08776)
				)
			)
		)
	)
	(zone
		(layer "In1.Cu")
		(hatch none 0.5)
		(connect_pads
			(clearance 0)
		)
		(min_thickness 0.25)
		(keepout
			(tracks not_allowed)
			(vias allowed)
			(pads allowed)
			(copperpour not_allowed)
			(footprints allowed)
		)
		(placement
			(enabled no)
			(sheetname "")
		)
		(fill
			(thermal_gap 0.5)
			(thermal_bridge_width 0.5)
			(island_removal_mode 0)
		)
		(polygon
			(pts
				(arc
					(start 83.69808 -383.92227)
					(mid 83.39328 -383.92227)
					(end 83.69808 -383.92227)
				)
			)
		)
	)
	(zone
		(layer "In1.Cu")
		(hatch none 0.5)
		(connect_pads
			(clearance 0)
		)
		(min_thickness 0.25)
		(keepout
			(tracks not_allowed)
			(vias allowed)
			(pads allowed)
			(copperpour not_allowed)
			(footprints allowed)
		)
		(placement
			(enabled no)
			(sheetname "")
		)
		(fill
			(thermal_gap 0.5)
			(thermal_bridge_width 0.5)
			(island_removal_mode 0)
		)
		(polygon
			(pts
				(arc
					(start 40.98925 -285.98241)
					(mid 40.98553 -285.99139)
					(end 40.97655 -285.99511)
				)
				(arc
					(start 39.50335 -285.99511)
					(mid 39.49437 -285.99139)
					(end 39.49065 -285.98241)
				)
				(arc
					(start 39.49065 -285.487872)
					(mid 39.49437 -285.478892)
					(end 39.50335 -285.475172)
				)
				(arc
					(start 40.97655 -285.475172)
					(mid 40.98553 -285.478892)
					(end 40.98925 -285.487872)
				)
			)
		)
	)
	(zone
		(layer "In1.Cu")
		(hatch none 0.5)
		(connect_pads
			(clearance 0)
		)
		(min_thickness 0.25)
		(keepout
			(tracks not_allowed)
			(vias allowed)
			(pads allowed)
			(copperpour not_allowed)
			(footprints allowed)
		)
		(placement
			(enabled no)
			(sheetname "")
		)
		(fill
			(thermal_gap 0.5)
			(thermal_bridge_width 0.5)
			(island_removal_mode 0)
		)
		(polygon
			(pts
				(arc
					(start 48.533304 -221.382336)
					(mid 48.529584 -221.391316)
					(end 48.520604 -221.395036)
				)
				(arc
					(start 47.047404 -221.395036)
					(mid 47.038424 -221.391316)
					(end 47.034704 -221.382336)
				)
				(arc
					(start 47.034704 -220.887798)
					(mid 47.038424 -220.878818)
					(end 47.047404 -220.875098)
				)
				(arc
					(start 48.520604 -220.875098)
					(mid 48.529584 -220.878818)
					(end 48.533304 -220.887798)
				)
			)
		)
	)
	(zone
		(layer "In1.Cu")
		(hatch none 0.5)
		(connect_pads
			(clearance 0)
		)
		(min_thickness 0.25)
		(keepout
			(tracks not_allowed)
			(vias allowed)
			(pads allowed)
			(copperpour not_allowed)
			(footprints allowed)
		)
		(placement
			(enabled no)
			(sheetname "")
		)
		(fill
			(thermal_gap 0.5)
			(thermal_bridge_width 0.5)
			(island_removal_mode 0)
		)
		(polygon
			(pts
				(arc
					(start 265.87831 -254.284988)
					(mid 265.21791 -254.284988)
					(end 265.87831 -254.284988)
				)
			)
		)
	)
	(zone
		(layer "In1.Cu")
		(hatch none 0.5)
		(connect_pads
			(clearance 0)
		)
		(min_thickness 0.25)
		(keepout
			(tracks not_allowed)
			(vias allowed)
			(pads allowed)
			(copperpour not_allowed)
			(footprints allowed)
		)
		(placement
			(enabled no)
			(sheetname "")
		)
		(fill
			(thermal_gap 0.5)
			(thermal_bridge_width 0.5)
			(island_removal_mode 0)
		)
		(polygon
			(pts
				(arc
					(start 270.397478 -303.83226)
					(mid 270.393758 -303.84124)
					(end 270.384778 -303.84496)
				)
				(arc
					(start 268.911578 -303.84496)
					(mid 268.902598 -303.84124)
					(end 268.898878 -303.83226)
				)
				(arc
					(start 268.898878 -303.337722)
					(mid 268.902598 -303.328742)
					(end 268.911578 -303.325022)
				)
				(arc
					(start 270.384778 -303.325022)
					(mid 270.393758 -303.328742)
					(end 270.397478 -303.337722)
				)
			)
		)
	)
	(zone
		(layer "In1.Cu")
		(hatch none 0.5)
		(connect_pads
			(clearance 0)
		)
		(min_thickness 0.25)
		(keepout
			(tracks not_allowed)
			(vias allowed)
			(pads allowed)
			(copperpour not_allowed)
			(footprints allowed)
		)
		(placement
			(enabled no)
			(sheetname "")
		)
		(fill
			(thermal_gap 0.5)
			(thermal_bridge_width 0.5)
			(island_removal_mode 0)
		)
		(polygon
			(pts
				(arc
					(start 270.397478 -214.582248)
					(mid 270.393758 -214.591228)
					(end 270.384778 -214.594948)
				)
				(arc
					(start 268.911578 -214.594948)
					(mid 268.902598 -214.591228)
					(end 268.898878 -214.582248)
				)
				(arc
					(start 268.898878 -214.08771)
					(mid 268.902598 -214.07873)
					(end 268.911578 -214.07501)
				)
				(arc
					(start 270.384778 -214.07501)
					(mid 270.393758 -214.07873)
					(end 270.397478 -214.08771)
				)
			)
		)
	)
	(zone
		(layer "In1.Cu")
		(hatch none 0.5)
		(connect_pads
			(clearance 0)
		)
		(min_thickness 0.25)
		(keepout
			(tracks not_allowed)
			(vias allowed)
			(pads allowed)
			(copperpour not_allowed)
			(footprints allowed)
		)
		(placement
			(enabled no)
			(sheetname "")
		)
		(fill
			(thermal_gap 0.5)
			(thermal_bridge_width 0.5)
			(island_removal_mode 0)
		)
		(polygon
			(pts
				(arc
					(start 270.397478 -283.43225)
					(mid 270.393758 -283.44123)
					(end 270.384778 -283.44495)
				)
				(arc
					(start 268.911578 -283.44495)
					(mid 268.902598 -283.44123)
					(end 268.898878 -283.43225)
				)
				(arc
					(start 268.898878 -282.937712)
					(mid 268.902598 -282.928732)
					(end 268.911578 -282.925012)
				)
				(arc
					(start 270.384778 -282.925012)
					(mid 270.393758 -282.928732)
					(end 270.397478 -282.937712)
				)
			)
		)
	)
	(zone
		(layer "In1.Cu")
		(hatch none 0.5)
		(connect_pads
			(clearance 0)
		)
		(min_thickness 0.25)
		(keepout
			(tracks not_allowed)
			(vias allowed)
			(pads allowed)
			(copperpour not_allowed)
			(footprints allowed)
		)
		(placement
			(enabled no)
			(sheetname "")
		)
		(fill
			(thermal_gap 0.5)
			(thermal_bridge_width 0.5)
			(island_removal_mode 0)
		)
		(polygon
			(pts
				(arc
					(start 57.791096 -383.440686)
					(mid 57.918096 -383.567686)
					(end 58.045096 -383.440686)
				)
				(arc
					(start 58.045096 -383.364486)
					(mid 57.918096 -383.237486)
					(end 57.791096 -383.364486)
				)
			)
		)
	)
	(zone
		(layer "In1.Cu")
		(hatch none 0.5)
		(connect_pads
			(clearance 0)
		)
		(min_thickness 0.25)
		(keepout
			(tracks not_allowed)
			(vias allowed)
			(pads allowed)
			(copperpour not_allowed)
			(footprints allowed)
		)
		(placement
			(enabled no)
			(sheetname "")
		)
		(fill
			(thermal_gap 0.5)
			(thermal_bridge_width 0.5)
			(island_removal_mode 0)
		)
		(polygon
			(pts
				(arc
					(start 18.357342 -209.482436)
					(mid 18.353622 -209.491416)
					(end 18.344642 -209.495136)
				)
				(arc
					(start 16.871442 -209.495136)
					(mid 16.862462 -209.491416)
					(end 16.858742 -209.482436)
				)
				(arc
					(start 16.858742 -208.987898)
					(mid 16.862462 -208.978918)
					(end 16.871442 -208.975198)
				)
				(arc
					(start 18.344642 -208.975198)
					(mid 18.353622 -208.978918)
					(end 18.357342 -208.987898)
				)
			)
		)
	)
	(zone
		(layer "In1.Cu")
		(hatch none 0.5)
		(connect_pads
			(clearance 0)
		)
		(min_thickness 0.25)
		(keepout
			(tracks not_allowed)
			(vias allowed)
			(pads allowed)
			(copperpour not_allowed)
			(footprints allowed)
		)
		(placement
			(enabled no)
			(sheetname "")
		)
		(fill
			(thermal_gap 0.5)
			(thermal_bridge_width 0.5)
			(island_removal_mode 0)
		)
		(polygon
			(pts
				(arc
					(start 450.8373 -241.782092)
					(mid 450.83358 -241.791072)
					(end 450.8246 -241.794792)
				)
				(arc
					(start 449.3514 -241.794792)
					(mid 449.34242 -241.791072)
					(end 449.3387 -241.782092)
				)
				(arc
					(start 449.3387 -241.287554)
					(mid 449.34242 -241.278574)
					(end 449.3514 -241.274854)
				)
				(arc
					(start 450.8246 -241.274854)
					(mid 450.83358 -241.278574)
					(end 450.8373 -241.287554)
				)
			)
		)
	)
	(zone
		(layer "In1.Cu")
		(hatch none 0.5)
		(connect_pads
			(clearance 0)
		)
		(min_thickness 0.25)
		(keepout
			(tracks not_allowed)
			(vias allowed)
			(pads allowed)
			(copperpour not_allowed)
			(footprints allowed)
		)
		(placement
			(enabled no)
			(sheetname "")
		)
		(fill
			(thermal_gap 0.5)
			(thermal_bridge_width 0.5)
			(island_removal_mode 0)
		)
		(polygon
			(pts
				(arc
					(start 199.4535 -280.03246)
					(mid 199.44978 -280.04144)
					(end 199.4408 -280.04516)
				)
				(arc
					(start 197.9676 -280.04516)
					(mid 197.95862 -280.04144)
					(end 197.9549 -280.03246)
				)
				(arc
					(start 197.9549 -279.537922)
					(mid 197.95862 -279.528942)
					(end 197.9676 -279.525222)
				)
				(arc
					(start 199.4408 -279.525222)
					(mid 199.44978 -279.528942)
					(end 199.4535 -279.537922)
				)
			)
		)
	)
	(zone
		(layer "In1.Cu")
		(hatch none 0.5)
		(connect_pads
			(clearance 0)
		)
		(min_thickness 0.25)
		(keepout
			(tracks not_allowed)
			(vias allowed)
			(pads allowed)
			(copperpour not_allowed)
			(footprints allowed)
		)
		(placement
			(enabled no)
			(sheetname "")
		)
		(fill
			(thermal_gap 0.5)
			(thermal_bridge_width 0.5)
			(island_removal_mode 0)
		)
		(polygon
			(pts
				(arc
					(start 150.798022 -383.92227)
					(mid 150.493222 -383.92227)
					(end 150.798022 -383.92227)
				)
			)
		)
	)
	(zone
		(layer "In1.Cu")
		(hatch none 0.5)
		(connect_pads
			(clearance 0)
		)
		(min_thickness 0.25)
		(keepout
			(tracks not_allowed)
			(vias allowed)
			(pads allowed)
			(copperpour not_allowed)
			(footprints allowed)
		)
		(placement
			(enabled no)
			(sheetname "")
		)
		(fill
			(thermal_gap 0.5)
			(thermal_bridge_width 0.5)
			(island_removal_mode 0)
		)
		(polygon
			(pts
				(arc
					(start 351.988628 -394.385292)
					(mid 351.607628 -394.385292)
					(end 351.988628 -394.385292)
				)
			)
		)
	)
	(zone
		(layer "In1.Cu")
		(hatch none 0.5)
		(connect_pads
			(clearance 0)
		)
		(min_thickness 0.25)
		(keepout
			(tracks not_allowed)
			(vias allowed)
			(pads allowed)
			(copperpour not_allowed)
			(footprints allowed)
		)
		(placement
			(enabled no)
			(sheetname "")
		)
		(fill
			(thermal_gap 0.5)
			(thermal_bridge_width 0.5)
			(island_removal_mode 0)
		)
		(polygon
			(pts
				(arc
					(start 199.4535 -285.132526)
					(mid 199.44978 -285.141506)
					(end 199.4408 -285.145226)
				)
				(arc
					(start 197.9676 -285.145226)
					(mid 197.95862 -285.141506)
					(end 197.9549 -285.132526)
				)
				(arc
					(start 197.9549 -284.637988)
					(mid 197.95862 -284.629008)
					(end 197.9676 -284.625288)
				)
				(arc
					(start 199.4408 -284.625288)
					(mid 199.44978 -284.629008)
					(end 199.4535 -284.637988)
				)
			)
		)
	)
	(zone
		(layer "In1.Cu")
		(hatch none 0.5)
		(connect_pads
			(clearance 0)
		)
		(min_thickness 0.25)
		(keepout
			(tracks not_allowed)
			(vias allowed)
			(pads allowed)
			(copperpour not_allowed)
			(footprints allowed)
		)
		(placement
			(enabled no)
			(sheetname "")
		)
		(fill
			(thermal_gap 0.5)
			(thermal_bridge_width 0.5)
			(island_removal_mode 0)
		)
		(polygon
			(pts
				(arc
					(start 86.388956 -389.467344)
					(mid 86.007956 -389.467344)
					(end 86.388956 -389.467344)
				)
			)
		)
	)
	(zone
		(layer "In1.Cu")
		(hatch none 0.5)
		(connect_pads
			(clearance 0)
		)
		(min_thickness 0.25)
		(keepout
			(tracks not_allowed)
			(vias allowed)
			(pads allowed)
			(copperpour not_allowed)
			(footprints allowed)
		)
		(placement
			(enabled no)
			(sheetname "")
		)
		(fill
			(thermal_gap 0.5)
			(thermal_bridge_width 0.5)
			(island_removal_mode 0)
		)
		(polygon
			(pts
				(arc
					(start 129.070354 -390.761474)
					(mid 128.765554 -390.761474)
					(end 129.070354 -390.761474)
				)
			)
		)
	)
	(zone
		(layer "In1.Cu")
		(hatch none 0.5)
		(connect_pads
			(clearance 0)
		)
		(min_thickness 0.25)
		(keepout
			(tracks not_allowed)
			(vias allowed)
			(pads allowed)
			(copperpour not_allowed)
			(footprints allowed)
		)
		(placement
			(enabled no)
			(sheetname "")
		)
		(fill
			(thermal_gap 0.5)
			(thermal_bridge_width 0.5)
			(island_removal_mode 0)
		)
		(polygon
			(pts
				(arc
					(start 424.761406 -280.032206)
					(mid 424.757686 -280.041186)
					(end 424.748706 -280.044906)
				)
				(arc
					(start 423.275506 -280.044906)
					(mid 423.266526 -280.041186)
					(end 423.262806 -280.032206)
				)
				(arc
					(start 423.262806 -279.537668)
					(mid 423.266526 -279.528688)
					(end 423.275506 -279.524968)
				)
				(arc
					(start 424.748706 -279.524968)
					(mid 424.757686 -279.528688)
					(end 424.761406 -279.537668)
				)
			)
		)
	)
	(zone
		(layer "In1.Cu")
		(hatch none 0.5)
		(connect_pads
			(clearance 0)
		)
		(min_thickness 0.25)
		(keepout
			(tracks not_allowed)
			(vias allowed)
			(pads allowed)
			(copperpour not_allowed)
			(footprints allowed)
		)
		(placement
			(enabled no)
			(sheetname "")
		)
		(fill
			(thermal_gap 0.5)
			(thermal_bridge_width 0.5)
			(island_removal_mode 0)
		)
		(polygon
			(pts
				(arc
					(start 265.87831 -237.285022)
					(mid 265.21791 -237.285022)
					(end 265.87831 -237.285022)
				)
			)
		)
	)
	(zone
		(layer "In1.Cu")
		(hatch none 0.5)
		(connect_pads
			(clearance 0)
		)
		(min_thickness 0.25)
		(keepout
			(tracks not_allowed)
			(vias allowed)
			(pads allowed)
			(copperpour not_allowed)
			(footprints allowed)
		)
		(placement
			(enabled no)
			(sheetname "")
		)
		(fill
			(thermal_gap 0.5)
			(thermal_bridge_width 0.5)
			(island_removal_mode 0)
		)
		(polygon
			(pts
				(arc
					(start 176.821338 -234.982512)
					(mid 176.817618 -234.991492)
					(end 176.808638 -234.995212)
				)
				(arc
					(start 175.335438 -234.995212)
					(mid 175.326458 -234.991492)
					(end 175.322738 -234.982512)
				)
				(arc
					(start 175.322738 -234.487974)
					(mid 175.326458 -234.478994)
					(end 175.335438 -234.475274)
				)
				(arc
					(start 176.808638 -234.475274)
					(mid 176.817618 -234.478994)
					(end 176.821338 -234.487974)
				)
			)
		)
	)
	(zone
		(layer "In1.Cu")
		(hatch none 0.5)
		(connect_pads
			(clearance 0)
		)
		(min_thickness 0.25)
		(keepout
			(tracks not_allowed)
			(vias allowed)
			(pads allowed)
			(copperpour not_allowed)
			(footprints allowed)
		)
		(placement
			(enabled no)
			(sheetname "")
		)
		(fill
			(thermal_gap 0.5)
			(thermal_bridge_width 0.5)
			(island_removal_mode 0)
		)
		(polygon
			(pts
				(arc
					(start 60.177426 -270.682466)
					(mid 60.173706 -270.691446)
					(end 60.164726 -270.695166)
				)
				(arc
					(start 58.691526 -270.695166)
					(mid 58.682546 -270.691446)
					(end 58.678826 -270.682466)
				)
				(arc
					(start 58.678826 -270.187928)
					(mid 58.682546 -270.178948)
					(end 58.691526 -270.175228)
				)
				(arc
					(start 60.164726 -270.175228)
					(mid 60.173706 -270.178948)
					(end 60.177426 -270.187928)
				)
			)
		)
	)
	(zone
		(layer "In1.Cu")
		(hatch none 0.5)
		(connect_pads
			(clearance 0)
		)
		(min_thickness 0.25)
		(keepout
			(tracks not_allowed)
			(vias allowed)
			(pads allowed)
			(copperpour not_allowed)
			(footprints allowed)
		)
		(placement
			(enabled no)
			(sheetname "")
		)
		(fill
			(thermal_gap 0.5)
			(thermal_bridge_width 0.5)
			(island_removal_mode 0)
		)
		(polygon
			(pts
				(arc
					(start 172.72127 -234.132374)
					(mid 172.71755 -234.141354)
					(end 172.70857 -234.145074)
				)
				(arc
					(start 171.23537 -234.145074)
					(mid 171.22639 -234.141354)
					(end 171.22267 -234.132374)
				)
				(arc
					(start 171.22267 -233.637836)
					(mid 171.22639 -233.628856)
					(end 171.23537 -233.625136)
				)
				(arc
					(start 172.70857 -233.625136)
					(mid 172.71755 -233.628856)
					(end 172.72127 -233.637836)
				)
			)
		)
	)
	(zone
		(layer "In1.Cu")
		(hatch none 0.5)
		(connect_pads
			(clearance 0)
		)
		(min_thickness 0.25)
		(keepout
			(tracks not_allowed)
			(vias allowed)
			(pads allowed)
			(copperpour not_allowed)
			(footprints allowed)
		)
		(placement
			(enabled no)
			(sheetname "")
		)
		(fill
			(thermal_gap 0.5)
			(thermal_bridge_width 0.5)
			(island_removal_mode 0)
		)
		(polygon
			(pts
				(arc
					(start 420.661338 -282.582112)
					(mid 420.657618 -282.591092)
					(end 420.648638 -282.594812)
				)
				(arc
					(start 419.175438 -282.594812)
					(mid 419.166458 -282.591092)
					(end 419.162738 -282.582112)
				)
				(arc
					(start 419.162738 -282.087574)
					(mid 419.166458 -282.078594)
					(end 419.175438 -282.074874)
				)
				(arc
					(start 420.648638 -282.074874)
					(mid 420.657618 -282.078594)
					(end 420.661338 -282.087574)
				)
			)
		)
	)
	(zone
		(layer "In1.Cu")
		(hatch none 0.5)
		(connect_pads
			(clearance 0)
		)
		(min_thickness 0.25)
		(keepout
			(tracks not_allowed)
			(vias allowed)
			(pads allowed)
			(copperpour not_allowed)
			(footprints allowed)
		)
		(placement
			(enabled no)
			(sheetname "")
		)
		(fill
			(thermal_gap 0.5)
			(thermal_bridge_width 0.5)
			(island_removal_mode 0)
		)
		(polygon
			(pts
				(arc
					(start 420.661338 -312.332116)
					(mid 420.657618 -312.341096)
					(end 420.648638 -312.344816)
				)
				(arc
					(start 419.175438 -312.344816)
					(mid 419.166458 -312.341096)
					(end 419.162738 -312.332116)
				)
				(arc
					(start 419.162738 -311.837578)
					(mid 419.166458 -311.828598)
					(end 419.175438 -311.824878)
				)
				(arc
					(start 420.648638 -311.824878)
					(mid 420.657618 -311.828598)
					(end 420.661338 -311.837578)
				)
			)
		)
	)
	(zone
		(layer "In1.Cu")
		(hatch none 0.5)
		(connect_pads
			(clearance 0)
		)
		(min_thickness 0.25)
		(keepout
			(tracks not_allowed)
			(vias allowed)
			(pads allowed)
			(copperpour not_allowed)
			(footprints allowed)
		)
		(placement
			(enabled no)
			(sheetname "")
		)
		(fill
			(thermal_gap 0.5)
			(thermal_bridge_width 0.5)
			(island_removal_mode 0)
		)
		(polygon
			(pts
				(arc
					(start 169.277284 -303.832514)
					(mid 169.273564 -303.841494)
					(end 169.264584 -303.845214)
				)
				(arc
					(start 167.791384 -303.845214)
					(mid 167.782404 -303.841494)
					(end 167.778684 -303.832514)
				)
				(arc
					(start 167.778684 -303.337976)
					(mid 167.782404 -303.328996)
					(end 167.791384 -303.325276)
				)
				(arc
					(start 169.264584 -303.325276)
					(mid 169.273564 -303.328996)
					(end 169.277284 -303.337976)
				)
			)
		)
	)
	(zone
		(layer "In1.Cu")
		(hatch none 0.5)
		(connect_pads
			(clearance 0)
		)
		(min_thickness 0.25)
		(keepout
			(tracks not_allowed)
			(vias allowed)
			(pads allowed)
			(copperpour not_allowed)
			(footprints allowed)
		)
		(placement
			(enabled no)
			(sheetname "")
		)
		(fill
			(thermal_gap 0.5)
			(thermal_bridge_width 0.5)
			(island_removal_mode 0)
		)
		(polygon
			(pts
				(arc
					(start 53.461412 -385.31038)
					(mid 53.080412 -385.31038)
					(end 53.461412 -385.31038)
				)
			)
		)
	)
	(zone
		(layer "In1.Cu")
		(hatch none 0.5)
		(connect_pads
			(clearance 0)
		)
		(min_thickness 0.25)
		(keepout
			(tracks not_allowed)
			(vias allowed)
			(pads allowed)
			(copperpour not_allowed)
			(footprints allowed)
		)
		(placement
			(enabled no)
			(sheetname "")
		)
		(fill
			(thermal_gap 0.5)
			(thermal_bridge_width 0.5)
			(island_removal_mode 0)
		)
		(polygon
			(pts
				(arc
					(start 206.9973 -295.332404)
					(mid 206.99358 -295.341384)
					(end 206.9846 -295.345104)
				)
				(arc
					(start 205.5114 -295.345104)
					(mid 205.50242 -295.341384)
					(end 205.4987 -295.332404)
				)
				(arc
					(start 205.4987 -294.837866)
					(mid 205.50242 -294.828886)
					(end 205.5114 -294.825166)
				)
				(arc
					(start 206.9846 -294.825166)
					(mid 206.99358 -294.828886)
					(end 206.9973 -294.837866)
				)
			)
		)
	)
	(zone
		(layer "In1.Cu")
		(hatch none 0.5)
		(connect_pads
			(clearance 0)
		)
		(min_thickness 0.25)
		(keepout
			(tracks not_allowed)
			(vias allowed)
			(pads allowed)
			(copperpour not_allowed)
			(footprints allowed)
		)
		(placement
			(enabled no)
			(sheetname "")
		)
		(fill
			(thermal_gap 0.5)
			(thermal_bridge_width 0.5)
			(island_removal_mode 0)
		)
		(polygon
			(pts
				(arc
					(start 309.57012 -392.30427)
					(mid 309.26532 -392.30427)
					(end 309.57012 -392.30427)
				)
			)
		)
	)
	(zone
		(layer "In1.Cu")
		(hatch none 0.5)
		(connect_pads
			(clearance 0)
		)
		(min_thickness 0.25)
		(keepout
			(tracks not_allowed)
			(vias allowed)
			(pads allowed)
			(copperpour not_allowed)
			(footprints allowed)
		)
		(placement
			(enabled no)
			(sheetname "")
		)
		(fill
			(thermal_gap 0.5)
			(thermal_bridge_width 0.5)
			(island_removal_mode 0)
		)
		(polygon
			(pts
				(arc
					(start 435.749446 -228.18217)
					(mid 435.745726 -228.19115)
					(end 435.736746 -228.19487)
				)
				(arc
					(start 434.263546 -228.19487)
					(mid 434.254566 -228.19115)
					(end 434.250846 -228.18217)
				)
				(arc
					(start 434.250846 -227.687632)
					(mid 434.254566 -227.678652)
					(end 434.263546 -227.674932)
				)
				(arc
					(start 435.736746 -227.674932)
					(mid 435.745726 -227.678652)
					(end 435.749446 -227.687632)
				)
			)
		)
	)
	(zone
		(layer "In1.Cu")
		(hatch none 0.5)
		(connect_pads
			(clearance 0)
		)
		(min_thickness 0.25)
		(keepout
			(tracks not_allowed)
			(vias allowed)
			(pads allowed)
			(copperpour not_allowed)
			(footprints allowed)
		)
		(placement
			(enabled no)
			(sheetname "")
		)
		(fill
			(thermal_gap 0.5)
			(thermal_bridge_width 0.5)
			(island_removal_mode 0)
		)
		(polygon
			(pts
				(arc
					(start 56.077358 -221.382336)
					(mid 56.073638 -221.391316)
					(end 56.064658 -221.395036)
				)
				(arc
					(start 54.591458 -221.395036)
					(mid 54.582478 -221.391316)
					(end 54.578758 -221.382336)
				)
				(arc
					(start 54.578758 -220.887798)
					(mid 54.582478 -220.878818)
					(end 54.591458 -220.875098)
				)
				(arc
					(start 56.064658 -220.875098)
					(mid 56.073638 -220.878818)
					(end 56.077358 -220.887798)
				)
			)
		)
	)
	(zone
		(layer "In1.Cu")
		(hatch none 0.5)
		(connect_pads
			(clearance 0)
		)
		(min_thickness 0.25)
		(keepout
			(tracks not_allowed)
			(vias allowed)
			(pads allowed)
			(copperpour not_allowed)
			(footprints allowed)
		)
		(placement
			(enabled no)
			(sheetname "")
		)
		(fill
			(thermal_gap 0.5)
			(thermal_bridge_width 0.5)
			(island_removal_mode 0)
		)
		(polygon
			(pts
				(arc
					(start 206.9973 -311.482486)
					(mid 206.99358 -311.491466)
					(end 206.9846 -311.495186)
				)
				(arc
					(start 205.5114 -311.495186)
					(mid 205.50242 -311.491466)
					(end 205.4987 -311.482486)
				)
				(arc
					(start 205.4987 -310.987948)
					(mid 205.50242 -310.978968)
					(end 205.5114 -310.975248)
				)
				(arc
					(start 206.9846 -310.975248)
					(mid 206.99358 -310.978968)
					(end 206.9973 -310.987948)
				)
			)
		)
	)
	(zone
		(layer "In1.Cu")
		(hatch none 0.5)
		(connect_pads
			(clearance 0)
		)
		(min_thickness 0.25)
		(keepout
			(tracks not_allowed)
			(vias allowed)
			(pads allowed)
			(copperpour not_allowed)
			(footprints allowed)
		)
		(placement
			(enabled no)
			(sheetname "")
		)
		(fill
			(thermal_gap 0.5)
			(thermal_bridge_width 0.5)
			(island_removal_mode 0)
		)
		(polygon
			(pts
				(arc
					(start 308.117494 -214.582248)
					(mid 308.113774 -214.591228)
					(end 308.104794 -214.594948)
				)
				(arc
					(start 306.631594 -214.594948)
					(mid 306.622614 -214.591228)
					(end 306.618894 -214.582248)
				)
				(arc
					(start 306.618894 -214.08771)
					(mid 306.622614 -214.07873)
					(end 306.631594 -214.07501)
				)
				(arc
					(start 308.104794 -214.07501)
					(mid 308.113774 -214.07873)
					(end 308.117494 -214.08771)
				)
			)
		)
	)
	(zone
		(layer "In1.Cu")
		(hatch none 0.5)
		(connect_pads
			(clearance 0)
		)
		(min_thickness 0.25)
		(keepout
			(tracks not_allowed)
			(vias allowed)
			(pads allowed)
			(copperpour not_allowed)
			(footprints allowed)
		)
		(placement
			(enabled no)
			(sheetname "")
		)
		(fill
			(thermal_gap 0.5)
			(thermal_bridge_width 0.5)
			(island_removal_mode 0)
		)
		(polygon
			(pts
				(arc
					(start 180.265324 -201.832464)
					(mid 180.261604 -201.841444)
					(end 180.252624 -201.845164)
				)
				(arc
					(start 178.779424 -201.845164)
					(mid 178.770444 -201.841444)
					(end 178.766724 -201.832464)
				)
				(arc
					(start 178.766724 -201.337926)
					(mid 178.770444 -201.328946)
					(end 178.779424 -201.325226)
				)
				(arc
					(start 180.252624 -201.325226)
					(mid 180.261604 -201.328946)
					(end 180.265324 -201.337926)
				)
			)
		)
	)
	(zone
		(layer "In1.Cu")
		(hatch none 0.5)
		(connect_pads
			(clearance 0)
		)
		(min_thickness 0.25)
		(keepout
			(tracks not_allowed)
			(vias allowed)
			(pads allowed)
			(copperpour not_allowed)
			(footprints allowed)
		)
		(placement
			(enabled no)
			(sheetname "")
		)
		(fill
			(thermal_gap 0.5)
			(thermal_bridge_width 0.5)
			(island_removal_mode 0)
		)
		(polygon
			(pts
				(arc
					(start 304.017426 -213.73211)
					(mid 304.013706 -213.74109)
					(end 304.004726 -213.74481)
				)
				(arc
					(start 302.531526 -213.74481)
					(mid 302.522546 -213.74109)
					(end 302.518826 -213.73211)
				)
				(arc
					(start 302.518826 -213.237572)
					(mid 302.522546 -213.228592)
					(end 302.531526 -213.224872)
				)
				(arc
					(start 304.004726 -213.224872)
					(mid 304.013706 -213.228592)
					(end 304.017426 -213.237572)
				)
			)
		)
	)
	(zone
		(layer "In1.Cu")
		(hatch none 0.5)
		(connect_pads
			(clearance 0)
		)
		(min_thickness 0.25)
		(keepout
			(tracks not_allowed)
			(vias allowed)
			(pads allowed)
			(copperpour not_allowed)
			(footprints allowed)
		)
		(placement
			(enabled no)
			(sheetname "")
		)
		(fill
			(thermal_gap 0.5)
			(thermal_bridge_width 0.5)
			(island_removal_mode 0)
		)
		(polygon
			(pts
				(arc
					(start 45.089318 -294.48252)
					(mid 45.085598 -294.4915)
					(end 45.076618 -294.49522)
				)
				(arc
					(start 43.603418 -294.49522)
					(mid 43.594438 -294.4915)
					(end 43.590718 -294.48252)
				)
				(arc
					(start 43.590718 -293.987982)
					(mid 43.594438 -293.979002)
					(end 43.603418 -293.975282)
				)
				(arc
					(start 45.076618 -293.975282)
					(mid 45.085598 -293.979002)
					(end 45.089318 -293.987982)
				)
			)
		)
	)
	(zone
		(layer "In1.Cu")
		(hatch none 0.5)
		(connect_pads
			(clearance 0)
		)
		(min_thickness 0.25)
		(keepout
			(tracks not_allowed)
			(vias allowed)
			(pads allowed)
			(copperpour not_allowed)
			(footprints allowed)
		)
		(placement
			(enabled no)
			(sheetname "")
		)
		(fill
			(thermal_gap 0.5)
			(thermal_bridge_width 0.5)
			(island_removal_mode 0)
		)
		(polygon
			(pts
				(arc
					(start 155.598114 -390.761474)
					(mid 155.293314 -390.761474)
					(end 155.598114 -390.761474)
				)
			)
		)
	)
	(zone
		(layer "In1.Cu")
		(hatch none 0.5)
		(connect_pads
			(clearance 0)
		)
		(min_thickness 0.25)
		(keepout
			(tracks not_allowed)
			(vias allowed)
			(pads allowed)
			(copperpour not_allowed)
			(footprints allowed)
		)
		(placement
			(enabled no)
			(sheetname "")
		)
		(fill
			(thermal_gap 0.5)
			(thermal_bridge_width 0.5)
			(island_removal_mode 0)
		)
		(polygon
			(pts
				(arc
					(start 296.473372 -198.432166)
					(mid 296.469652 -198.441146)
					(end 296.460672 -198.444866)
				)
				(arc
					(start 294.987472 -198.444866)
					(mid 294.978492 -198.441146)
					(end 294.974772 -198.432166)
				)
				(arc
					(start 294.974772 -197.937628)
					(mid 294.978492 -197.928648)
					(end 294.987472 -197.924928)
				)
				(arc
					(start 296.460672 -197.924928)
					(mid 296.469652 -197.928648)
					(end 296.473372 -197.937628)
				)
			)
		)
	)
	(zone
		(layer "In1.Cu")
		(hatch none 0.5)
		(connect_pads
			(clearance 0)
		)
		(min_thickness 0.25)
		(keepout
			(tracks not_allowed)
			(vias allowed)
			(pads allowed)
			(copperpour not_allowed)
			(footprints allowed)
		)
		(placement
			(enabled no)
			(sheetname "")
		)
		(fill
			(thermal_gap 0.5)
			(thermal_bridge_width 0.5)
			(island_removal_mode 0)
		)
		(polygon
			(pts
				(arc
					(start 184.365392 -251.13234)
					(mid 184.361672 -251.14132)
					(end 184.352692 -251.14504)
				)
				(arc
					(start 182.879492 -251.14504)
					(mid 182.870512 -251.14132)
					(end 182.866792 -251.13234)
				)
				(arc
					(start 182.866792 -250.637802)
					(mid 182.870512 -250.628822)
					(end 182.879492 -250.625102)
				)
				(arc
					(start 184.352692 -250.625102)
					(mid 184.361672 -250.628822)
					(end 184.365392 -250.637802)
				)
			)
		)
	)
	(zone
		(layer "In1.Cu")
		(hatch none 0.5)
		(connect_pads
			(clearance 0)
		)
		(min_thickness 0.25)
		(keepout
			(tracks not_allowed)
			(vias allowed)
			(pads allowed)
			(copperpour not_allowed)
			(footprints allowed)
		)
		(placement
			(enabled no)
			(sheetname "")
		)
		(fill
			(thermal_gap 0.5)
			(thermal_bridge_width 0.5)
			(island_removal_mode 0)
		)
		(polygon
			(pts
				(arc
					(start 375.3612 -397.156432)
					(mid 374.9802 -397.156432)
					(end 375.3612 -397.156432)
				)
			)
		)
	)
	(zone
		(layer "In1.Cu")
		(hatch none 0.5)
		(connect_pads
			(clearance 0)
		)
		(min_thickness 0.25)
		(keepout
			(tracks not_allowed)
			(vias allowed)
			(pads allowed)
			(copperpour not_allowed)
			(footprints allowed)
		)
		(placement
			(enabled no)
			(sheetname "")
		)
		(fill
			(thermal_gap 0.5)
			(thermal_bridge_width 0.5)
			(island_removal_mode 0)
		)
		(polygon
			(pts
				(arc
					(start 191.909446 -206.93253)
					(mid 191.905726 -206.94151)
					(end 191.896746 -206.94523)
				)
				(arc
					(start 190.423546 -206.94523)
					(mid 190.414566 -206.94151)
					(end 190.410846 -206.93253)
				)
				(arc
					(start 190.410846 -206.437992)
					(mid 190.414566 -206.429012)
					(end 190.423546 -206.425292)
				)
				(arc
					(start 191.896746 -206.425292)
					(mid 191.905726 -206.429012)
					(end 191.909446 -206.437992)
				)
			)
		)
	)
	(zone
		(layer "In1.Cu")
		(hatch none 0.5)
		(connect_pads
			(clearance 0)
		)
		(min_thickness 0.25)
		(keepout
			(tracks not_allowed)
			(vias allowed)
			(pads allowed)
			(copperpour not_allowed)
			(footprints allowed)
		)
		(placement
			(enabled no)
			(sheetname "")
		)
		(fill
			(thermal_gap 0.5)
			(thermal_bridge_width 0.5)
			(island_removal_mode 0)
		)
		(polygon
			(pts
				(arc
					(start 45.089318 -252.832362)
					(mid 45.085598 -252.841342)
					(end 45.076618 -252.845062)
				)
				(arc
					(start 43.603418 -252.845062)
					(mid 43.594438 -252.841342)
					(end 43.590718 -252.832362)
				)
				(arc
					(start 43.590718 -252.337824)
					(mid 43.594438 -252.328844)
					(end 43.603418 -252.325124)
				)
				(arc
					(start 45.076618 -252.325124)
					(mid 45.085598 -252.328844)
					(end 45.089318 -252.337824)
				)
			)
		)
	)
	(zone
		(layer "In1.Cu")
		(hatch none 0.5)
		(connect_pads
			(clearance 0)
		)
		(min_thickness 0.25)
		(keepout
			(tracks not_allowed)
			(vias allowed)
			(pads allowed)
			(copperpour not_allowed)
			(footprints allowed)
		)
		(placement
			(enabled no)
			(sheetname "")
		)
		(fill
			(thermal_gap 0.5)
			(thermal_bridge_width 0.5)
			(island_removal_mode 0)
		)
		(polygon
			(pts
				(arc
					(start 51.772566 -7.672324)
					(mid 51.794884 -7.618442)
					(end 51.848766 -7.596124)
				)
				(arc
					(start 52.88534 -7.596124)
					(mid 52.939222 -7.618442)
					(end 52.96154 -7.672324)
				)
				(arc
					(start 52.96154 -9.071864)
					(mid 52.939222 -9.125746)
					(end 52.88534 -9.148064)
				)
				(arc
					(start 51.848766 -9.148064)
					(mid 51.794884 -9.125746)
					(end 51.772566 -9.071864)
				)
			)
		)
	)
	(zone
		(layer "In1.Cu")
		(hatch none 0.5)
		(connect_pads
			(clearance 0)
		)
		(min_thickness 0.25)
		(keepout
			(tracks not_allowed)
			(vias allowed)
			(pads allowed)
			(copperpour not_allowed)
			(footprints allowed)
		)
		(placement
			(enabled no)
			(sheetname "")
		)
		(fill
			(thermal_gap 0.5)
			(thermal_bridge_width 0.5)
			(island_removal_mode 0)
		)
		(polygon
			(pts
				(arc
					(start 96.788986 -388.774432)
					(mid 96.407986 -388.774432)
					(end 96.788986 -388.774432)
				)
			)
		)
	)
	(zone
		(layer "In1.Cu")
		(hatch none 0.5)
		(connect_pads
			(clearance 0)
		)
		(min_thickness 0.25)
		(keepout
			(tracks not_allowed)
			(vias allowed)
			(pads allowed)
			(copperpour not_allowed)
			(footprints allowed)
		)
		(placement
			(enabled no)
			(sheetname "")
		)
		(fill
			(thermal_gap 0.5)
			(thermal_bridge_width 0.5)
			(island_removal_mode 0)
		)
		(polygon
			(pts
				(arc
					(start 413.117284 -237.532164)
					(mid 413.113564 -237.541144)
					(end 413.104584 -237.544864)
				)
				(arc
					(start 411.631384 -237.544864)
					(mid 411.622404 -237.541144)
					(end 411.618684 -237.532164)
				)
				(arc
					(start 411.618684 -237.037626)
					(mid 411.622404 -237.028646)
					(end 411.631384 -237.024926)
				)
				(arc
					(start 413.104584 -237.024926)
					(mid 413.113564 -237.028646)
					(end 413.117284 -237.037626)
				)
			)
		)
	)
	(zone
		(layer "In1.Cu")
		(hatch none 0.5)
		(connect_pads
			(clearance 0)
		)
		(min_thickness 0.25)
		(keepout
			(tracks not_allowed)
			(vias allowed)
			(pads allowed)
			(copperpour not_allowed)
			(footprints allowed)
		)
		(placement
			(enabled no)
			(sheetname "")
		)
		(fill
			(thermal_gap 0.5)
			(thermal_bridge_width 0.5)
			(island_removal_mode 0)
		)
		(polygon
			(pts
				(arc
					(start 293.029386 -254.53213)
					(mid 293.025666 -254.54111)
					(end 293.016686 -254.54483)
				)
				(arc
					(start 291.543486 -254.54483)
					(mid 291.534506 -254.54111)
					(end 291.530786 -254.53213)
				)
				(arc
					(start 291.530786 -254.037592)
					(mid 291.534506 -254.028612)
					(end 291.543486 -254.024892)
				)
				(arc
					(start 293.016686 -254.024892)
					(mid 293.025666 -254.028612)
					(end 293.029386 -254.037592)
				)
			)
		)
	)
	(zone
		(layer "In1.Cu")
		(hatch none 0.5)
		(connect_pads
			(clearance 0)
		)
		(min_thickness 0.25)
		(keepout
			(tracks not_allowed)
			(vias allowed)
			(pads allowed)
			(copperpour not_allowed)
			(footprints allowed)
		)
		(placement
			(enabled no)
			(sheetname "")
		)
		(fill
			(thermal_gap 0.5)
			(thermal_bridge_width 0.5)
			(island_removal_mode 0)
		)
		(polygon
			(pts
				(arc
					(start 288.929318 -246.882158)
					(mid 288.925598 -246.891138)
					(end 288.916618 -246.894858)
				)
				(arc
					(start 287.443418 -246.894858)
					(mid 287.434438 -246.891138)
					(end 287.430718 -246.882158)
				)
				(arc
					(start 287.430718 -246.38762)
					(mid 287.434438 -246.37864)
					(end 287.443418 -246.37492)
				)
				(arc
					(start 288.916618 -246.37492)
					(mid 288.925598 -246.37864)
					(end 288.929318 -246.38762)
				)
			)
		)
	)
	(zone
		(layer "In1.Cu")
		(hatch none 0.5)
		(connect_pads
			(clearance 0)
		)
		(min_thickness 0.25)
		(keepout
			(tracks not_allowed)
			(vias allowed)
			(pads allowed)
			(copperpour not_allowed)
			(footprints allowed)
		)
		(placement
			(enabled no)
			(sheetname "")
		)
		(fill
			(thermal_gap 0.5)
			(thermal_bridge_width 0.5)
			(island_removal_mode 0)
		)
		(polygon
			(pts
				(arc
					(start 60.177426 -269.832582)
					(mid 60.173706 -269.841562)
					(end 60.164726 -269.845282)
				)
				(arc
					(start 58.691526 -269.845282)
					(mid 58.682546 -269.841562)
					(end 58.678826 -269.832582)
				)
				(arc
					(start 58.678826 -269.338044)
					(mid 58.682546 -269.329064)
					(end 58.691526 -269.325344)
				)
				(arc
					(start 60.164726 -269.325344)
					(mid 60.173706 -269.329064)
					(end 60.177426 -269.338044)
				)
			)
		)
	)
	(zone
		(layer "In1.Cu")
		(hatch none 0.5)
		(connect_pads
			(clearance 0)
		)
		(min_thickness 0.25)
		(keepout
			(tracks not_allowed)
			(vias allowed)
			(pads allowed)
			(copperpour not_allowed)
			(footprints allowed)
		)
		(placement
			(enabled no)
			(sheetname "")
		)
		(fill
			(thermal_gap 0.5)
			(thermal_bridge_width 0.5)
			(island_removal_mode 0)
		)
		(polygon
			(pts
				(arc
					(start 447.393568 -300.432216)
					(mid 447.389848 -300.441196)
					(end 447.380868 -300.444916)
				)
				(arc
					(start 445.907668 -300.444916)
					(mid 445.898688 -300.441196)
					(end 445.894968 -300.432216)
				)
				(arc
					(start 445.894968 -299.937678)
					(mid 445.898688 -299.928698)
					(end 445.907668 -299.924978)
				)
				(arc
					(start 447.380868 -299.924978)
					(mid 447.389848 -299.928698)
					(end 447.393568 -299.937678)
				)
			)
		)
	)
	(zone
		(layer "In1.Cu")
		(hatch none 0.5)
		(connect_pads
			(clearance 0)
		)
		(min_thickness 0.25)
		(keepout
			(tracks not_allowed)
			(vias allowed)
			(pads allowed)
			(copperpour not_allowed)
			(footprints allowed)
		)
		(placement
			(enabled no)
			(sheetname "")
		)
		(fill
			(thermal_gap 0.5)
			(thermal_bridge_width 0.5)
			(island_removal_mode 0)
		)
		(polygon
			(pts
				(arc
					(start 293.029386 -223.932242)
					(mid 293.025666 -223.941222)
					(end 293.016686 -223.944942)
				)
				(arc
					(start 291.543486 -223.944942)
					(mid 291.534506 -223.941222)
					(end 291.530786 -223.932242)
				)
				(arc
					(start 291.530786 -223.437704)
					(mid 291.534506 -223.428724)
					(end 291.543486 -223.425004)
				)
				(arc
					(start 293.016686 -223.425004)
					(mid 293.025666 -223.428724)
					(end 293.029386 -223.437704)
				)
			)
		)
	)
	(zone
		(layer "In1.Cu")
		(hatch none 0.5)
		(connect_pads
			(clearance 0)
		)
		(min_thickness 0.25)
		(keepout
			(tracks not_allowed)
			(vias allowed)
			(pads allowed)
			(copperpour not_allowed)
			(footprints allowed)
		)
		(placement
			(enabled no)
			(sheetname "")
		)
		(fill
			(thermal_gap 0.5)
			(thermal_bridge_width 0.5)
			(island_removal_mode 0)
		)
		(polygon
			(pts
				(arc
					(start 443.2935 -296.182288)
					(mid 443.28978 -296.191268)
					(end 443.2808 -296.194988)
				)
				(arc
					(start 441.8076 -296.194988)
					(mid 441.79862 -296.191268)
					(end 441.7949 -296.182288)
				)
				(arc
					(start 441.7949 -295.68775)
					(mid 441.79862 -295.67877)
					(end 441.8076 -295.67505)
				)
				(arc
					(start 443.2808 -295.67505)
					(mid 443.28978 -295.67877)
					(end 443.2935 -295.68775)
				)
			)
		)
	)
	(zone
		(layer "In1.Cu")
		(hatch none 0.5)
		(connect_pads
			(clearance 0)
		)
		(min_thickness 0.25)
		(keepout
			(tracks not_allowed)
			(vias allowed)
			(pads allowed)
			(copperpour not_allowed)
			(footprints allowed)
		)
		(placement
			(enabled no)
			(sheetname "")
		)
		(fill
			(thermal_gap 0.5)
			(thermal_bridge_width 0.5)
			(island_removal_mode 0)
		)
		(polygon
			(pts
				(arc
					(start 384.96113 -393.69238)
					(mid 384.58013 -393.69238)
					(end 384.96113 -393.69238)
				)
			)
		)
	)
	(zone
		(layer "In1.Cu")
		(hatch none 0.5)
		(connect_pads
			(clearance 0)
		)
		(min_thickness 0.25)
		(keepout
			(tracks not_allowed)
			(vias allowed)
			(pads allowed)
			(copperpour not_allowed)
			(footprints allowed)
		)
		(placement
			(enabled no)
			(sheetname "")
		)
		(fill
			(thermal_gap 0.5)
			(thermal_bridge_width 0.5)
			(island_removal_mode 0)
		)
		(polygon
			(pts
				(arc
					(start 306.5907 -391.822686)
					(mid 306.7177 -391.949686)
					(end 306.8447 -391.822686)
				)
				(arc
					(start 306.8447 -391.746486)
					(mid 306.7177 -391.619486)
					(end 306.5907 -391.746486)
				)
			)
		)
	)
	(zone
		(layer "In1.Cu")
		(hatch none 0.5)
		(connect_pads
			(clearance 0)
		)
		(min_thickness 0.25)
		(keepout
			(tracks not_allowed)
			(vias allowed)
			(pads allowed)
			(copperpour not_allowed)
			(footprints allowed)
		)
		(placement
			(enabled no)
			(sheetname "")
		)
		(fill
			(thermal_gap 0.5)
			(thermal_bridge_width 0.5)
			(island_removal_mode 0)
		)
		(polygon
			(pts
				(arc
					(start 153.818844 -383.440686)
					(mid 153.945844 -383.567686)
					(end 154.072844 -383.440686)
				)
				(arc
					(start 154.072844 -383.364486)
					(mid 153.945844 -383.237486)
					(end 153.818844 -383.364486)
				)
			)
		)
	)
	(zone
		(layer "In1.Cu")
		(hatch none 0.5)
		(connect_pads
			(clearance 0)
		)
		(min_thickness 0.25)
		(keepout
			(tracks not_allowed)
			(vias allowed)
			(pads allowed)
			(copperpour not_allowed)
			(footprints allowed)
		)
		(placement
			(enabled no)
			(sheetname "")
		)
		(fill
			(thermal_gap 0.5)
			(thermal_bridge_width 0.5)
			(island_removal_mode 0)
		)
		(polygon
			(pts
				(arc
					(start 149.598126 -390.761474)
					(mid 149.293326 -390.761474)
					(end 149.598126 -390.761474)
				)
			)
		)
	)
	(zone
		(layer "In1.Cu")
		(hatch none 0.5)
		(connect_pads
			(clearance 0)
		)
		(min_thickness 0.25)
		(keepout
			(tracks not_allowed)
			(vias allowed)
			(pads allowed)
			(copperpour not_allowed)
			(footprints allowed)
		)
		(placement
			(enabled no)
			(sheetname "")
		)
		(fill
			(thermal_gap 0.5)
			(thermal_bridge_width 0.5)
			(island_removal_mode 0)
		)
		(polygon
			(pts
				(arc
					(start 184.365392 -254.532384)
					(mid 184.361672 -254.541364)
					(end 184.352692 -254.545084)
				)
				(arc
					(start 182.879492 -254.545084)
					(mid 182.870512 -254.541364)
					(end 182.866792 -254.532384)
				)
				(arc
					(start 182.866792 -254.037846)
					(mid 182.870512 -254.028866)
					(end 182.879492 -254.025146)
				)
				(arc
					(start 184.352692 -254.025146)
					(mid 184.361672 -254.028866)
					(end 184.365392 -254.037846)
				)
			)
		)
	)
	(zone
		(layer "In1.Cu")
		(hatch none 0.5)
		(connect_pads
			(clearance 0)
		)
		(min_thickness 0.25)
		(keepout
			(tracks not_allowed)
			(vias allowed)
			(pads allowed)
			(copperpour not_allowed)
			(footprints allowed)
		)
		(placement
			(enabled no)
			(sheetname "")
		)
		(fill
			(thermal_gap 0.5)
			(thermal_bridge_width 0.5)
			(island_removal_mode 0)
		)
		(polygon
			(pts
				(arc
					(start 285.485332 -292.782244)
					(mid 285.481612 -292.791224)
					(end 285.472632 -292.794944)
				)
				(arc
					(start 283.999432 -292.794944)
					(mid 283.990452 -292.791224)
					(end 283.986732 -292.782244)
				)
				(arc
					(start 283.986732 -292.287706)
					(mid 283.990452 -292.278726)
					(end 283.999432 -292.275006)
				)
				(arc
					(start 285.472632 -292.275006)
					(mid 285.481612 -292.278726)
					(end 285.485332 -292.287706)
				)
			)
		)
	)
	(zone
		(layer "In1.Cu")
		(hatch none 0.5)
		(connect_pads
			(clearance 0)
		)
		(min_thickness 0.25)
		(keepout
			(tracks not_allowed)
			(vias allowed)
			(pads allowed)
			(copperpour not_allowed)
			(footprints allowed)
		)
		(placement
			(enabled no)
			(sheetname "")
		)
		(fill
			(thermal_gap 0.5)
			(thermal_bridge_width 0.5)
			(island_removal_mode 0)
		)
		(polygon
			(pts
				(arc
					(start 93.298264 -383.92227)
					(mid 92.993464 -383.92227)
					(end 93.298264 -383.92227)
				)
			)
		)
	)
	(zone
		(layer "In1.Cu")
		(hatch none 0.5)
		(connect_pads
			(clearance 0)
		)
		(min_thickness 0.25)
		(keepout
			(tracks not_allowed)
			(vias allowed)
			(pads allowed)
			(copperpour not_allowed)
			(footprints allowed)
		)
		(placement
			(enabled no)
			(sheetname "")
		)
		(fill
			(thermal_gap 0.5)
			(thermal_bridge_width 0.5)
			(island_removal_mode 0)
		)
		(polygon
			(pts
				(arc
					(start 413.117284 -288.532316)
					(mid 413.113564 -288.541296)
					(end 413.104584 -288.545016)
				)
				(arc
					(start 411.631384 -288.545016)
					(mid 411.622404 -288.541296)
					(end 411.618684 -288.532316)
				)
				(arc
					(start 411.618684 -288.037778)
					(mid 411.622404 -288.028798)
					(end 411.631384 -288.025078)
				)
				(arc
					(start 413.104584 -288.025078)
					(mid 413.113564 -288.028798)
					(end 413.117284 -288.037778)
				)
			)
		)
	)
	(zone
		(layer "In1.Cu")
		(hatch none 0.5)
		(connect_pads
			(clearance 0)
		)
		(min_thickness 0.25)
		(keepout
			(tracks not_allowed)
			(vias allowed)
			(pads allowed)
			(copperpour not_allowed)
			(footprints allowed)
		)
		(placement
			(enabled no)
			(sheetname "")
		)
		(fill
			(thermal_gap 0.5)
			(thermal_bridge_width 0.5)
			(island_removal_mode 0)
		)
		(polygon
			(pts
				(arc
					(start 176.821338 -300.43247)
					(mid 176.817618 -300.44145)
					(end 176.808638 -300.44517)
				)
				(arc
					(start 175.335438 -300.44517)
					(mid 175.326458 -300.44145)
					(end 175.322738 -300.43247)
				)
				(arc
					(start 175.322738 -299.937932)
					(mid 175.326458 -299.928952)
					(end 175.335438 -299.925232)
				)
				(arc
					(start 176.808638 -299.925232)
					(mid 176.817618 -299.928952)
					(end 176.821338 -299.937932)
				)
			)
		)
	)
	(zone
		(layer "In1.Cu")
		(hatch none 0.5)
		(connect_pads
			(clearance 0)
		)
		(min_thickness 0.25)
		(keepout
			(tracks not_allowed)
			(vias allowed)
			(pads allowed)
			(copperpour not_allowed)
			(footprints allowed)
		)
		(placement
			(enabled no)
			(sheetname "")
		)
		(fill
			(thermal_gap 0.5)
			(thermal_bridge_width 0.5)
			(island_removal_mode 0)
		)
		(polygon
			(pts
				(arc
					(start 281.385264 -232.432098)
					(mid 281.381544 -232.441078)
					(end 281.372564 -232.444798)
				)
				(arc
					(start 279.899364 -232.444798)
					(mid 279.890384 -232.441078)
					(end 279.886664 -232.432098)
				)
				(arc
					(start 279.886664 -231.93756)
					(mid 279.890384 -231.92858)
					(end 279.899364 -231.92486)
				)
				(arc
					(start 281.372564 -231.92486)
					(mid 281.381544 -231.92858)
					(end 281.385264 -231.93756)
				)
			)
		)
	)
	(zone
		(layer "In1.Cu")
		(hatch none 0.5)
		(connect_pads
			(clearance 0)
		)
		(min_thickness 0.25)
		(keepout
			(tracks not_allowed)
			(vias allowed)
			(pads allowed)
			(copperpour not_allowed)
			(footprints allowed)
		)
		(placement
			(enabled no)
			(sheetname "")
		)
		(fill
			(thermal_gap 0.5)
			(thermal_bridge_width 0.5)
			(island_removal_mode 0)
		)
		(polygon
			(pts
				(arc
					(start 345.588844 -393.69238)
					(mid 345.207844 -393.69238)
					(end 345.588844 -393.69238)
				)
			)
		)
	)
	(zone
		(layer "In1.Cu")
		(hatch none 0.5)
		(connect_pads
			(clearance 0)
		)
		(min_thickness 0.25)
		(keepout
			(tracks not_allowed)
			(vias allowed)
			(pads allowed)
			(copperpour not_allowed)
			(footprints allowed)
		)
		(placement
			(enabled no)
			(sheetname "")
		)
		(fill
			(thermal_gap 0.5)
			(thermal_bridge_width 0.5)
			(island_removal_mode 0)
		)
		(polygon
			(pts
				(arc
					(start 443.2935 -316.582298)
					(mid 443.28978 -316.591278)
					(end 443.2808 -316.594998)
				)
				(arc
					(start 441.8076 -316.594998)
					(mid 441.79862 -316.591278)
					(end 441.7949 -316.582298)
				)
				(arc
					(start 441.7949 -316.08776)
					(mid 441.79862 -316.07878)
					(end 441.8076 -316.07506)
				)
				(arc
					(start 443.2808 -316.07506)
					(mid 443.28978 -316.07878)
					(end 443.2935 -316.08776)
				)
			)
		)
	)
	(zone
		(layer "In1.Cu")
		(hatch none 0.5)
		(connect_pads
			(clearance 0)
		)
		(min_thickness 0.25)
		(keepout
			(tracks not_allowed)
			(vias allowed)
			(pads allowed)
			(copperpour not_allowed)
			(footprints allowed)
		)
		(placement
			(enabled no)
			(sheetname "")
		)
		(fill
			(thermal_gap 0.5)
			(thermal_bridge_width 0.5)
			(island_removal_mode 0)
		)
		(polygon
			(pts
				(arc
					(start 270.397478 -289.3822)
					(mid 270.393758 -289.39118)
					(end 270.384778 -289.3949)
				)
				(arc
					(start 268.911578 -289.3949)
					(mid 268.902598 -289.39118)
					(end 268.898878 -289.3822)
				)
				(arc
					(start 268.898878 -288.887662)
					(mid 268.902598 -288.878682)
					(end 268.911578 -288.874962)
				)
				(arc
					(start 270.384778 -288.874962)
					(mid 270.393758 -288.878682)
					(end 270.397478 -288.887662)
				)
			)
		)
	)
	(zone
		(layer "In1.Cu")
		(hatch none 0.5)
		(connect_pads
			(clearance 0)
		)
		(min_thickness 0.25)
		(keepout
			(tracks not_allowed)
			(vias allowed)
			(pads allowed)
			(copperpour not_allowed)
			(footprints allowed)
		)
		(placement
			(enabled no)
			(sheetname "")
		)
		(fill
			(thermal_gap 0.5)
			(thermal_bridge_width 0.5)
			(island_removal_mode 0)
		)
		(polygon
			(pts
				(arc
					(start 454.937368 -274.082256)
					(mid 454.933648 -274.091236)
					(end 454.924668 -274.094956)
				)
				(arc
					(start 453.451468 -274.094956)
					(mid 453.442488 -274.091236)
					(end 453.438768 -274.082256)
				)
				(arc
					(start 453.438768 -273.587718)
					(mid 453.442488 -273.578738)
					(end 453.451468 -273.575018)
				)
				(arc
					(start 454.924668 -273.575018)
					(mid 454.933648 -273.578738)
					(end 454.937368 -273.587718)
				)
			)
		)
	)
	(zone
		(layer "In1.Cu")
		(hatch none 0.5)
		(connect_pads
			(clearance 0)
		)
		(min_thickness 0.25)
		(keepout
			(tracks not_allowed)
			(vias allowed)
			(pads allowed)
			(copperpour not_allowed)
			(footprints allowed)
		)
		(placement
			(enabled no)
			(sheetname "")
		)
		(fill
			(thermal_gap 0.5)
			(thermal_bridge_width 0.5)
			(island_removal_mode 0)
		)
		(polygon
			(pts
				(arc
					(start 60.177426 -287.682432)
					(mid 60.173706 -287.691412)
					(end 60.164726 -287.695132)
				)
				(arc
					(start 58.691526 -287.695132)
					(mid 58.682546 -287.691412)
					(end 58.678826 -287.682432)
				)
				(arc
					(start 58.678826 -287.187894)
					(mid 58.682546 -287.178914)
					(end 58.691526 -287.175194)
				)
				(arc
					(start 60.164726 -287.175194)
					(mid 60.173706 -287.178914)
					(end 60.177426 -287.187894)
				)
			)
		)
	)
	(zone
		(layer "In1.Cu")
		(hatch none 0.5)
		(connect_pads
			(clearance 0)
		)
		(min_thickness 0.25)
		(keepout
			(tracks not_allowed)
			(vias allowed)
			(pads allowed)
			(copperpour not_allowed)
			(footprints allowed)
		)
		(placement
			(enabled no)
			(sheetname "")
		)
		(fill
			(thermal_gap 0.5)
			(thermal_bridge_width 0.5)
			(island_removal_mode 0)
		)
		(polygon
			(pts
				(arc
					(start 439.849514 -252.832108)
					(mid 439.845794 -252.841088)
					(end 439.836814 -252.844808)
				)
				(arc
					(start 438.363614 -252.844808)
					(mid 438.354634 -252.841088)
					(end 438.350914 -252.832108)
				)
				(arc
					(start 438.350914 -252.33757)
					(mid 438.354634 -252.32859)
					(end 438.363614 -252.32487)
				)
				(arc
					(start 439.836814 -252.32487)
					(mid 439.845794 -252.32859)
					(end 439.849514 -252.33757)
				)
			)
		)
	)
	(zone
		(layer "In1.Cu")
		(hatch none 0.5)
		(connect_pads
			(clearance 0)
		)
		(min_thickness 0.25)
		(keepout
			(tracks not_allowed)
			(vias allowed)
			(pads allowed)
			(copperpour not_allowed)
			(footprints allowed)
		)
		(placement
			(enabled no)
			(sheetname "")
		)
		(fill
			(thermal_gap 0.5)
			(thermal_bridge_width 0.5)
			(island_removal_mode 0)
		)
		(polygon
			(pts
				(arc
					(start 277.941532 -246.032274)
					(mid 277.937812 -246.041254)
					(end 277.928832 -246.044974)
				)
				(arc
					(start 276.455632 -246.044974)
					(mid 276.446652 -246.041254)
					(end 276.442932 -246.032274)
				)
				(arc
					(start 276.442932 -245.537736)
					(mid 276.446652 -245.528756)
					(end 276.455632 -245.525036)
				)
				(arc
					(start 277.928832 -245.525036)
					(mid 277.937812 -245.528756)
					(end 277.941532 -245.537736)
				)
			)
		)
	)
	(zone
		(layer "In1.Cu")
		(hatch none 0.5)
		(connect_pads
			(clearance 0)
		)
		(min_thickness 0.25)
		(keepout
			(tracks not_allowed)
			(vias allowed)
			(pads allowed)
			(copperpour not_allowed)
			(footprints allowed)
		)
		(placement
			(enabled no)
			(sheetname "")
		)
		(fill
			(thermal_gap 0.5)
			(thermal_bridge_width 0.5)
			(island_removal_mode 0)
		)
		(polygon
			(pts
				(arc
					(start 300.57344 -201.83221)
					(mid 300.56972 -201.84119)
					(end 300.56074 -201.84491)
				)
				(arc
					(start 299.08754 -201.84491)
					(mid 299.07856 -201.84119)
					(end 299.07484 -201.83221)
				)
				(arc
					(start 299.07484 -201.337672)
					(mid 299.07856 -201.328692)
					(end 299.08754 -201.324972)
				)
				(arc
					(start 300.56074 -201.324972)
					(mid 300.56972 -201.328692)
					(end 300.57344 -201.337672)
				)
			)
		)
	)
	(zone
		(layer "In1.Cu")
		(hatch none 0.5)
		(connect_pads
			(clearance 0)
		)
		(min_thickness 0.25)
		(keepout
			(tracks not_allowed)
			(vias allowed)
			(pads allowed)
			(copperpour not_allowed)
			(footprints allowed)
		)
		(placement
			(enabled no)
			(sheetname "")
		)
		(fill
			(thermal_gap 0.5)
			(thermal_bridge_width 0.5)
			(island_removal_mode 0)
		)
		(polygon
			(pts
				(arc
					(start 308.2925 -379.360684)
					(mid 308.312424 -379.36992)
					(end 308.334156 -379.37313)
				)
				(arc
					(start 308.52872 -379.37313)
					(mid 308.582602 -379.350812)
					(end 308.60492 -379.29693)
				)
				(arc
					(start 308.60492 -378.61113)
					(mid 308.582602 -378.557248)
					(end 308.52872 -378.53493)
				)
				(arc
					(start 308.334156 -378.53493)
					(mid 308.312412 -378.538098)
					(end 308.2925 -378.547376)
				)
				(arc
					(start 307.996336 -378.740162)
					(mid 307.954652 -378.752384)
					(end 307.913024 -378.739908)
				)
				(arc
					(start 307.6194 -378.547376)
					(mid 307.599476 -378.53814)
					(end 307.577744 -378.53493)
				)
				(arc
					(start 307.38318 -378.53493)
					(mid 307.329298 -378.557248)
					(end 307.30698 -378.61113)
				)
				(arc
					(start 307.30698 -379.29693)
					(mid 307.329298 -379.350812)
					(end 307.38318 -379.37313)
				)
				(arc
					(start 307.579014 -379.37313)
					(mid 307.600758 -379.369962)
					(end 307.62067 -379.360684)
				)
				(arc
					(start 307.914294 -379.168152)
					(mid 307.95595 -379.15575)
					(end 307.997606 -379.168152)
				)
			)
		)
	)
	(zone
		(layer "In1.Cu")
		(hatch none 0.5)
		(connect_pads
			(clearance 0)
		)
		(min_thickness 0.25)
		(keepout
			(tracks not_allowed)
			(vias allowed)
			(pads allowed)
			(copperpour not_allowed)
			(footprints allowed)
		)
		(placement
			(enabled no)
			(sheetname "")
		)
		(fill
			(thermal_gap 0.5)
			(thermal_bridge_width 0.5)
			(island_removal_mode 0)
		)
		(polygon
			(pts
				(arc
					(start 33.445196 -254.532384)
					(mid 33.441476 -254.541364)
					(end 33.432496 -254.545084)
				)
				(arc
					(start 31.959296 -254.545084)
					(mid 31.950316 -254.541364)
					(end 31.946596 -254.532384)
				)
				(arc
					(start 31.946596 -254.037846)
					(mid 31.950316 -254.028866)
					(end 31.959296 -254.025146)
				)
				(arc
					(start 33.432496 -254.025146)
					(mid 33.441476 -254.028866)
					(end 33.445196 -254.037846)
				)
			)
		)
	)
	(zone
		(layer "In1.Cu")
		(hatch none 0.5)
		(connect_pads
			(clearance 0)
		)
		(min_thickness 0.25)
		(keepout
			(tracks not_allowed)
			(vias allowed)
			(pads allowed)
			(copperpour not_allowed)
			(footprints allowed)
		)
		(placement
			(enabled no)
			(sheetname "")
		)
		(fill
			(thermal_gap 0.5)
			(thermal_bridge_width 0.5)
			(island_removal_mode 0)
		)
		(polygon
			(pts
				(arc
					(start 40.98925 -201.832464)
					(mid 40.98553 -201.841444)
					(end 40.97655 -201.845164)
				)
				(arc
					(start 39.50335 -201.845164)
					(mid 39.49437 -201.841444)
					(end 39.49065 -201.832464)
				)
				(arc
					(start 39.49065 -201.337926)
					(mid 39.49437 -201.328946)
					(end 39.50335 -201.325226)
				)
				(arc
					(start 40.97655 -201.325226)
					(mid 40.98553 -201.328946)
					(end 40.98925 -201.337926)
				)
			)
		)
	)
	(zone
		(layer "In1.Cu")
		(hatch none 0.5)
		(connect_pads
			(clearance 0)
		)
		(min_thickness 0.25)
		(keepout
			(tracks not_allowed)
			(vias allowed)
			(pads allowed)
			(copperpour not_allowed)
			(footprints allowed)
		)
		(placement
			(enabled no)
			(sheetname "")
		)
		(fill
			(thermal_gap 0.5)
			(thermal_bridge_width 0.5)
			(island_removal_mode 0)
		)
		(polygon
			(pts
				(arc
					(start 93.189044 -385.31038)
					(mid 92.808044 -385.31038)
					(end 93.189044 -385.31038)
				)
			)
		)
	)
	(zone
		(layer "In1.Cu")
		(hatch none 0.5)
		(connect_pads
			(clearance 0)
		)
		(min_thickness 0.25)
		(keepout
			(tracks not_allowed)
			(vias allowed)
			(pads allowed)
			(copperpour not_allowed)
			(footprints allowed)
		)
		(placement
			(enabled no)
			(sheetname "")
		)
		(fill
			(thermal_gap 0.5)
			(thermal_bridge_width 0.5)
			(island_removal_mode 0)
		)
		(polygon
			(pts
				(arc
					(start 52.633372 -203.532486)
					(mid 52.629652 -203.541466)
					(end 52.620672 -203.545186)
				)
				(arc
					(start 51.147472 -203.545186)
					(mid 51.138492 -203.541466)
					(end 51.134772 -203.532486)
				)
				(arc
					(start 51.134772 -203.037948)
					(mid 51.138492 -203.028968)
					(end 51.147472 -203.025248)
				)
				(arc
					(start 52.620672 -203.025248)
					(mid 52.629652 -203.028968)
					(end 52.633372 -203.037948)
				)
			)
		)
	)
	(zone
		(layer "In1.Cu")
		(hatch none 0.5)
		(connect_pads
			(clearance 0)
		)
		(min_thickness 0.25)
		(keepout
			(tracks not_allowed)
			(vias allowed)
			(pads allowed)
			(copperpour not_allowed)
			(footprints allowed)
		)
		(placement
			(enabled no)
			(sheetname "")
		)
		(fill
			(thermal_gap 0.5)
			(thermal_bridge_width 0.5)
			(island_removal_mode 0)
		)
		(polygon
			(pts
				(arc
					(start 266.29741 -243.482114)
					(mid 266.29369 -243.491094)
					(end 266.28471 -243.494814)
				)
				(arc
					(start 264.81151 -243.494814)
					(mid 264.80253 -243.491094)
					(end 264.79881 -243.482114)
				)
				(arc
					(start 264.79881 -242.987576)
					(mid 264.80253 -242.978596)
					(end 264.81151 -242.974876)
				)
				(arc
					(start 266.28471 -242.974876)
					(mid 266.29369 -242.978596)
					(end 266.29741 -242.987576)
				)
			)
		)
	)
	(zone
		(layer "In1.Cu")
		(hatch none 0.5)
		(connect_pads
			(clearance 0)
		)
		(min_thickness 0.25)
		(keepout
			(tracks not_allowed)
			(vias allowed)
			(pads allowed)
			(copperpour not_allowed)
			(footprints allowed)
		)
		(placement
			(enabled no)
			(sheetname "")
		)
		(fill
			(thermal_gap 0.5)
			(thermal_bridge_width 0.5)
			(island_removal_mode 0)
		)
		(polygon
			(pts
				(arc
					(start 37.545264 -274.08251)
					(mid 37.541544 -274.09149)
					(end 37.532564 -274.09521)
				)
				(arc
					(start 36.059364 -274.09521)
					(mid 36.050384 -274.09149)
					(end 36.046664 -274.08251)
				)
				(arc
					(start 36.046664 -273.587972)
					(mid 36.050384 -273.578992)
					(end 36.059364 -273.575272)
				)
				(arc
					(start 37.532564 -273.575272)
					(mid 37.541544 -273.578992)
					(end 37.545264 -273.587972)
				)
			)
		)
	)
	(zone
		(layer "In1.Cu")
		(hatch none 0.5)
		(connect_pads
			(clearance 0)
		)
		(min_thickness 0.25)
		(keepout
			(tracks not_allowed)
			(vias allowed)
			(pads allowed)
			(copperpour not_allowed)
			(footprints allowed)
		)
		(placement
			(enabled no)
			(sheetname "")
		)
		(fill
			(thermal_gap 0.5)
			(thermal_bridge_width 0.5)
			(island_removal_mode 0)
		)
		(polygon
			(pts
				(arc
					(start 439.849514 -306.382166)
					(mid 439.845794 -306.391146)
					(end 439.836814 -306.394866)
				)
				(arc
					(start 438.363614 -306.394866)
					(mid 438.354634 -306.391146)
					(end 438.350914 -306.382166)
				)
				(arc
					(start 438.350914 -305.887628)
					(mid 438.354634 -305.878648)
					(end 438.363614 -305.874928)
				)
				(arc
					(start 439.836814 -305.874928)
					(mid 439.845794 -305.878648)
					(end 439.849514 -305.887628)
				)
			)
		)
	)
	(zone
		(layer "In1.Cu")
		(hatch none 0.5)
		(connect_pads
			(clearance 0)
		)
		(min_thickness 0.25)
		(keepout
			(tracks not_allowed)
			(vias allowed)
			(pads allowed)
			(copperpour not_allowed)
			(footprints allowed)
		)
		(placement
			(enabled no)
			(sheetname "")
		)
		(fill
			(thermal_gap 0.5)
			(thermal_bridge_width 0.5)
			(island_removal_mode 0)
		)
		(polygon
			(pts
				(arc
					(start 25.901396 -226.482402)
					(mid 25.897676 -226.491382)
					(end 25.888696 -226.495102)
				)
				(arc
					(start 24.415496 -226.495102)
					(mid 24.406516 -226.491382)
					(end 24.402796 -226.482402)
				)
				(arc
					(start 24.402796 -225.987864)
					(mid 24.406516 -225.978884)
					(end 24.415496 -225.975164)
				)
				(arc
					(start 25.888696 -225.975164)
					(mid 25.897676 -225.978884)
					(end 25.901396 -225.987864)
				)
			)
		)
	)
	(zone
		(layer "In1.Cu")
		(hatch none 0.5)
		(connect_pads
			(clearance 0)
		)
		(min_thickness 0.25)
		(keepout
			(tracks not_allowed)
			(vias allowed)
			(pads allowed)
			(copperpour not_allowed)
			(footprints allowed)
		)
		(placement
			(enabled no)
			(sheetname "")
		)
		(fill
			(thermal_gap 0.5)
			(thermal_bridge_width 0.5)
			(island_removal_mode 0)
		)
		(polygon
			(pts
				(arc
					(start 40.98925 -253.6825)
					(mid 40.98553 -253.69148)
					(end 40.97655 -253.6952)
				)
				(arc
					(start 39.50335 -253.6952)
					(mid 39.49437 -253.69148)
					(end 39.49065 -253.6825)
				)
				(arc
					(start 39.49065 -253.187962)
					(mid 39.49437 -253.178982)
					(end 39.50335 -253.175262)
				)
				(arc
					(start 40.97655 -253.175262)
					(mid 40.98553 -253.178982)
					(end 40.98925 -253.187962)
				)
			)
		)
	)
	(zone
		(layer "In1.Cu")
		(hatch none 0.5)
		(connect_pads
			(clearance 0)
		)
		(min_thickness 0.25)
		(keepout
			(tracks not_allowed)
			(vias allowed)
			(pads allowed)
			(copperpour not_allowed)
			(footprints allowed)
		)
		(placement
			(enabled no)
			(sheetname "")
		)
		(fill
			(thermal_gap 0.5)
			(thermal_bridge_width 0.5)
			(island_removal_mode 0)
		)
		(polygon
			(pts
				(arc
					(start 450.8373 -293.632128)
					(mid 450.83358 -293.641108)
					(end 450.8246 -293.644828)
				)
				(arc
					(start 449.3514 -293.644828)
					(mid 449.34242 -293.641108)
					(end 449.3387 -293.632128)
				)
				(arc
					(start 449.3387 -293.13759)
					(mid 449.34242 -293.12861)
					(end 449.3514 -293.12489)
				)
				(arc
					(start 450.8246 -293.12489)
					(mid 450.83358 -293.12861)
					(end 450.8373 -293.13759)
				)
			)
		)
	)
	(zone
		(layer "In1.Cu")
		(hatch none 0.5)
		(connect_pads
			(clearance 0)
		)
		(min_thickness 0.25)
		(keepout
			(tracks not_allowed)
			(vias allowed)
			(pads allowed)
			(copperpour not_allowed)
			(footprints allowed)
		)
		(placement
			(enabled no)
			(sheetname "")
		)
		(fill
			(thermal_gap 0.5)
			(thermal_bridge_width 0.5)
			(island_removal_mode 0)
		)
		(polygon
			(pts
				(arc
					(start 417.598098 -392.30427)
					(mid 417.293298 -392.30427)
					(end 417.598098 -392.30427)
				)
			)
		)
	)
	(zone
		(layer "In1.Cu")
		(hatch none 0.5)
		(connect_pads
			(clearance 0)
		)
		(min_thickness 0.25)
		(keepout
			(tracks not_allowed)
			(vias allowed)
			(pads allowed)
			(copperpour not_allowed)
			(footprints allowed)
		)
		(placement
			(enabled no)
			(sheetname "")
		)
		(fill
			(thermal_gap 0.5)
			(thermal_bridge_width 0.5)
			(island_removal_mode 0)
		)
		(polygon
			(pts
				(arc
					(start 15.01013 -107.796076)
					(mid 15.017569 -107.814037)
					(end 15.03553 -107.821476)
				)
				(arc
					(start 15.250668 -107.821476)
					(mid 15.268629 -107.828915)
					(end 15.276068 -107.846876)
				)
				(arc
					(start 15.276068 -107.85602)
					(mid 15.283507 -107.873981)
					(end 15.301468 -107.88142)
				)
				(arc
					(start 15.416276 -107.88142)
					(mid 15.486158 -107.852211)
					(end 15.514828 -107.782106)
				)
				(arc
					(start 15.514828 -107.480862)
					(mid 15.486158 -107.410757)
					(end 15.416276 -107.381548)
				)
				(arc
					(start 15.301468 -107.381548)
					(mid 15.283507 -107.388987)
					(end 15.276068 -107.406948)
				)
				(arc
					(start 15.276068 -107.416092)
					(mid 15.268629 -107.434053)
					(end 15.250668 -107.441492)
				)
				(arc
					(start 15.03553 -107.441492)
					(mid 15.017569 -107.448931)
					(end 15.01013 -107.466892)
				)
			)
		)
	)
	(zone
		(layer "In1.Cu")
		(hatch none 0.5)
		(connect_pads
			(clearance 0)
		)
		(min_thickness 0.25)
		(keepout
			(tracks not_allowed)
			(vias allowed)
			(pads allowed)
			(copperpour not_allowed)
			(footprints allowed)
		)
		(placement
			(enabled no)
			(sheetname "")
		)
		(fill
			(thermal_gap 0.5)
			(thermal_bridge_width 0.5)
			(island_removal_mode 0)
		)
		(polygon
			(pts
				(arc
					(start 443.2935 -285.982156)
					(mid 443.28978 -285.991136)
					(end 443.2808 -285.994856)
				)
				(arc
					(start 441.8076 -285.994856)
					(mid 441.79862 -285.991136)
					(end 441.7949 -285.982156)
				)
				(arc
					(start 441.7949 -285.487618)
					(mid 441.79862 -285.478638)
					(end 441.8076 -285.474918)
				)
				(arc
					(start 443.2808 -285.474918)
					(mid 443.28978 -285.478638)
					(end 443.2935 -285.487618)
				)
			)
		)
	)
	(zone
		(layer "In1.Cu")
		(hatch none 0.5)
		(connect_pads
			(clearance 0)
		)
		(min_thickness 0.25)
		(keepout
			(tracks not_allowed)
			(vias allowed)
			(pads allowed)
			(copperpour not_allowed)
			(footprints allowed)
		)
		(placement
			(enabled no)
			(sheetname "")
		)
		(fill
			(thermal_gap 0.5)
			(thermal_bridge_width 0.5)
			(island_removal_mode 0)
		)
		(polygon
			(pts
				(arc
					(start 435.749446 -304.682144)
					(mid 435.745726 -304.691124)
					(end 435.736746 -304.694844)
				)
				(arc
					(start 434.263546 -304.694844)
					(mid 434.254566 -304.691124)
					(end 434.250846 -304.682144)
				)
				(arc
					(start 434.250846 -304.187606)
					(mid 434.254566 -304.178626)
					(end 434.263546 -304.174906)
				)
				(arc
					(start 435.736746 -304.174906)
					(mid 435.745726 -304.178626)
					(end 435.749446 -304.187606)
				)
			)
		)
	)
	(zone
		(layer "In1.Cu")
		(hatch none 0.5)
		(connect_pads
			(clearance 0)
		)
		(min_thickness 0.25)
		(keepout
			(tracks not_allowed)
			(vias allowed)
			(pads allowed)
			(copperpour not_allowed)
			(footprints allowed)
		)
		(placement
			(enabled no)
			(sheetname "")
		)
		(fill
			(thermal_gap 0.5)
			(thermal_bridge_width 0.5)
			(island_removal_mode 0)
		)
		(polygon
			(pts
				(arc
					(start 296.473372 -297.88231)
					(mid 296.469652 -297.89129)
					(end 296.460672 -297.89501)
				)
				(arc
					(start 294.987472 -297.89501)
					(mid 294.978492 -297.89129)
					(end 294.974772 -297.88231)
				)
				(arc
					(start 294.974772 -297.387772)
					(mid 294.978492 -297.378792)
					(end 294.987472 -297.375072)
				)
				(arc
					(start 296.460672 -297.375072)
					(mid 296.469652 -297.378792)
					(end 296.473372 -297.387772)
				)
			)
		)
	)
	(zone
		(layer "In1.Cu")
		(hatch none 0.5)
		(connect_pads
			(clearance 0)
		)
		(min_thickness 0.25)
		(keepout
			(tracks not_allowed)
			(vias allowed)
			(pads allowed)
			(copperpour not_allowed)
			(footprints allowed)
		)
		(placement
			(enabled no)
			(sheetname "")
		)
		(fill
			(thermal_gap 0.5)
			(thermal_bridge_width 0.5)
			(island_removal_mode 0)
		)
		(polygon
			(pts
				(arc
					(start 435.749446 -284.282134)
					(mid 435.745726 -284.291114)
					(end 435.736746 -284.294834)
				)
				(arc
					(start 434.263546 -284.294834)
					(mid 434.254566 -284.291114)
					(end 434.250846 -284.282134)
				)
				(arc
					(start 434.250846 -283.787596)
					(mid 434.254566 -283.778616)
					(end 434.263546 -283.774896)
				)
				(arc
					(start 435.736746 -283.774896)
					(mid 435.745726 -283.778616)
					(end 435.749446 -283.787596)
				)
			)
		)
	)
	(zone
		(layer "In1.Cu")
		(hatch none 0.5)
		(connect_pads
			(clearance 0)
		)
		(min_thickness 0.25)
		(keepout
			(tracks not_allowed)
			(vias allowed)
			(pads allowed)
			(copperpour not_allowed)
			(footprints allowed)
		)
		(placement
			(enabled no)
			(sheetname "")
		)
		(fill
			(thermal_gap 0.5)
			(thermal_bridge_width 0.5)
			(island_removal_mode 0)
		)
		(polygon
			(pts
				(arc
					(start 432.30546 -200.982326)
					(mid 432.30174 -200.991306)
					(end 432.29276 -200.995026)
				)
				(arc
					(start 430.81956 -200.995026)
					(mid 430.81058 -200.991306)
					(end 430.80686 -200.982326)
				)
				(arc
					(start 430.80686 -200.487788)
					(mid 430.81058 -200.478808)
					(end 430.81956 -200.475088)
				)
				(arc
					(start 432.29276 -200.475088)
					(mid 432.30174 -200.478808)
					(end 432.30546 -200.487788)
				)
			)
		)
	)
	(zone
		(layer "In1.Cu")
		(hatch none 0.5)
		(connect_pads
			(clearance 0)
		)
		(min_thickness 0.25)
		(keepout
			(tracks not_allowed)
			(vias allowed)
			(pads allowed)
			(copperpour not_allowed)
			(footprints allowed)
		)
		(placement
			(enabled no)
			(sheetname "")
		)
		(fill
			(thermal_gap 0.5)
			(thermal_bridge_width 0.5)
			(island_removal_mode 0)
		)
		(polygon
			(pts
				(arc
					(start 176.821338 -313.182508)
					(mid 176.817618 -313.191488)
					(end 176.808638 -313.195208)
				)
				(arc
					(start 175.335438 -313.195208)
					(mid 175.326458 -313.191488)
					(end 175.322738 -313.182508)
				)
				(arc
					(start 175.322738 -312.68797)
					(mid 175.326458 -312.67899)
					(end 175.335438 -312.67527)
				)
				(arc
					(start 176.808638 -312.67527)
					(mid 176.817618 -312.67899)
					(end 176.821338 -312.68797)
				)
			)
		)
	)
	(zone
		(layer "In1.Cu")
		(hatch none 0.5)
		(connect_pads
			(clearance 0)
		)
		(min_thickness 0.25)
		(keepout
			(tracks not_allowed)
			(vias allowed)
			(pads allowed)
			(copperpour not_allowed)
			(footprints allowed)
		)
		(placement
			(enabled no)
			(sheetname "")
		)
		(fill
			(thermal_gap 0.5)
			(thermal_bridge_width 0.5)
			(island_removal_mode 0)
		)
		(polygon
			(pts
				(arc
					(start 206.5782 -250.885198)
					(mid 205.9178 -250.885198)
					(end 206.5782 -250.885198)
				)
			)
		)
	)
	(zone
		(layer "In1.Cu")
		(hatch none 0.5)
		(connect_pads
			(clearance 0)
		)
		(min_thickness 0.25)
		(keepout
			(tracks not_allowed)
			(vias allowed)
			(pads allowed)
			(copperpour not_allowed)
			(footprints allowed)
		)
		(placement
			(enabled no)
			(sheetname "")
		)
		(fill
			(thermal_gap 0.5)
			(thermal_bridge_width 0.5)
			(island_removal_mode 0)
		)
		(polygon
			(pts
				(arc
					(start 45.089318 -208.632552)
					(mid 45.085598 -208.641532)
					(end 45.076618 -208.645252)
				)
				(arc
					(start 43.603418 -208.645252)
					(mid 43.594438 -208.641532)
					(end 43.590718 -208.632552)
				)
				(arc
					(start 43.590718 -208.138014)
					(mid 43.594438 -208.129034)
					(end 43.603418 -208.125314)
				)
				(arc
					(start 45.076618 -208.125314)
					(mid 45.085598 -208.129034)
					(end 45.089318 -208.138014)
				)
			)
		)
	)
	(zone
		(layer "In1.Cu")
		(hatch none 0.5)
		(connect_pads
			(clearance 0)
		)
		(min_thickness 0.25)
		(keepout
			(tracks not_allowed)
			(vias allowed)
			(pads allowed)
			(copperpour not_allowed)
			(footprints allowed)
		)
		(placement
			(enabled no)
			(sheetname "")
		)
		(fill
			(thermal_gap 0.5)
			(thermal_bridge_width 0.5)
			(island_removal_mode 0)
		)
		(polygon
			(pts
				(arc
					(start 293.029386 -309.78221)
					(mid 293.025666 -309.79119)
					(end 293.016686 -309.79491)
				)
				(arc
					(start 291.543486 -309.79491)
					(mid 291.534506 -309.79119)
					(end 291.530786 -309.78221)
				)
				(arc
					(start 291.530786 -309.287672)
					(mid 291.534506 -309.278692)
					(end 291.543486 -309.274972)
				)
				(arc
					(start 293.016686 -309.274972)
					(mid 293.025666 -309.278692)
					(end 293.029386 -309.287672)
				)
			)
		)
	)
	(zone
		(layer "In1.Cu")
		(hatch none 0.5)
		(connect_pads
			(clearance 0)
		)
		(min_thickness 0.25)
		(keepout
			(tracks not_allowed)
			(vias allowed)
			(pads allowed)
			(copperpour not_allowed)
			(footprints allowed)
		)
		(placement
			(enabled no)
			(sheetname "")
		)
		(fill
			(thermal_gap 0.5)
			(thermal_bridge_width 0.5)
			(island_removal_mode 0)
		)
		(polygon
			(pts
				(arc
					(start 129.428494 -33.584388)
					(mid 129.482376 -33.606706)
					(end 129.504694 -33.660588)
				)
				(arc
					(start 129.504694 -34.086038)
					(mid 129.482376 -34.13992)
					(end 129.428494 -34.162238)
				)
				(arc
					(start 128.260094 -34.162238)
					(mid 128.206212 -34.13992)
					(end 128.183894 -34.086038)
				)
				(arc
					(start 128.183894 -33.660588)
					(mid 128.206212 -33.606706)
					(end 128.260094 -33.584388)
				)
			)
		)
	)
	(zone
		(layer "In1.Cu")
		(hatch none 0.5)
		(connect_pads
			(clearance 0)
		)
		(min_thickness 0.25)
		(keepout
			(tracks not_allowed)
			(vias allowed)
			(pads allowed)
			(copperpour not_allowed)
			(footprints allowed)
		)
		(placement
			(enabled no)
			(sheetname "")
		)
		(fill
			(thermal_gap 0.5)
			(thermal_bridge_width 0.5)
			(island_removal_mode 0)
		)
		(polygon
			(pts
				(arc
					(start 266.29741 -273.232118)
					(mid 266.29369 -273.241098)
					(end 266.28471 -273.244818)
				)
				(arc
					(start 264.81151 -273.244818)
					(mid 264.80253 -273.241098)
					(end 264.79881 -273.232118)
				)
				(arc
					(start 264.79881 -272.73758)
					(mid 264.80253 -272.7286)
					(end 264.81151 -272.72488)
				)
				(arc
					(start 266.28471 -272.72488)
					(mid 266.29369 -272.7286)
					(end 266.29741 -272.73758)
				)
			)
		)
	)
	(zone
		(layer "In1.Cu")
		(hatch none 0.5)
		(connect_pads
			(clearance 0)
		)
		(min_thickness 0.25)
		(keepout
			(tracks not_allowed)
			(vias allowed)
			(pads allowed)
			(copperpour not_allowed)
			(footprints allowed)
		)
		(placement
			(enabled no)
			(sheetname "")
		)
		(fill
			(thermal_gap 0.5)
			(thermal_bridge_width 0.5)
			(island_removal_mode 0)
		)
		(polygon
			(pts
				(arc
					(start 180.265324 -285.98241)
					(mid 180.261604 -285.99139)
					(end 180.252624 -285.99511)
				)
				(arc
					(start 178.779424 -285.99511)
					(mid 178.770444 -285.99139)
					(end 178.766724 -285.98241)
				)
				(arc
					(start 178.766724 -285.487872)
					(mid 178.770444 -285.478892)
					(end 178.779424 -285.475172)
				)
				(arc
					(start 180.252624 -285.475172)
					(mid 180.261604 -285.478892)
					(end 180.265324 -285.487872)
				)
			)
		)
	)
	(zone
		(layer "In1.Cu")
		(hatch none 0.5)
		(connect_pads
			(clearance 0)
		)
		(min_thickness 0.25)
		(keepout
			(tracks not_allowed)
			(vias allowed)
			(pads allowed)
			(copperpour not_allowed)
			(footprints allowed)
		)
		(placement
			(enabled no)
			(sheetname "")
		)
		(fill
			(thermal_gap 0.5)
			(thermal_bridge_width 0.5)
			(island_removal_mode 0)
		)
		(polygon
			(pts
				(arc
					(start 435.749446 -282.582112)
					(mid 435.745726 -282.591092)
					(end 435.736746 -282.594812)
				)
				(arc
					(start 434.263546 -282.594812)
					(mid 434.254566 -282.591092)
					(end 434.250846 -282.582112)
				)
				(arc
					(start 434.250846 -282.087574)
					(mid 434.254566 -282.078594)
					(end 434.263546 -282.074874)
				)
				(arc
					(start 435.736746 -282.074874)
					(mid 435.745726 -282.078594)
					(end 435.749446 -282.087574)
				)
			)
		)
	)
	(zone
		(layer "In1.Cu")
		(hatch none 0.5)
		(connect_pads
			(clearance 0)
		)
		(min_thickness 0.25)
		(keepout
			(tracks not_allowed)
			(vias allowed)
			(pads allowed)
			(copperpour not_allowed)
			(footprints allowed)
		)
		(placement
			(enabled no)
			(sheetname "")
		)
		(fill
			(thermal_gap 0.5)
			(thermal_bridge_width 0.5)
			(island_removal_mode 0)
		)
		(polygon
			(pts
				(arc
					(start 48.533304 -218.83243)
					(mid 48.529584 -218.84141)
					(end 48.520604 -218.84513)
				)
				(arc
					(start 47.047404 -218.84513)
					(mid 47.038424 -218.84141)
					(end 47.034704 -218.83243)
				)
				(arc
					(start 47.034704 -218.337892)
					(mid 47.038424 -218.328912)
					(end 47.047404 -218.325192)
				)
				(arc
					(start 48.520604 -218.325192)
					(mid 48.529584 -218.328912)
					(end 48.533304 -218.337892)
				)
			)
		)
	)
	(zone
		(layer "In1.Cu")
		(hatch none 0.5)
		(connect_pads
			(clearance 0)
		)
		(min_thickness 0.25)
		(keepout
			(tracks not_allowed)
			(vias allowed)
			(pads allowed)
			(copperpour not_allowed)
			(footprints allowed)
		)
		(placement
			(enabled no)
			(sheetname "")
		)
		(fill
			(thermal_gap 0.5)
			(thermal_bridge_width 0.5)
			(island_removal_mode 0)
		)
		(polygon
			(pts
				(arc
					(start 343.91854 -391.822686)
					(mid 344.04554 -391.949686)
					(end 344.17254 -391.822686)
				)
				(arc
					(start 344.17254 -391.746486)
					(mid 344.04554 -391.619486)
					(end 343.91854 -391.746486)
				)
			)
		)
	)
	(zone
		(layer "In1.Cu")
		(hatch none 0.5)
		(connect_pads
			(clearance 0)
		)
		(min_thickness 0.25)
		(keepout
			(tracks not_allowed)
			(vias allowed)
			(pads allowed)
			(copperpour not_allowed)
			(footprints allowed)
		)
		(placement
			(enabled no)
			(sheetname "")
		)
		(fill
			(thermal_gap 0.5)
			(thermal_bridge_width 0.5)
			(island_removal_mode 0)
		)
		(polygon
			(pts
				(arc
					(start 435.749446 -285.982156)
					(mid 435.745726 -285.991136)
					(end 435.736746 -285.994856)
				)
				(arc
					(start 434.263546 -285.994856)
					(mid 434.254566 -285.991136)
					(end 434.250846 -285.982156)
				)
				(arc
					(start 434.250846 -285.487618)
					(mid 434.254566 -285.478638)
					(end 434.263546 -285.474918)
				)
				(arc
					(start 435.736746 -285.474918)
					(mid 435.745726 -285.478638)
					(end 435.749446 -285.487618)
				)
			)
		)
	)
	(zone
		(layer "In1.Cu")
		(hatch none 0.5)
		(connect_pads
			(clearance 0)
		)
		(min_thickness 0.25)
		(keepout
			(tracks not_allowed)
			(vias allowed)
			(pads allowed)
			(copperpour not_allowed)
			(footprints allowed)
		)
		(placement
			(enabled no)
			(sheetname "")
		)
		(fill
			(thermal_gap 0.5)
			(thermal_bridge_width 0.5)
			(island_removal_mode 0)
		)
		(polygon
			(pts
				(arc
					(start 347.518482 -399.701258)
					(mid 347.645482 -399.828258)
					(end 347.772482 -399.701258)
				)
				(arc
					(start 347.772482 -399.625058)
					(mid 347.645482 -399.498058)
					(end 347.518482 -399.625058)
				)
			)
		)
	)
	(zone
		(layer "In1.Cu")
		(hatch none 0.5)
		(connect_pads
			(clearance 0)
		)
		(min_thickness 0.25)
		(keepout
			(tracks not_allowed)
			(vias allowed)
			(pads allowed)
			(copperpour not_allowed)
			(footprints allowed)
		)
		(placement
			(enabled no)
			(sheetname "")
		)
		(fill
			(thermal_gap 0.5)
			(thermal_bridge_width 0.5)
			(island_removal_mode 0)
		)
		(polygon
			(pts
				(arc
					(start 281.385264 -228.18217)
					(mid 281.381544 -228.19115)
					(end 281.372564 -228.19487)
				)
				(arc
					(start 279.899364 -228.19487)
					(mid 279.890384 -228.19115)
					(end 279.886664 -228.18217)
				)
				(arc
					(start 279.886664 -227.687632)
					(mid 279.890384 -227.678652)
					(end 279.899364 -227.674932)
				)
				(arc
					(start 281.372564 -227.674932)
					(mid 281.381544 -227.678652)
					(end 281.385264 -227.687632)
				)
			)
		)
	)
	(zone
		(layer "In1.Cu")
		(hatch none 0.5)
		(connect_pads
			(clearance 0)
		)
		(min_thickness 0.25)
		(keepout
			(tracks not_allowed)
			(vias allowed)
			(pads allowed)
			(copperpour not_allowed)
			(footprints allowed)
		)
		(placement
			(enabled no)
			(sheetname "")
		)
		(fill
			(thermal_gap 0.5)
			(thermal_bridge_width 0.5)
			(island_removal_mode 0)
		)
		(polygon
			(pts
				(arc
					(start 428.205392 -237.532164)
					(mid 428.201672 -237.541144)
					(end 428.192692 -237.544864)
				)
				(arc
					(start 426.719492 -237.544864)
					(mid 426.710512 -237.541144)
					(end 426.706792 -237.532164)
				)
				(arc
					(start 426.706792 -237.037626)
					(mid 426.710512 -237.028646)
					(end 426.719492 -237.024926)
				)
				(arc
					(start 428.192692 -237.024926)
					(mid 428.201672 -237.028646)
					(end 428.205392 -237.037626)
				)
			)
		)
	)
	(zone
		(layer "In1.Cu")
		(hatch none 0.5)
		(connect_pads
			(clearance 0)
		)
		(min_thickness 0.25)
		(keepout
			(tracks not_allowed)
			(vias allowed)
			(pads allowed)
			(copperpour not_allowed)
			(footprints allowed)
		)
		(placement
			(enabled no)
			(sheetname "")
		)
		(fill
			(thermal_gap 0.5)
			(thermal_bridge_width 0.5)
			(island_removal_mode 0)
		)
		(polygon
			(pts
				(arc
					(start 443.2935 -263.882124)
					(mid 443.28978 -263.891104)
					(end 443.2808 -263.894824)
				)
				(arc
					(start 441.8076 -263.894824)
					(mid 441.79862 -263.891104)
					(end 441.7949 -263.882124)
				)
				(arc
					(start 441.7949 -263.387586)
					(mid 441.79862 -263.378606)
					(end 441.8076 -263.374886)
				)
				(arc
					(start 443.2808 -263.374886)
					(mid 443.28978 -263.378606)
					(end 443.2935 -263.387586)
				)
			)
		)
	)
	(zone
		(layer "In1.Cu")
		(hatch none 0.5)
		(connect_pads
			(clearance 0)
		)
		(min_thickness 0.25)
		(keepout
			(tracks not_allowed)
			(vias allowed)
			(pads allowed)
			(copperpour not_allowed)
			(footprints allowed)
		)
		(placement
			(enabled no)
			(sheetname "")
		)
		(fill
			(thermal_gap 0.5)
			(thermal_bridge_width 0.5)
			(island_removal_mode 0)
		)
		(polygon
			(pts
				(arc
					(start 314.260992 -393.69238)
					(mid 313.879992 -393.69238)
					(end 314.260992 -393.69238)
				)
			)
		)
	)
	(zone
		(layer "In1.Cu")
		(hatch none 0.5)
		(connect_pads
			(clearance 0)
		)
		(min_thickness 0.25)
		(keepout
			(tracks not_allowed)
			(vias allowed)
			(pads allowed)
			(copperpour not_allowed)
			(footprints allowed)
		)
		(placement
			(enabled no)
			(sheetname "")
		)
		(fill
			(thermal_gap 0.5)
			(thermal_bridge_width 0.5)
			(island_removal_mode 0)
		)
		(polygon
			(pts
				(arc
					(start 428.205392 -307.232304)
					(mid 428.201672 -307.241284)
					(end 428.192692 -307.245004)
				)
				(arc
					(start 426.719492 -307.245004)
					(mid 426.710512 -307.241284)
					(end 426.706792 -307.232304)
				)
				(arc
					(start 426.706792 -306.737766)
					(mid 426.710512 -306.728786)
					(end 426.719492 -306.725066)
				)
				(arc
					(start 428.192692 -306.725066)
					(mid 428.201672 -306.728786)
					(end 428.205392 -306.737766)
				)
			)
		)
	)
	(zone
		(layer "In1.Cu")
		(hatch none 0.5)
		(connect_pads
			(clearance 0)
		)
		(min_thickness 0.25)
		(keepout
			(tracks not_allowed)
			(vias allowed)
			(pads allowed)
			(copperpour not_allowed)
			(footprints allowed)
		)
		(placement
			(enabled no)
			(sheetname "")
		)
		(fill
			(thermal_gap 0.5)
			(thermal_bridge_width 0.5)
			(island_removal_mode 0)
		)
		(polygon
			(pts
				(arc
					(start 281.385264 -263.882124)
					(mid 281.381544 -263.891104)
					(end 281.372564 -263.894824)
				)
				(arc
					(start 279.899364 -263.894824)
					(mid 279.890384 -263.891104)
					(end 279.886664 -263.882124)
				)
				(arc
					(start 279.886664 -263.387586)
					(mid 279.890384 -263.378606)
					(end 279.899364 -263.374886)
				)
				(arc
					(start 281.372564 -263.374886)
					(mid 281.381544 -263.378606)
					(end 281.385264 -263.387586)
				)
			)
		)
	)
	(zone
		(layer "In1.Cu")
		(hatch none 0.5)
		(connect_pads
			(clearance 0)
		)
		(min_thickness 0.25)
		(keepout
			(tracks not_allowed)
			(vias allowed)
			(pads allowed)
			(copperpour not_allowed)
			(footprints allowed)
		)
		(placement
			(enabled no)
			(sheetname "")
		)
		(fill
			(thermal_gap 0.5)
			(thermal_bridge_width 0.5)
			(island_removal_mode 0)
		)
		(polygon
			(pts
				(arc
					(start 288.929318 -220.532198)
					(mid 288.925598 -220.541178)
					(end 288.916618 -220.544898)
				)
				(arc
					(start 287.443418 -220.544898)
					(mid 287.434438 -220.541178)
					(end 287.430718 -220.532198)
				)
				(arc
					(start 287.430718 -220.03766)
					(mid 287.434438 -220.02868)
					(end 287.443418 -220.02496)
				)
				(arc
					(start 288.916618 -220.02496)
					(mid 288.925598 -220.02868)
					(end 288.929318 -220.03766)
				)
			)
		)
	)
	(zone
		(layer "In1.Cu")
		(hatch none 0.5)
		(connect_pads
			(clearance 0)
		)
		(min_thickness 0.25)
		(keepout
			(tracks not_allowed)
			(vias allowed)
			(pads allowed)
			(copperpour not_allowed)
			(footprints allowed)
		)
		(placement
			(enabled no)
			(sheetname "")
		)
		(fill
			(thermal_gap 0.5)
			(thermal_bridge_width 0.5)
			(island_removal_mode 0)
		)
		(polygon
			(pts
				(arc
					(start 293.029386 -234.982258)
					(mid 293.025666 -234.991238)
					(end 293.016686 -234.994958)
				)
				(arc
					(start 291.543486 -234.994958)
					(mid 291.534506 -234.991238)
					(end 291.530786 -234.982258)
				)
				(arc
					(start 291.530786 -234.48772)
					(mid 291.534506 -234.47874)
					(end 291.543486 -234.47502)
				)
				(arc
					(start 293.016686 -234.47502)
					(mid 293.025666 -234.47874)
					(end 293.029386 -234.48772)
				)
			)
		)
	)
	(zone
		(layer "In1.Cu")
		(hatch none 0.5)
		(connect_pads
			(clearance 0)
		)
		(min_thickness 0.25)
		(keepout
			(tracks not_allowed)
			(vias allowed)
			(pads allowed)
			(copperpour not_allowed)
			(footprints allowed)
		)
		(placement
			(enabled no)
			(sheetname "")
		)
		(fill
			(thermal_gap 0.5)
			(thermal_bridge_width 0.5)
			(island_removal_mode 0)
		)
		(polygon
			(pts
				(arc
					(start 266.29741 -279.182322)
					(mid 266.29369 -279.191302)
					(end 266.28471 -279.195022)
				)
				(arc
					(start 264.81151 -279.195022)
					(mid 264.80253 -279.191302)
					(end 264.79881 -279.182322)
				)
				(arc
					(start 264.79881 -278.687784)
					(mid 264.80253 -278.678804)
					(end 264.81151 -278.675084)
				)
				(arc
					(start 266.28471 -278.675084)
					(mid 266.29369 -278.678804)
					(end 266.29741 -278.687784)
				)
			)
		)
	)
	(zone
		(layer "In1.Cu")
		(hatch none 0.5)
		(connect_pads
			(clearance 0)
		)
		(min_thickness 0.25)
		(keepout
			(tracks not_allowed)
			(vias allowed)
			(pads allowed)
			(copperpour not_allowed)
			(footprints allowed)
		)
		(placement
			(enabled no)
			(sheetname "")
		)
		(fill
			(thermal_gap 0.5)
			(thermal_bridge_width 0.5)
			(island_removal_mode 0)
		)
		(polygon
			(pts
				(arc
					(start 281.385264 -308.932326)
					(mid 281.381544 -308.941306)
					(end 281.372564 -308.945026)
				)
				(arc
					(start 279.899364 -308.945026)
					(mid 279.890384 -308.941306)
					(end 279.886664 -308.932326)
				)
				(arc
					(start 279.886664 -308.437788)
					(mid 279.890384 -308.428808)
					(end 279.899364 -308.425088)
				)
				(arc
					(start 281.372564 -308.425088)
					(mid 281.381544 -308.428808)
					(end 281.385264 -308.437788)
				)
			)
		)
	)
	(zone
		(layer "In1.Cu")
		(hatch none 0.5)
		(connect_pads
			(clearance 0)
		)
		(min_thickness 0.25)
		(keepout
			(tracks not_allowed)
			(vias allowed)
			(pads allowed)
			(copperpour not_allowed)
			(footprints allowed)
		)
		(placement
			(enabled no)
			(sheetname "")
		)
		(fill
			(thermal_gap 0.5)
			(thermal_bridge_width 0.5)
			(island_removal_mode 0)
		)
		(polygon
			(pts
				(arc
					(start 116.491004 -383.440686)
					(mid 116.618004 -383.567686)
					(end 116.745004 -383.440686)
				)
				(arc
					(start 116.745004 -383.364486)
					(mid 116.618004 -383.237486)
					(end 116.491004 -383.364486)
				)
			)
		)
	)
	(zone
		(layer "In1.Cu")
		(hatch none 0.5)
		(connect_pads
			(clearance 0)
		)
		(min_thickness 0.25)
		(keepout
			(tracks not_allowed)
			(vias allowed)
			(pads allowed)
			(copperpour not_allowed)
			(footprints allowed)
		)
		(placement
			(enabled no)
			(sheetname "")
		)
		(fill
			(thermal_gap 0.5)
			(thermal_bridge_width 0.5)
			(island_removal_mode 0)
		)
		(polygon
			(pts
				(arc
					(start 60.177426 -276.632416)
					(mid 60.173706 -276.641396)
					(end 60.164726 -276.645116)
				)
				(arc
					(start 58.691526 -276.645116)
					(mid 58.682546 -276.641396)
					(end 58.678826 -276.632416)
				)
				(arc
					(start 58.678826 -276.137878)
					(mid 58.682546 -276.128898)
					(end 58.691526 -276.125178)
				)
				(arc
					(start 60.164726 -276.125178)
					(mid 60.173706 -276.128898)
					(end 60.177426 -276.137878)
				)
			)
		)
	)
	(zone
		(layer "In1.Cu")
		(hatch none 0.5)
		(connect_pads
			(clearance 0)
		)
		(min_thickness 0.25)
		(keepout
			(tracks not_allowed)
			(vias allowed)
			(pads allowed)
			(copperpour not_allowed)
			(footprints allowed)
		)
		(placement
			(enabled no)
			(sheetname "")
		)
		(fill
			(thermal_gap 0.5)
			(thermal_bridge_width 0.5)
			(island_removal_mode 0)
		)
		(polygon
			(pts
				(arc
					(start 33.445196 -206.082392)
					(mid 33.441476 -206.091372)
					(end 33.432496 -206.095092)
				)
				(arc
					(start 31.959296 -206.095092)
					(mid 31.950316 -206.091372)
					(end 31.946596 -206.082392)
				)
				(arc
					(start 31.946596 -205.587854)
					(mid 31.950316 -205.578874)
					(end 31.959296 -205.575154)
				)
				(arc
					(start 33.432496 -205.575154)
					(mid 33.441476 -205.578874)
					(end 33.445196 -205.587854)
				)
			)
		)
	)
	(zone
		(layer "In1.Cu")
		(hatch none 0.5)
		(connect_pads
			(clearance 0)
		)
		(min_thickness 0.25)
		(keepout
			(tracks not_allowed)
			(vias allowed)
			(pads allowed)
			(copperpour not_allowed)
			(footprints allowed)
		)
		(placement
			(enabled no)
			(sheetname "")
		)
		(fill
			(thermal_gap 0.5)
			(thermal_bridge_width 0.5)
			(island_removal_mode 0)
		)
		(polygon
			(pts
				(arc
					(start 52.370482 -390.761474)
					(mid 52.065682 -390.761474)
					(end 52.370482 -390.761474)
				)
			)
		)
	)
	(zone
		(layer "In1.Cu")
		(hatch none 0.5)
		(connect_pads
			(clearance 0)
		)
		(min_thickness 0.25)
		(keepout
			(tracks not_allowed)
			(vias allowed)
			(pads allowed)
			(copperpour not_allowed)
			(footprints allowed)
		)
		(placement
			(enabled no)
			(sheetname "")
		)
		(fill
			(thermal_gap 0.5)
			(thermal_bridge_width 0.5)
			(island_removal_mode 0)
		)
		(polygon
			(pts
				(arc
					(start 413.117284 -307.232304)
					(mid 413.113564 -307.241284)
					(end 413.104584 -307.245004)
				)
				(arc
					(start 411.631384 -307.245004)
					(mid 411.622404 -307.241284)
					(end 411.618684 -307.232304)
				)
				(arc
					(start 411.618684 -306.737766)
					(mid 411.622404 -306.728786)
					(end 411.631384 -306.725066)
				)
				(arc
					(start 413.104584 -306.725066)
					(mid 413.113564 -306.728786)
					(end 413.117284 -306.737766)
				)
			)
		)
	)
	(zone
		(layer "In1.Cu")
		(hatch none 0.5)
		(connect_pads
			(clearance 0)
		)
		(min_thickness 0.25)
		(keepout
			(tracks not_allowed)
			(vias allowed)
			(pads allowed)
			(copperpour not_allowed)
			(footprints allowed)
		)
		(placement
			(enabled no)
			(sheetname "")
		)
		(fill
			(thermal_gap 0.5)
			(thermal_bridge_width 0.5)
			(island_removal_mode 0)
		)
		(polygon
			(pts
				(arc
					(start 56.077358 -251.982478)
					(mid 56.073638 -251.991458)
					(end 56.064658 -251.995178)
				)
				(arc
					(start 54.591458 -251.995178)
					(mid 54.582478 -251.991458)
					(end 54.578758 -251.982478)
				)
				(arc
					(start 54.578758 -251.48794)
					(mid 54.582478 -251.47896)
					(end 54.591458 -251.47524)
				)
				(arc
					(start 56.064658 -251.47524)
					(mid 56.073638 -251.47896)
					(end 56.077358 -251.48794)
				)
			)
		)
	)
	(zone
		(layer "In1.Cu")
		(hatch none 0.5)
		(connect_pads
			(clearance 0)
		)
		(min_thickness 0.25)
		(keepout
			(tracks not_allowed)
			(vias allowed)
			(pads allowed)
			(copperpour not_allowed)
			(footprints allowed)
		)
		(placement
			(enabled no)
			(sheetname "")
		)
		(fill
			(thermal_gap 0.5)
			(thermal_bridge_width 0.5)
			(island_removal_mode 0)
		)
		(polygon
			(pts
				(arc
					(start 416.288982 -397.156432)
					(mid 415.907982 -397.156432)
					(end 416.288982 -397.156432)
				)
			)
		)
	)
	(zone
		(layer "In1.Cu")
		(hatch none 0.5)
		(connect_pads
			(clearance 0)
		)
		(min_thickness 0.25)
		(keepout
			(tracks not_allowed)
			(vias allowed)
			(pads allowed)
			(copperpour not_allowed)
			(footprints allowed)
		)
		(placement
			(enabled no)
			(sheetname "")
		)
		(fill
			(thermal_gap 0.5)
			(thermal_bridge_width 0.5)
			(island_removal_mode 0)
		)
		(polygon
			(pts
				(arc
					(start 435.749446 -262.182102)
					(mid 435.745726 -262.191082)
					(end 435.736746 -262.194802)
				)
				(arc
					(start 434.263546 -262.194802)
					(mid 434.254566 -262.191082)
					(end 434.250846 -262.182102)
				)
				(arc
					(start 434.250846 -261.687564)
					(mid 434.254566 -261.678584)
					(end 434.263546 -261.674864)
				)
				(arc
					(start 435.736746 -261.674864)
					(mid 435.745726 -261.678584)
					(end 435.749446 -261.687564)
				)
			)
		)
	)
	(zone
		(layer "In1.Cu")
		(hatch none 0.5)
		(connect_pads
			(clearance 0)
		)
		(min_thickness 0.25)
		(keepout
			(tracks not_allowed)
			(vias allowed)
			(pads allowed)
			(copperpour not_allowed)
			(footprints allowed)
		)
		(placement
			(enabled no)
			(sheetname "")
		)
		(fill
			(thermal_gap 0.5)
			(thermal_bridge_width 0.5)
			(island_removal_mode 0)
		)
		(polygon
			(pts
				(arc
					(start 277.941532 -208.632298)
					(mid 277.937812 -208.641278)
					(end 277.928832 -208.644998)
				)
				(arc
					(start 276.455632 -208.644998)
					(mid 276.446652 -208.641278)
					(end 276.442932 -208.632298)
				)
				(arc
					(start 276.442932 -208.13776)
					(mid 276.446652 -208.12878)
					(end 276.455632 -208.12506)
				)
				(arc
					(start 277.928832 -208.12506)
					(mid 277.937812 -208.12878)
					(end 277.941532 -208.13776)
				)
			)
		)
	)
	(zone
		(layer "In1.Cu")
		(hatch none 0.5)
		(connect_pads
			(clearance 0)
		)
		(min_thickness 0.25)
		(keepout
			(tracks not_allowed)
			(vias allowed)
			(pads allowed)
			(copperpour not_allowed)
			(footprints allowed)
		)
		(placement
			(enabled no)
			(sheetname "")
		)
		(fill
			(thermal_gap 0.5)
			(thermal_bridge_width 0.5)
			(island_removal_mode 0)
		)
		(polygon
			(pts
				(arc
					(start 202.897232 -302.982376)
					(mid 202.893512 -302.991356)
					(end 202.884532 -302.995076)
				)
				(arc
					(start 201.411332 -302.995076)
					(mid 201.402352 -302.991356)
					(end 201.398632 -302.982376)
				)
				(arc
					(start 201.398632 -302.487838)
					(mid 201.402352 -302.478858)
					(end 201.411332 -302.475138)
				)
				(arc
					(start 202.884532 -302.475138)
					(mid 202.893512 -302.478858)
					(end 202.897232 -302.487838)
				)
			)
		)
	)
	(zone
		(layer "In1.Cu")
		(hatch none 0.5)
		(connect_pads
			(clearance 0)
		)
		(min_thickness 0.25)
		(keepout
			(tracks not_allowed)
			(vias allowed)
			(pads allowed)
			(copperpour not_allowed)
			(footprints allowed)
		)
		(placement
			(enabled no)
			(sheetname "")
		)
		(fill
			(thermal_gap 0.5)
			(thermal_bridge_width 0.5)
			(island_removal_mode 0)
		)
		(polygon
			(pts
				(arc
					(start 417.217352 -294.482266)
					(mid 417.213632 -294.491246)
					(end 417.204652 -294.494966)
				)
				(arc
					(start 415.731452 -294.494966)
					(mid 415.722472 -294.491246)
					(end 415.718752 -294.482266)
				)
				(arc
					(start 415.718752 -293.987728)
					(mid 415.722472 -293.978748)
					(end 415.731452 -293.975028)
				)
				(arc
					(start 417.204652 -293.975028)
					(mid 417.213632 -293.978748)
					(end 417.217352 -293.987728)
				)
			)
		)
	)
	(zone
		(layer "In1.Cu")
		(hatch none 0.5)
		(connect_pads
			(clearance 0)
		)
		(min_thickness 0.25)
		(keepout
			(tracks not_allowed)
			(vias allowed)
			(pads allowed)
			(copperpour not_allowed)
			(footprints allowed)
		)
		(placement
			(enabled no)
			(sheetname "")
		)
		(fill
			(thermal_gap 0.5)
			(thermal_bridge_width 0.5)
			(island_removal_mode 0)
		)
		(polygon
			(pts
				(arc
					(start 45.089318 -285.98241)
					(mid 45.085598 -285.99139)
					(end 45.076618 -285.99511)
				)
				(arc
					(start 43.603418 -285.99511)
					(mid 43.594438 -285.99139)
					(end 43.590718 -285.98241)
				)
				(arc
					(start 43.590718 -285.487872)
					(mid 43.594438 -285.478892)
					(end 43.603418 -285.475172)
				)
				(arc
					(start 45.076618 -285.475172)
					(mid 45.085598 -285.478892)
					(end 45.089318 -285.487872)
				)
			)
		)
	)
	(zone
		(layer "In1.Cu")
		(hatch none 0.5)
		(connect_pads
			(clearance 0)
		)
		(min_thickness 0.25)
		(keepout
			(tracks not_allowed)
			(vias allowed)
			(pads allowed)
			(copperpour not_allowed)
			(footprints allowed)
		)
		(placement
			(enabled no)
			(sheetname "")
		)
		(fill
			(thermal_gap 0.5)
			(thermal_bridge_width 0.5)
			(island_removal_mode 0)
		)
		(polygon
			(pts
				(arc
					(start 270.397478 -222.23222)
					(mid 270.393758 -222.2412)
					(end 270.384778 -222.24492)
				)
				(arc
					(start 268.911578 -222.24492)
					(mid 268.902598 -222.2412)
					(end 268.898878 -222.23222)
				)
				(arc
					(start 268.898878 -221.737682)
					(mid 268.902598 -221.728702)
					(end 268.911578 -221.724982)
				)
				(arc
					(start 270.384778 -221.724982)
					(mid 270.393758 -221.728702)
					(end 270.397478 -221.737682)
				)
			)
		)
	)
	(zone
		(layer "In1.Cu")
		(hatch none 0.5)
		(connect_pads
			(clearance 0)
		)
		(min_thickness 0.25)
		(keepout
			(tracks not_allowed)
			(vias allowed)
			(pads allowed)
			(copperpour not_allowed)
			(footprints allowed)
		)
		(placement
			(enabled no)
			(sheetname "")
		)
		(fill
			(thermal_gap 0.5)
			(thermal_bridge_width 0.5)
			(island_removal_mode 0)
		)
		(polygon
			(pts
				(arc
					(start 169.277284 -233.28249)
					(mid 169.273564 -233.29147)
					(end 169.264584 -233.29519)
				)
				(arc
					(start 167.791384 -233.29519)
					(mid 167.782404 -233.29147)
					(end 167.778684 -233.28249)
				)
				(arc
					(start 167.778684 -232.787952)
					(mid 167.782404 -232.778972)
					(end 167.791384 -232.775252)
				)
				(arc
					(start 169.264584 -232.775252)
					(mid 169.273564 -232.778972)
					(end 169.277284 -232.787952)
				)
			)
		)
	)
	(zone
		(layer "In1.Cu")
		(hatch none 0.5)
		(connect_pads
			(clearance 0)
		)
		(min_thickness 0.25)
		(keepout
			(tracks not_allowed)
			(vias allowed)
			(pads allowed)
			(copperpour not_allowed)
			(footprints allowed)
		)
		(placement
			(enabled no)
			(sheetname "")
		)
		(fill
			(thermal_gap 0.5)
			(thermal_bridge_width 0.5)
			(island_removal_mode 0)
		)
		(polygon
			(pts
				(arc
					(start 172.72127 -202.682348)
					(mid 172.71755 -202.691328)
					(end 172.70857 -202.695048)
				)
				(arc
					(start 171.23537 -202.695048)
					(mid 171.22639 -202.691328)
					(end 171.22267 -202.682348)
				)
				(arc
					(start 171.22267 -202.18781)
					(mid 171.22639 -202.17883)
					(end 171.23537 -202.17511)
				)
				(arc
					(start 172.70857 -202.17511)
					(mid 172.71755 -202.17883)
					(end 172.72127 -202.18781)
				)
			)
		)
	)
	(zone
		(layer "In1.Cu")
		(hatch none 0.5)
		(connect_pads
			(clearance 0)
		)
		(min_thickness 0.25)
		(keepout
			(tracks not_allowed)
			(vias allowed)
			(pads allowed)
			(copperpour not_allowed)
			(footprints allowed)
		)
		(placement
			(enabled no)
			(sheetname "")
		)
		(fill
			(thermal_gap 0.5)
			(thermal_bridge_width 0.5)
			(island_removal_mode 0)
		)
		(polygon
			(pts
				(arc
					(start 169.277284 -306.38242)
					(mid 169.273564 -306.3914)
					(end 169.264584 -306.39512)
				)
				(arc
					(start 167.791384 -306.39512)
					(mid 167.782404 -306.3914)
					(end 167.778684 -306.38242)
				)
				(arc
					(start 167.778684 -305.887882)
					(mid 167.782404 -305.878902)
					(end 167.791384 -305.875182)
				)
				(arc
					(start 169.264584 -305.875182)
					(mid 169.273564 -305.878902)
					(end 169.277284 -305.887882)
				)
			)
		)
	)
	(zone
		(layer "In1.Cu")
		(hatch none 0.5)
		(connect_pads
			(clearance 0)
		)
		(min_thickness 0.25)
		(keepout
			(tracks not_allowed)
			(vias allowed)
			(pads allowed)
			(copperpour not_allowed)
			(footprints allowed)
		)
		(placement
			(enabled no)
			(sheetname "")
		)
		(fill
			(thermal_gap 0.5)
			(thermal_bridge_width 0.5)
			(island_removal_mode 0)
		)
		(polygon
			(pts
				(arc
					(start 52.633372 -206.93253)
					(mid 52.629652 -206.94151)
					(end 52.620672 -206.94523)
				)
				(arc
					(start 51.147472 -206.94523)
					(mid 51.138492 -206.94151)
					(end 51.134772 -206.93253)
				)
				(arc
					(start 51.134772 -206.437992)
					(mid 51.138492 -206.429012)
					(end 51.147472 -206.425292)
				)
				(arc
					(start 52.620672 -206.425292)
					(mid 52.629652 -206.429012)
					(end 52.633372 -206.437992)
				)
			)
		)
	)
	(zone
		(layer "In1.Cu")
		(hatch none 0.5)
		(connect_pads
			(clearance 0)
		)
		(min_thickness 0.25)
		(keepout
			(tracks not_allowed)
			(vias allowed)
			(pads allowed)
			(copperpour not_allowed)
			(footprints allowed)
		)
		(placement
			(enabled no)
			(sheetname "")
		)
		(fill
			(thermal_gap 0.5)
			(thermal_bridge_width 0.5)
			(island_removal_mode 0)
		)
		(polygon
			(pts
				(arc
					(start 376.961146 -397.849344)
					(mid 376.580146 -397.849344)
					(end 376.961146 -397.849344)
				)
			)
		)
	)
	(zone
		(layer "In1.Cu")
		(hatch none 0.5)
		(connect_pads
			(clearance 0)
		)
		(min_thickness 0.25)
		(keepout
			(tracks not_allowed)
			(vias allowed)
			(pads allowed)
			(copperpour not_allowed)
			(footprints allowed)
		)
		(placement
			(enabled no)
			(sheetname "")
		)
		(fill
			(thermal_gap 0.5)
			(thermal_bridge_width 0.5)
			(island_removal_mode 0)
		)
		(polygon
			(pts
				(arc
					(start 293.029386 -292.782244)
					(mid 293.025666 -292.791224)
					(end 293.016686 -292.794944)
				)
				(arc
					(start 291.543486 -292.794944)
					(mid 291.534506 -292.791224)
					(end 291.530786 -292.782244)
				)
				(arc
					(start 291.530786 -292.287706)
					(mid 291.534506 -292.278726)
					(end 291.543486 -292.275006)
				)
				(arc
					(start 293.016686 -292.275006)
					(mid 293.025666 -292.278726)
					(end 293.029386 -292.287706)
				)
			)
		)
	)
	(zone
		(layer "In1.Cu")
		(hatch none 0.5)
		(connect_pads
			(clearance 0)
		)
		(min_thickness 0.25)
		(keepout
			(tracks not_allowed)
			(vias allowed)
			(pads allowed)
			(copperpour not_allowed)
			(footprints allowed)
		)
		(placement
			(enabled no)
			(sheetname "")
		)
		(fill
			(thermal_gap 0.5)
			(thermal_bridge_width 0.5)
			(island_removal_mode 0)
		)
		(polygon
			(pts
				(arc
					(start 428.205392 -213.73211)
					(mid 428.201672 -213.74109)
					(end 428.192692 -213.74481)
				)
				(arc
					(start 426.719492 -213.74481)
					(mid 426.710512 -213.74109)
					(end 426.706792 -213.73211)
				)
				(arc
					(start 426.706792 -213.237572)
					(mid 426.710512 -213.228592)
					(end 426.719492 -213.224872)
				)
				(arc
					(start 428.192692 -213.224872)
					(mid 428.201672 -213.228592)
					(end 428.205392 -213.237572)
				)
			)
		)
	)
	(zone
		(layer "In1.Cu")
		(hatch none 0.5)
		(connect_pads
			(clearance 0)
		)
		(min_thickness 0.25)
		(keepout
			(tracks not_allowed)
			(vias allowed)
			(pads allowed)
			(copperpour not_allowed)
			(footprints allowed)
		)
		(placement
			(enabled no)
			(sheetname "")
		)
		(fill
			(thermal_gap 0.5)
			(thermal_bridge_width 0.5)
			(island_removal_mode 0)
		)
		(polygon
			(pts
				(arc
					(start 184.365392 -211.182458)
					(mid 184.361672 -211.191438)
					(end 184.352692 -211.195158)
				)
				(arc
					(start 182.879492 -211.195158)
					(mid 182.870512 -211.191438)
					(end 182.866792 -211.182458)
				)
				(arc
					(start 182.866792 -210.68792)
					(mid 182.870512 -210.67894)
					(end 182.879492 -210.67522)
				)
				(arc
					(start 184.352692 -210.67522)
					(mid 184.361672 -210.67894)
					(end 184.365392 -210.68792)
				)
			)
		)
	)
	(zone
		(layer "In1.Cu")
		(hatch none 0.5)
		(connect_pads
			(clearance 0)
		)
		(min_thickness 0.25)
		(keepout
			(tracks not_allowed)
			(vias allowed)
			(pads allowed)
			(copperpour not_allowed)
			(footprints allowed)
		)
		(placement
			(enabled no)
			(sheetname "")
		)
		(fill
			(thermal_gap 0.5)
			(thermal_bridge_width 0.5)
			(island_removal_mode 0)
		)
		(polygon
			(pts
				(arc
					(start 184.365392 -317.432436)
					(mid 184.361672 -317.441416)
					(end 184.352692 -317.445136)
				)
				(arc
					(start 182.879492 -317.445136)
					(mid 182.870512 -317.441416)
					(end 182.866792 -317.432436)
				)
				(arc
					(start 182.866792 -316.937898)
					(mid 182.870512 -316.928918)
					(end 182.879492 -316.925198)
				)
				(arc
					(start 184.352692 -316.925198)
					(mid 184.361672 -316.928918)
					(end 184.365392 -316.937898)
				)
			)
		)
	)
	(zone
		(layer "In1.Cu")
		(hatch none 0.5)
		(connect_pads
			(clearance 0)
		)
		(min_thickness 0.25)
		(keepout
			(tracks not_allowed)
			(vias allowed)
			(pads allowed)
			(copperpour not_allowed)
			(footprints allowed)
		)
		(placement
			(enabled no)
			(sheetname "")
		)
		(fill
			(thermal_gap 0.5)
			(thermal_bridge_width 0.5)
			(island_removal_mode 0)
		)
		(polygon
			(pts
				(arc
					(start 304.661062 -393.69238)
					(mid 304.280062 -393.69238)
					(end 304.661062 -393.69238)
				)
			)
		)
	)
	(zone
		(layer "In1.Cu")
		(hatch none 0.5)
		(connect_pads
			(clearance 0)
		)
		(min_thickness 0.25)
		(keepout
			(tracks not_allowed)
			(vias allowed)
			(pads allowed)
			(copperpour not_allowed)
			(footprints allowed)
		)
		(placement
			(enabled no)
			(sheetname "")
		)
		(fill
			(thermal_gap 0.5)
			(thermal_bridge_width 0.5)
			(island_removal_mode 0)
		)
		(polygon
			(pts
				(arc
					(start 22.45741 -283.432504)
					(mid 22.45369 -283.441484)
					(end 22.44471 -283.445204)
				)
				(arc
					(start 20.97151 -283.445204)
					(mid 20.96253 -283.441484)
					(end 20.95881 -283.432504)
				)
				(arc
					(start 20.95881 -282.937966)
					(mid 20.96253 -282.928986)
					(end 20.97151 -282.925266)
				)
				(arc
					(start 22.44471 -282.925266)
					(mid 22.45369 -282.928986)
					(end 22.45741 -282.937966)
				)
			)
		)
	)
	(zone
		(layer "In1.Cu")
		(hatch none 0.5)
		(connect_pads
			(clearance 0)
		)
		(min_thickness 0.25)
		(keepout
			(tracks not_allowed)
			(vias allowed)
			(pads allowed)
			(copperpour not_allowed)
			(footprints allowed)
		)
		(placement
			(enabled no)
			(sheetname "")
		)
		(fill
			(thermal_gap 0.5)
			(thermal_bridge_width 0.5)
			(island_removal_mode 0)
		)
		(polygon
			(pts
				(arc
					(start 308.117494 -229.882192)
					(mid 308.113774 -229.891172)
					(end 308.104794 -229.894892)
				)
				(arc
					(start 306.631594 -229.894892)
					(mid 306.622614 -229.891172)
					(end 306.618894 -229.882192)
				)
				(arc
					(start 306.618894 -229.387654)
					(mid 306.622614 -229.378674)
					(end 306.631594 -229.374954)
				)
				(arc
					(start 308.104794 -229.374954)
					(mid 308.113774 -229.378674)
					(end 308.117494 -229.387654)
				)
			)
		)
	)
	(zone
		(layer "In1.Cu")
		(hatch none 0.5)
		(connect_pads
			(clearance 0)
		)
		(min_thickness 0.25)
		(keepout
			(tracks not_allowed)
			(vias allowed)
			(pads allowed)
			(copperpour not_allowed)
			(footprints allowed)
		)
		(placement
			(enabled no)
			(sheetname "")
		)
		(fill
			(thermal_gap 0.5)
			(thermal_bridge_width 0.5)
			(island_removal_mode 0)
		)
		(polygon
			(pts
				(arc
					(start 424.761406 -278.332184)
					(mid 424.757686 -278.341164)
					(end 424.748706 -278.344884)
				)
				(arc
					(start 423.275506 -278.344884)
					(mid 423.266526 -278.341164)
					(end 423.262806 -278.332184)
				)
				(arc
					(start 423.262806 -277.837646)
					(mid 423.266526 -277.828666)
					(end 423.275506 -277.824946)
				)
				(arc
					(start 424.748706 -277.824946)
					(mid 424.757686 -277.828666)
					(end 424.761406 -277.837646)
				)
			)
		)
	)
	(zone
		(layer "In1.Cu")
		(hatch none 0.5)
		(connect_pads
			(clearance 0)
		)
		(min_thickness 0.25)
		(keepout
			(tracks not_allowed)
			(vias allowed)
			(pads allowed)
			(copperpour not_allowed)
			(footprints allowed)
		)
		(placement
			(enabled no)
			(sheetname "")
		)
		(fill
			(thermal_gap 0.5)
			(thermal_bridge_width 0.5)
			(island_removal_mode 0)
		)
		(polygon
			(pts
				(arc
					(start 187.809378 -285.98241)
					(mid 187.805658 -285.99139)
					(end 187.796678 -285.99511)
				)
				(arc
					(start 186.323478 -285.99511)
					(mid 186.314498 -285.99139)
					(end 186.310778 -285.98241)
				)
				(arc
					(start 186.310778 -285.487872)
					(mid 186.314498 -285.478892)
					(end 186.323478 -285.475172)
				)
				(arc
					(start 187.796678 -285.475172)
					(mid 187.805658 -285.478892)
					(end 187.809378 -285.487872)
				)
			)
		)
	)
	(zone
		(layer "In1.Cu")
		(hatch none 0.5)
		(connect_pads
			(clearance 0)
		)
		(min_thickness 0.25)
		(keepout
			(tracks not_allowed)
			(vias allowed)
			(pads allowed)
			(copperpour not_allowed)
			(footprints allowed)
		)
		(placement
			(enabled no)
			(sheetname "")
		)
		(fill
			(thermal_gap 0.5)
			(thermal_bridge_width 0.5)
			(island_removal_mode 0)
		)
		(polygon
			(pts
				(arc
					(start 33.445196 -218.83243)
					(mid 33.441476 -218.84141)
					(end 33.432496 -218.84513)
				)
				(arc
					(start 31.959296 -218.84513)
					(mid 31.950316 -218.84141)
					(end 31.946596 -218.83243)
				)
				(arc
					(start 31.946596 -218.337892)
					(mid 31.950316 -218.328912)
					(end 31.959296 -218.325192)
				)
				(arc
					(start 33.432496 -218.325192)
					(mid 33.441476 -218.328912)
					(end 33.445196 -218.337892)
				)
			)
		)
	)
	(zone
		(layer "In1.Cu")
		(hatch none 0.5)
		(connect_pads
			(clearance 0)
		)
		(min_thickness 0.25)
		(keepout
			(tracks not_allowed)
			(vias allowed)
			(pads allowed)
			(copperpour not_allowed)
			(footprints allowed)
		)
		(placement
			(enabled no)
			(sheetname "")
		)
		(fill
			(thermal_gap 0.5)
			(thermal_bridge_width 0.5)
			(island_removal_mode 0)
		)
		(polygon
			(pts
				(arc
					(start 320.26098 -393.69238)
					(mid 319.87998 -393.69238)
					(end 320.26098 -393.69238)
				)
			)
		)
	)
	(zone
		(layer "In1.Cu")
		(hatch none 0.5)
		(connect_pads
			(clearance 0)
		)
		(min_thickness 0.25)
		(keepout
			(tracks not_allowed)
			(vias allowed)
			(pads allowed)
			(copperpour not_allowed)
			(footprints allowed)
		)
		(placement
			(enabled no)
			(sheetname "")
		)
		(fill
			(thermal_gap 0.5)
			(thermal_bridge_width 0.5)
			(island_removal_mode 0)
		)
		(polygon
			(pts
				(arc
					(start 40.98925 -230.732584)
					(mid 40.98553 -230.741564)
					(end 40.97655 -230.745284)
				)
				(arc
					(start 39.50335 -230.745284)
					(mid 39.49437 -230.741564)
					(end 39.49065 -230.732584)
				)
				(arc
					(start 39.49065 -230.238046)
					(mid 39.49437 -230.229066)
					(end 39.50335 -230.225346)
				)
				(arc
					(start 40.97655 -230.225346)
					(mid 40.98553 -230.229066)
					(end 40.98925 -230.238046)
				)
			)
		)
	)
	(zone
		(layer "In1.Cu")
		(hatch none 0.5)
		(connect_pads
			(clearance 0)
		)
		(min_thickness 0.25)
		(keepout
			(tracks not_allowed)
			(vias allowed)
			(pads allowed)
			(copperpour not_allowed)
			(footprints allowed)
		)
		(placement
			(enabled no)
			(sheetname "")
		)
		(fill
			(thermal_gap 0.5)
			(thermal_bridge_width 0.5)
			(island_removal_mode 0)
		)
		(polygon
			(pts
				(arc
					(start 439.849514 -251.132086)
					(mid 439.845794 -251.141066)
					(end 439.836814 -251.144786)
				)
				(arc
					(start 438.363614 -251.144786)
					(mid 438.354634 -251.141066)
					(end 438.350914 -251.132086)
				)
				(arc
					(start 438.350914 -250.637548)
					(mid 438.354634 -250.628568)
					(end 438.363614 -250.624848)
				)
				(arc
					(start 439.836814 -250.624848)
					(mid 439.845794 -250.628568)
					(end 439.849514 -250.637548)
				)
			)
		)
	)
	(zone
		(layer "In1.Cu")
		(hatch none 0.5)
		(connect_pads
			(clearance 0)
		)
		(min_thickness 0.25)
		(keepout
			(tracks not_allowed)
			(vias allowed)
			(pads allowed)
			(copperpour not_allowed)
			(footprints allowed)
		)
		(placement
			(enabled no)
			(sheetname "")
		)
		(fill
			(thermal_gap 0.5)
			(thermal_bridge_width 0.5)
			(island_removal_mode 0)
		)
		(polygon
			(pts
				(arc
					(start 266.29741 -314.882276)
					(mid 266.29369 -314.891256)
					(end 266.28471 -314.894976)
				)
				(arc
					(start 264.81151 -314.894976)
					(mid 264.80253 -314.891256)
					(end 264.79881 -314.882276)
				)
				(arc
					(start 264.79881 -314.387738)
					(mid 264.80253 -314.378758)
					(end 264.81151 -314.375038)
				)
				(arc
					(start 266.28471 -314.375038)
					(mid 266.29369 -314.378758)
					(end 266.29741 -314.387738)
				)
			)
		)
	)
	(zone
		(layer "In1.Cu")
		(hatch none 0.5)
		(connect_pads
			(clearance 0)
		)
		(min_thickness 0.25)
		(keepout
			(tracks not_allowed)
			(vias allowed)
			(pads allowed)
			(copperpour not_allowed)
			(footprints allowed)
		)
		(placement
			(enabled no)
			(sheetname "")
		)
		(fill
			(thermal_gap 0.5)
			(thermal_bridge_width 0.5)
			(island_removal_mode 0)
		)
		(polygon
			(pts
				(arc
					(start 273.841464 -302.982122)
					(mid 273.837744 -302.991102)
					(end 273.828764 -302.994822)
				)
				(arc
					(start 272.355564 -302.994822)
					(mid 272.346584 -302.991102)
					(end 272.342864 -302.982122)
				)
				(arc
					(start 272.342864 -302.487584)
					(mid 272.346584 -302.478604)
					(end 272.355564 -302.474884)
				)
				(arc
					(start 273.828764 -302.474884)
					(mid 273.837744 -302.478604)
					(end 273.841464 -302.487584)
				)
			)
		)
	)
	(zone
		(layer "In1.Cu")
		(hatch none 0.5)
		(connect_pads
			(clearance 0)
		)
		(min_thickness 0.25)
		(keepout
			(tracks not_allowed)
			(vias allowed)
			(pads allowed)
			(copperpour not_allowed)
			(footprints allowed)
		)
		(placement
			(enabled no)
			(sheetname "")
		)
		(fill
			(thermal_gap 0.5)
			(thermal_bridge_width 0.5)
			(island_removal_mode 0)
		)
		(polygon
			(pts
				(arc
					(start 60.177426 -274.08251)
					(mid 60.173706 -274.09149)
					(end 60.164726 -274.09521)
				)
				(arc
					(start 58.691526 -274.09521)
					(mid 58.682546 -274.09149)
					(end 58.678826 -274.08251)
				)
				(arc
					(start 58.678826 -273.587972)
					(mid 58.682546 -273.578992)
					(end 58.691526 -273.575272)
				)
				(arc
					(start 60.164726 -273.575272)
					(mid 60.173706 -273.578992)
					(end 60.177426 -273.587972)
				)
			)
		)
	)
	(zone
		(layer "In1.Cu")
		(hatch none 0.5)
		(connect_pads
			(clearance 0)
		)
		(min_thickness 0.25)
		(keepout
			(tracks not_allowed)
			(vias allowed)
			(pads allowed)
			(copperpour not_allowed)
			(footprints allowed)
		)
		(placement
			(enabled no)
			(sheetname "")
		)
		(fill
			(thermal_gap 0.5)
			(thermal_bridge_width 0.5)
			(island_removal_mode 0)
		)
		(polygon
			(pts
				(arc
					(start 33.445196 -302.982376)
					(mid 33.441476 -302.991356)
					(end 33.432496 -302.995076)
				)
				(arc
					(start 31.959296 -302.995076)
					(mid 31.950316 -302.991356)
					(end 31.946596 -302.982376)
				)
				(arc
					(start 31.946596 -302.487838)
					(mid 31.950316 -302.478858)
					(end 31.959296 -302.475138)
				)
				(arc
					(start 33.432496 -302.475138)
					(mid 33.441476 -302.478858)
					(end 33.445196 -302.487838)
				)
			)
		)
	)
	(zone
		(layer "In1.Cu")
		(hatch none 0.5)
		(connect_pads
			(clearance 0)
		)
		(min_thickness 0.25)
		(keepout
			(tracks not_allowed)
			(vias allowed)
			(pads allowed)
			(copperpour not_allowed)
			(footprints allowed)
		)
		(placement
			(enabled no)
			(sheetname "")
		)
		(fill
			(thermal_gap 0.5)
			(thermal_bridge_width 0.5)
			(island_removal_mode 0)
		)
		(polygon
			(pts
				(arc
					(start 435.749446 -288.532316)
					(mid 435.745726 -288.541296)
					(end 435.736746 -288.545016)
				)
				(arc
					(start 434.263546 -288.545016)
					(mid 434.254566 -288.541296)
					(end 434.250846 -288.532316)
				)
				(arc
					(start 434.250846 -288.037778)
					(mid 434.254566 -288.028798)
					(end 434.263546 -288.025078)
				)
				(arc
					(start 435.736746 -288.025078)
					(mid 435.745726 -288.028798)
					(end 435.749446 -288.037778)
				)
			)
		)
	)
	(zone
		(layer "In1.Cu")
		(hatch none 0.5)
		(connect_pads
			(clearance 0)
		)
		(min_thickness 0.25)
		(keepout
			(tracks not_allowed)
			(vias allowed)
			(pads allowed)
			(copperpour not_allowed)
			(footprints allowed)
		)
		(placement
			(enabled no)
			(sheetname "")
		)
		(fill
			(thermal_gap 0.5)
			(thermal_bridge_width 0.5)
			(island_removal_mode 0)
		)
		(polygon
			(pts
				(arc
					(start 349.918528 -391.822686)
					(mid 350.045528 -391.949686)
					(end 350.172528 -391.822686)
				)
				(arc
					(start 350.172528 -391.746486)
					(mid 350.045528 -391.619486)
					(end 349.918528 -391.746486)
				)
			)
		)
	)
	(zone
		(layer "In1.Cu")
		(hatch none 0.5)
		(connect_pads
			(clearance 0)
		)
		(min_thickness 0.25)
		(keepout
			(tracks not_allowed)
			(vias allowed)
			(pads allowed)
			(copperpour not_allowed)
			(footprints allowed)
		)
		(placement
			(enabled no)
			(sheetname "")
		)
		(fill
			(thermal_gap 0.5)
			(thermal_bridge_width 0.5)
			(island_removal_mode 0)
		)
		(polygon
			(pts
				(arc
					(start 184.365392 -227.33254)
					(mid 184.361672 -227.34152)
					(end 184.352692 -227.34524)
				)
				(arc
					(start 182.879492 -227.34524)
					(mid 182.870512 -227.34152)
					(end 182.866792 -227.33254)
				)
				(arc
					(start 182.866792 -226.838002)
					(mid 182.870512 -226.829022)
					(end 182.879492 -226.825302)
				)
				(arc
					(start 184.352692 -226.825302)
					(mid 184.361672 -226.829022)
					(end 184.365392 -226.838002)
				)
			)
		)
	)
	(zone
		(layer "In1.Cu")
		(hatch none 0.5)
		(connect_pads
			(clearance 0)
		)
		(min_thickness 0.25)
		(keepout
			(tracks not_allowed)
			(vias allowed)
			(pads allowed)
			(copperpour not_allowed)
			(footprints allowed)
		)
		(placement
			(enabled no)
			(sheetname "")
		)
		(fill
			(thermal_gap 0.5)
			(thermal_bridge_width 0.5)
			(island_removal_mode 0)
		)
		(polygon
			(pts
				(arc
					(start 435.749446 -307.232304)
					(mid 435.745726 -307.241284)
					(end 435.736746 -307.245004)
				)
				(arc
					(start 434.263546 -307.245004)
					(mid 434.254566 -307.241284)
					(end 434.250846 -307.232304)
				)
				(arc
					(start 434.250846 -306.737766)
					(mid 434.254566 -306.728786)
					(end 434.263546 -306.725066)
				)
				(arc
					(start 435.736746 -306.725066)
					(mid 435.745726 -306.728786)
					(end 435.749446 -306.737766)
				)
			)
		)
	)
	(zone
		(layer "In1.Cu")
		(hatch none 0.5)
		(connect_pads
			(clearance 0)
		)
		(min_thickness 0.25)
		(keepout
			(tracks not_allowed)
			(vias allowed)
			(pads allowed)
			(copperpour not_allowed)
			(footprints allowed)
		)
		(placement
			(enabled no)
			(sheetname "")
		)
		(fill
			(thermal_gap 0.5)
			(thermal_bridge_width 0.5)
			(island_removal_mode 0)
		)
		(polygon
			(pts
				(arc
					(start 439.849514 -211.182204)
					(mid 439.845794 -211.191184)
					(end 439.836814 -211.194904)
				)
				(arc
					(start 438.363614 -211.194904)
					(mid 438.354634 -211.191184)
					(end 438.350914 -211.182204)
				)
				(arc
					(start 438.350914 -210.687666)
					(mid 438.354634 -210.678686)
					(end 438.363614 -210.674966)
				)
				(arc
					(start 439.836814 -210.674966)
					(mid 439.845794 -210.678686)
					(end 439.849514 -210.687666)
				)
			)
		)
	)
	(zone
		(layer "In1.Cu")
		(hatch none 0.5)
		(connect_pads
			(clearance 0)
		)
		(min_thickness 0.25)
		(keepout
			(tracks not_allowed)
			(vias allowed)
			(pads allowed)
			(copperpour not_allowed)
			(footprints allowed)
		)
		(placement
			(enabled no)
			(sheetname "")
		)
		(fill
			(thermal_gap 0.5)
			(thermal_bridge_width 0.5)
			(island_removal_mode 0)
		)
		(polygon
			(pts
				(arc
					(start 428.205392 -316.582298)
					(mid 428.201672 -316.591278)
					(end 428.192692 -316.594998)
				)
				(arc
					(start 426.719492 -316.594998)
					(mid 426.710512 -316.591278)
					(end 426.706792 -316.582298)
				)
				(arc
					(start 426.706792 -316.08776)
					(mid 426.710512 -316.07878)
					(end 426.719492 -316.07506)
				)
				(arc
					(start 428.192692 -316.07506)
					(mid 428.201672 -316.07878)
					(end 428.205392 -316.08776)
				)
			)
		)
	)
	(zone
		(layer "In1.Cu")
		(hatch none 0.5)
		(connect_pads
			(clearance 0)
		)
		(min_thickness 0.25)
		(keepout
			(tracks not_allowed)
			(vias allowed)
			(pads allowed)
			(copperpour not_allowed)
			(footprints allowed)
		)
		(placement
			(enabled no)
			(sheetname "")
		)
		(fill
			(thermal_gap 0.5)
			(thermal_bridge_width 0.5)
			(island_removal_mode 0)
		)
		(polygon
			(pts
				(arc
					(start 420.661338 -217.132154)
					(mid 420.657618 -217.141134)
					(end 420.648638 -217.144854)
				)
				(arc
					(start 419.175438 -217.144854)
					(mid 419.166458 -217.141134)
					(end 419.162738 -217.132154)
				)
				(arc
					(start 419.162738 -216.637616)
					(mid 419.166458 -216.628636)
					(end 419.175438 -216.624916)
				)
				(arc
					(start 420.648638 -216.624916)
					(mid 420.657618 -216.628636)
					(end 420.661338 -216.637616)
				)
			)
		)
	)
	(zone
		(layer "In1.Cu")
		(hatch none 0.5)
		(connect_pads
			(clearance 0)
		)
		(min_thickness 0.25)
		(keepout
			(tracks not_allowed)
			(vias allowed)
			(pads allowed)
			(copperpour not_allowed)
			(footprints allowed)
		)
		(placement
			(enabled no)
			(sheetname "")
		)
		(fill
			(thermal_gap 0.5)
			(thermal_bridge_width 0.5)
			(island_removal_mode 0)
		)
		(polygon
			(pts
				(arc
					(start 304.190654 -399.701258)
					(mid 304.317654 -399.828258)
					(end 304.444654 -399.701258)
				)
				(arc
					(start 304.444654 -399.625058)
					(mid 304.317654 -399.498058)
					(end 304.190654 -399.625058)
				)
			)
		)
	)
	(zone
		(layer "In1.Cu")
		(hatch none 0.5)
		(connect_pads
			(clearance 0)
		)
		(min_thickness 0.25)
		(keepout
			(tracks not_allowed)
			(vias allowed)
			(pads allowed)
			(copperpour not_allowed)
			(footprints allowed)
		)
		(placement
			(enabled no)
			(sheetname "")
		)
		(fill
			(thermal_gap 0.5)
			(thermal_bridge_width 0.5)
			(island_removal_mode 0)
		)
		(polygon
			(pts
				(arc
					(start 60.177426 -291.082476)
					(mid 60.173706 -291.091456)
					(end 60.164726 -291.095176)
				)
				(arc
					(start 58.691526 -291.095176)
					(mid 58.682546 -291.091456)
					(end 58.678826 -291.082476)
				)
				(arc
					(start 58.678826 -290.587938)
					(mid 58.682546 -290.578958)
					(end 58.691526 -290.575238)
				)
				(arc
					(start 60.164726 -290.575238)
					(mid 60.173706 -290.578958)
					(end 60.177426 -290.587938)
				)
			)
		)
	)
	(zone
		(layer "In1.Cu")
		(hatch none 0.5)
		(connect_pads
			(clearance 0)
		)
		(min_thickness 0.25)
		(keepout
			(tracks not_allowed)
			(vias allowed)
			(pads allowed)
			(copperpour not_allowed)
			(footprints allowed)
		)
		(placement
			(enabled no)
			(sheetname "")
		)
		(fill
			(thermal_gap 0.5)
			(thermal_bridge_width 0.5)
			(island_removal_mode 0)
		)
		(polygon
			(pts
				(arc
					(start 169.277284 -225.632518)
					(mid 169.273564 -225.641498)
					(end 169.264584 -225.645218)
				)
				(arc
					(start 167.791384 -225.645218)
					(mid 167.782404 -225.641498)
					(end 167.778684 -225.632518)
				)
				(arc
					(start 167.778684 -225.13798)
					(mid 167.782404 -225.129)
					(end 167.791384 -225.12528)
				)
				(arc
					(start 169.264584 -225.12528)
					(mid 169.273564 -225.129)
					(end 169.277284 -225.13798)
				)
			)
		)
	)
	(zone
		(layer "In1.Cu")
		(hatch none 0.5)
		(connect_pads
			(clearance 0)
		)
		(min_thickness 0.25)
		(keepout
			(tracks not_allowed)
			(vias allowed)
			(pads allowed)
			(copperpour not_allowed)
			(footprints allowed)
		)
		(placement
			(enabled no)
			(sheetname "")
		)
		(fill
			(thermal_gap 0.5)
			(thermal_bridge_width 0.5)
			(island_removal_mode 0)
		)
		(polygon
			(pts
				(arc
					(start 304.017426 -305.532282)
					(mid 304.013706 -305.541262)
					(end 304.004726 -305.544982)
				)
				(arc
					(start 302.531526 -305.544982)
					(mid 302.522546 -305.541262)
					(end 302.518826 -305.532282)
				)
				(arc
					(start 302.518826 -305.037744)
					(mid 302.522546 -305.028764)
					(end 302.531526 -305.025044)
				)
				(arc
					(start 304.004726 -305.025044)
					(mid 304.013706 -305.028764)
					(end 304.017426 -305.037744)
				)
			)
		)
	)
	(zone
		(layer "In1.Cu")
		(hatch none 0.5)
		(connect_pads
			(clearance 0)
		)
		(min_thickness 0.25)
		(keepout
			(tracks not_allowed)
			(vias allowed)
			(pads allowed)
			(copperpour not_allowed)
			(footprints allowed)
		)
		(placement
			(enabled no)
			(sheetname "")
		)
		(fill
			(thermal_gap 0.5)
			(thermal_bridge_width 0.5)
			(island_removal_mode 0)
		)
		(polygon
			(pts
				(arc
					(start 30.001464 -239.23244)
					(mid 29.997744 -239.24142)
					(end 29.988764 -239.24514)
				)
				(arc
					(start 28.515564 -239.24514)
					(mid 28.506584 -239.24142)
					(end 28.502864 -239.23244)
				)
				(arc
					(start 28.502864 -238.737902)
					(mid 28.506584 -238.728922)
					(end 28.515564 -238.725202)
				)
				(arc
					(start 29.988764 -238.725202)
					(mid 29.997744 -238.728922)
					(end 30.001464 -238.737902)
				)
			)
		)
	)
	(zone
		(layer "In1.Cu")
		(hatch none 0.5)
		(connect_pads
			(clearance 0)
		)
		(min_thickness 0.25)
		(keepout
			(tracks not_allowed)
			(vias allowed)
			(pads allowed)
			(copperpour not_allowed)
			(footprints allowed)
		)
		(placement
			(enabled no)
			(sheetname "")
		)
		(fill
			(thermal_gap 0.5)
			(thermal_bridge_width 0.5)
			(island_removal_mode 0)
		)
		(polygon
			(pts
				(arc
					(start 266.29741 -297.88231)
					(mid 266.29369 -297.89129)
					(end 266.28471 -297.89501)
				)
				(arc
					(start 264.81151 -297.89501)
					(mid 264.80253 -297.89129)
					(end 264.79881 -297.88231)
				)
				(arc
					(start 264.79881 -297.387772)
					(mid 264.80253 -297.378792)
					(end 264.81151 -297.375072)
				)
				(arc
					(start 266.28471 -297.375072)
					(mid 266.29369 -297.378792)
					(end 266.29741 -297.387772)
				)
			)
		)
	)
	(zone
		(layer "In1.Cu")
		(hatch none 0.5)
		(connect_pads
			(clearance 0)
		)
		(min_thickness 0.25)
		(keepout
			(tracks not_allowed)
			(vias allowed)
			(pads allowed)
			(copperpour not_allowed)
			(footprints allowed)
		)
		(placement
			(enabled no)
			(sheetname "")
		)
		(fill
			(thermal_gap 0.5)
			(thermal_bridge_width 0.5)
			(island_removal_mode 0)
		)
		(polygon
			(pts
				(arc
					(start 48.190912 -383.440686)
					(mid 48.317912 -383.567686)
					(end 48.444912 -383.440686)
				)
				(arc
					(start 48.444912 -383.364486)
					(mid 48.317912 -383.237486)
					(end 48.190912 -383.364486)
				)
			)
		)
	)
	(zone
		(layer "In1.Cu")
		(hatch none 0.5)
		(connect_pads
			(clearance 0)
		)
		(min_thickness 0.25)
		(keepout
			(tracks not_allowed)
			(vias allowed)
			(pads allowed)
			(copperpour not_allowed)
			(footprints allowed)
		)
		(placement
			(enabled no)
			(sheetname "")
		)
		(fill
			(thermal_gap 0.5)
			(thermal_bridge_width 0.5)
			(island_removal_mode 0)
		)
		(polygon
			(pts
				(arc
					(start 296.473372 -251.982224)
					(mid 296.469652 -251.991204)
					(end 296.460672 -251.994924)
				)
				(arc
					(start 294.987472 -251.994924)
					(mid 294.978492 -251.991204)
					(end 294.974772 -251.982224)
				)
				(arc
					(start 294.974772 -251.487686)
					(mid 294.978492 -251.478706)
					(end 294.987472 -251.474986)
				)
				(arc
					(start 296.460672 -251.474986)
					(mid 296.469652 -251.478706)
					(end 296.473372 -251.487686)
				)
			)
		)
	)
	(zone
		(layer "In1.Cu")
		(hatch none 0.5)
		(connect_pads
			(clearance 0)
		)
		(min_thickness 0.25)
		(keepout
			(tracks not_allowed)
			(vias allowed)
			(pads allowed)
			(copperpour not_allowed)
			(footprints allowed)
		)
		(placement
			(enabled no)
			(sheetname "")
		)
		(fill
			(thermal_gap 0.5)
			(thermal_bridge_width 0.5)
			(island_removal_mode 0)
		)
		(polygon
			(pts
				(arc
					(start 309.461154 -397.156432)
					(mid 309.080154 -397.156432)
					(end 309.461154 -397.156432)
				)
			)
		)
	)
	(zone
		(layer "In1.Cu")
		(hatch none 0.5)
		(connect_pads
			(clearance 0)
		)
		(min_thickness 0.25)
		(keepout
			(tracks not_allowed)
			(vias allowed)
			(pads allowed)
			(copperpour not_allowed)
			(footprints allowed)
		)
		(placement
			(enabled no)
			(sheetname "")
		)
		(fill
			(thermal_gap 0.5)
			(thermal_bridge_width 0.5)
			(island_removal_mode 0)
		)
		(polygon
			(pts
				(arc
					(start 270.397478 -233.282236)
					(mid 270.393758 -233.291216)
					(end 270.384778 -233.294936)
				)
				(arc
					(start 268.911578 -233.294936)
					(mid 268.902598 -233.291216)
					(end 268.898878 -233.282236)
				)
				(arc
					(start 268.898878 -232.787698)
					(mid 268.902598 -232.778718)
					(end 268.911578 -232.774998)
				)
				(arc
					(start 270.384778 -232.774998)
					(mid 270.393758 -232.778718)
					(end 270.397478 -232.787698)
				)
			)
		)
	)
	(zone
		(layer "In1.Cu")
		(hatch none 0.5)
		(connect_pads
			(clearance 0)
		)
		(min_thickness 0.25)
		(keepout
			(tracks not_allowed)
			(vias allowed)
			(pads allowed)
			(copperpour not_allowed)
			(footprints allowed)
		)
		(placement
			(enabled no)
			(sheetname "")
		)
		(fill
			(thermal_gap 0.5)
			(thermal_bridge_width 0.5)
			(island_removal_mode 0)
		)
		(polygon
			(pts
				(arc
					(start 187.809378 -206.082392)
					(mid 187.805658 -206.091372)
					(end 187.796678 -206.095092)
				)
				(arc
					(start 186.323478 -206.095092)
					(mid 186.314498 -206.091372)
					(end 186.310778 -206.082392)
				)
				(arc
					(start 186.310778 -205.587854)
					(mid 186.314498 -205.578874)
					(end 186.323478 -205.575154)
				)
				(arc
					(start 187.796678 -205.575154)
					(mid 187.805658 -205.578874)
					(end 187.809378 -205.587854)
				)
			)
		)
	)
	(zone
		(layer "In1.Cu")
		(hatch none 0.5)
		(connect_pads
			(clearance 0)
		)
		(min_thickness 0.25)
		(keepout
			(tracks not_allowed)
			(vias allowed)
			(pads allowed)
			(copperpour not_allowed)
			(footprints allowed)
		)
		(placement
			(enabled no)
			(sheetname "")
		)
		(fill
			(thermal_gap 0.5)
			(thermal_bridge_width 0.5)
			(island_removal_mode 0)
		)
		(polygon
			(pts
				(arc
					(start 413.117284 -268.98219)
					(mid 413.113564 -268.99117)
					(end 413.104584 -268.99489)
				)
				(arc
					(start 411.631384 -268.99489)
					(mid 411.622404 -268.99117)
					(end 411.618684 -268.98219)
				)
				(arc
					(start 411.618684 -268.487652)
					(mid 411.622404 -268.478672)
					(end 411.631384 -268.474952)
				)
				(arc
					(start 413.104584 -268.474952)
					(mid 413.113564 -268.478672)
					(end 413.117284 -268.487652)
				)
			)
		)
	)
	(zone
		(layer "In1.Cu")
		(hatch none 0.5)
		(connect_pads
			(clearance 0)
		)
		(min_thickness 0.25)
		(keepout
			(tracks not_allowed)
			(vias allowed)
			(pads allowed)
			(copperpour not_allowed)
			(footprints allowed)
		)
		(placement
			(enabled no)
			(sheetname "")
		)
		(fill
			(thermal_gap 0.5)
			(thermal_bridge_width 0.5)
			(island_removal_mode 0)
		)
		(polygon
			(pts
				(arc
					(start 443.2935 -250.282202)
					(mid 443.28978 -250.291182)
					(end 443.2808 -250.294902)
				)
				(arc
					(start 441.8076 -250.294902)
					(mid 441.79862 -250.291182)
					(end 441.7949 -250.282202)
				)
				(arc
					(start 441.7949 -249.787664)
					(mid 441.79862 -249.778684)
					(end 441.8076 -249.774964)
				)
				(arc
					(start 443.2808 -249.774964)
					(mid 443.28978 -249.778684)
					(end 443.2935 -249.787664)
				)
			)
		)
	)
	(zone
		(layer "In1.Cu")
		(hatch none 0.5)
		(connect_pads
			(clearance 0)
		)
		(min_thickness 0.25)
		(keepout
			(tracks not_allowed)
			(vias allowed)
			(pads allowed)
			(copperpour not_allowed)
			(footprints allowed)
		)
		(placement
			(enabled no)
			(sheetname "")
		)
		(fill
			(thermal_gap 0.5)
			(thermal_bridge_width 0.5)
			(island_removal_mode 0)
		)
		(polygon
			(pts
				(arc
					(start 30.001464 -208.632552)
					(mid 29.997744 -208.641532)
					(end 29.988764 -208.645252)
				)
				(arc
					(start 28.515564 -208.645252)
					(mid 28.506584 -208.641532)
					(end 28.502864 -208.632552)
				)
				(arc
					(start 28.502864 -208.138014)
					(mid 28.506584 -208.129034)
					(end 28.515564 -208.125314)
				)
				(arc
					(start 29.988764 -208.125314)
					(mid 29.997744 -208.129034)
					(end 30.001464 -208.138014)
				)
			)
		)
	)
	(zone
		(layer "In1.Cu")
		(hatch none 0.5)
		(connect_pads
			(clearance 0)
		)
		(min_thickness 0.25)
		(keepout
			(tracks not_allowed)
			(vias allowed)
			(pads allowed)
			(copperpour not_allowed)
			(footprints allowed)
		)
		(placement
			(enabled no)
			(sheetname "")
		)
		(fill
			(thermal_gap 0.5)
			(thermal_bridge_width 0.5)
			(island_removal_mode 0)
		)
		(polygon
			(pts
				(arc
					(start 320.26098 -397.156432)
					(mid 319.87998 -397.156432)
					(end 320.26098 -397.156432)
				)
			)
		)
	)
	(zone
		(layer "In1.Cu")
		(hatch none 0.5)
		(connect_pads
			(clearance 0)
		)
		(min_thickness 0.25)
		(keepout
			(tracks not_allowed)
			(vias allowed)
			(pads allowed)
			(copperpour not_allowed)
			(footprints allowed)
		)
		(placement
			(enabled no)
			(sheetname "")
		)
		(fill
			(thermal_gap 0.5)
			(thermal_bridge_width 0.5)
			(island_removal_mode 0)
		)
		(polygon
			(pts
				(arc
					(start 443.2935 -224.782126)
					(mid 443.28978 -224.791106)
					(end 443.2808 -224.794826)
				)
				(arc
					(start 441.8076 -224.794826)
					(mid 441.79862 -224.791106)
					(end 441.7949 -224.782126)
				)
				(arc
					(start 441.7949 -224.287588)
					(mid 441.79862 -224.278608)
					(end 441.8076 -224.274888)
				)
				(arc
					(start 443.2808 -224.274888)
					(mid 443.28978 -224.278608)
					(end 443.2935 -224.287588)
				)
			)
		)
	)
	(zone
		(layer "In1.Cu")
		(hatch none 0.5)
		(connect_pads
			(clearance 0)
		)
		(min_thickness 0.25)
		(keepout
			(tracks not_allowed)
			(vias allowed)
			(pads allowed)
			(copperpour not_allowed)
			(footprints allowed)
		)
		(placement
			(enabled no)
			(sheetname "")
		)
		(fill
			(thermal_gap 0.5)
			(thermal_bridge_width 0.5)
			(island_removal_mode 0)
		)
		(polygon
			(pts
				(arc
					(start 266.29741 -198.432166)
					(mid 266.29369 -198.441146)
					(end 266.28471 -198.444866)
				)
				(arc
					(start 264.81151 -198.444866)
					(mid 264.80253 -198.441146)
					(end 264.79881 -198.432166)
				)
				(arc
					(start 264.79881 -197.937628)
					(mid 264.80253 -197.928648)
					(end 264.81151 -197.924928)
				)
				(arc
					(start 266.28471 -197.924928)
					(mid 266.29369 -197.928648)
					(end 266.29741 -197.937628)
				)
			)
		)
	)
	(zone
		(layer "In1.Cu")
		(hatch none 0.5)
		(connect_pads
			(clearance 0)
		)
		(min_thickness 0.25)
		(keepout
			(tracks not_allowed)
			(vias allowed)
			(pads allowed)
			(copperpour not_allowed)
			(footprints allowed)
		)
		(placement
			(enabled no)
			(sheetname "")
		)
		(fill
			(thermal_gap 0.5)
			(thermal_bridge_width 0.5)
			(island_removal_mode 0)
		)
		(polygon
			(pts
				(arc
					(start 288.929318 -288.532316)
					(mid 288.925598 -288.541296)
					(end 288.916618 -288.545016)
				)
				(arc
					(start 287.443418 -288.545016)
					(mid 287.434438 -288.541296)
					(end 287.430718 -288.532316)
				)
				(arc
					(start 287.430718 -288.037778)
					(mid 287.434438 -288.028798)
					(end 287.443418 -288.025078)
				)
				(arc
					(start 288.916618 -288.025078)
					(mid 288.925598 -288.028798)
					(end 288.929318 -288.037778)
				)
			)
		)
	)
	(zone
		(layer "In1.Cu")
		(hatch none 0.5)
		(connect_pads
			(clearance 0)
		)
		(min_thickness 0.25)
		(keepout
			(tracks not_allowed)
			(vias allowed)
			(pads allowed)
			(copperpour not_allowed)
			(footprints allowed)
		)
		(placement
			(enabled no)
			(sheetname "")
		)
		(fill
			(thermal_gap 0.5)
			(thermal_bridge_width 0.5)
			(island_removal_mode 0)
		)
		(polygon
			(pts
				(arc
					(start 18.357342 -280.882344)
					(mid 18.353622 -280.891324)
					(end 18.344642 -280.895044)
				)
				(arc
					(start 16.871442 -280.895044)
					(mid 16.862462 -280.891324)
					(end 16.858742 -280.882344)
				)
				(arc
					(start 16.858742 -280.387806)
					(mid 16.862462 -280.378826)
					(end 16.871442 -280.375106)
				)
				(arc
					(start 18.344642 -280.375106)
					(mid 18.353622 -280.378826)
					(end 18.357342 -280.387806)
				)
			)
		)
	)
	(zone
		(layer "In1.Cu")
		(hatch none 0.5)
		(connect_pads
			(clearance 0)
		)
		(min_thickness 0.25)
		(keepout
			(tracks not_allowed)
			(vias allowed)
			(pads allowed)
			(copperpour not_allowed)
			(footprints allowed)
		)
		(placement
			(enabled no)
			(sheetname "")
		)
		(fill
			(thermal_gap 0.5)
			(thermal_bridge_width 0.5)
			(island_removal_mode 0)
		)
		(polygon
			(pts
				(arc
					(start 172.72127 -296.182542)
					(mid 172.71755 -296.191522)
					(end 172.70857 -296.195242)
				)
				(arc
					(start 171.23537 -296.195242)
					(mid 171.22639 -296.191522)
					(end 171.22267 -296.182542)
				)
				(arc
					(start 171.22267 -295.688004)
					(mid 171.22639 -295.679024)
					(end 171.23537 -295.675304)
				)
				(arc
					(start 172.70857 -295.675304)
					(mid 172.71755 -295.679024)
					(end 172.72127 -295.688004)
				)
			)
		)
	)
	(zone
		(layer "In1.Cu")
		(hatch none 0.5)
		(connect_pads
			(clearance 0)
		)
		(min_thickness 0.25)
		(keepout
			(tracks not_allowed)
			(vias allowed)
			(pads allowed)
			(copperpour not_allowed)
			(footprints allowed)
		)
		(placement
			(enabled no)
			(sheetname "")
		)
		(fill
			(thermal_gap 0.5)
			(thermal_bridge_width 0.5)
			(island_removal_mode 0)
		)
		(polygon
			(pts
				(arc
					(start 439.849514 -223.932242)
					(mid 439.845794 -223.941222)
					(end 439.836814 -223.944942)
				)
				(arc
					(start 438.363614 -223.944942)
					(mid 438.354634 -223.941222)
					(end 438.350914 -223.932242)
				)
				(arc
					(start 438.350914 -223.437704)
					(mid 438.354634 -223.428724)
					(end 438.363614 -223.425004)
				)
				(arc
					(start 439.836814 -223.425004)
					(mid 439.845794 -223.428724)
					(end 439.849514 -223.437704)
				)
			)
		)
	)
	(zone
		(layer "In1.Cu")
		(hatch none 0.5)
		(connect_pads
			(clearance 0)
		)
		(min_thickness 0.25)
		(keepout
			(tracks not_allowed)
			(vias allowed)
			(pads allowed)
			(copperpour not_allowed)
			(footprints allowed)
		)
		(placement
			(enabled no)
			(sheetname "")
		)
		(fill
			(thermal_gap 0.5)
			(thermal_bridge_width 0.5)
			(island_removal_mode 0)
		)
		(polygon
			(pts
				(arc
					(start 157.99816 -383.92227)
					(mid 157.69336 -383.92227)
					(end 157.99816 -383.92227)
				)
			)
		)
	)
	(zone
		(layer "In1.Cu")
		(hatch none 0.5)
		(connect_pads
			(clearance 0)
		)
		(min_thickness 0.25)
		(keepout
			(tracks not_allowed)
			(vias allowed)
			(pads allowed)
			(copperpour not_allowed)
			(footprints allowed)
		)
		(placement
			(enabled no)
			(sheetname "")
		)
		(fill
			(thermal_gap 0.5)
			(thermal_bridge_width 0.5)
			(island_removal_mode 0)
		)
		(polygon
			(pts
				(arc
					(start 443.2935 -241.782092)
					(mid 443.28978 -241.791072)
					(end 443.2808 -241.794792)
				)
				(arc
					(start 441.8076 -241.794792)
					(mid 441.79862 -241.791072)
					(end 441.7949 -241.782092)
				)
				(arc
					(start 441.7949 -241.287554)
					(mid 441.79862 -241.278574)
					(end 441.8076 -241.274854)
				)
				(arc
					(start 443.2808 -241.274854)
					(mid 443.28978 -241.278574)
					(end 443.2935 -241.287554)
				)
			)
		)
	)
	(zone
		(layer "In1.Cu")
		(hatch none 0.5)
		(connect_pads
			(clearance 0)
		)
		(min_thickness 0.25)
		(keepout
			(tracks not_allowed)
			(vias allowed)
			(pads allowed)
			(copperpour not_allowed)
			(footprints allowed)
		)
		(placement
			(enabled no)
			(sheetname "")
		)
		(fill
			(thermal_gap 0.5)
			(thermal_bridge_width 0.5)
			(island_removal_mode 0)
		)
		(polygon
			(pts
				(arc
					(start 378.490988 -391.822686)
					(mid 378.617988 -391.949686)
					(end 378.744988 -391.822686)
				)
				(arc
					(start 378.744988 -391.746486)
					(mid 378.617988 -391.619486)
					(end 378.490988 -391.746486)
				)
			)
		)
	)
	(zone
		(layer "In1.Cu")
		(hatch none 0.5)
		(connect_pads
			(clearance 0)
		)
		(min_thickness 0.25)
		(keepout
			(tracks not_allowed)
			(vias allowed)
			(pads allowed)
			(copperpour not_allowed)
			(footprints allowed)
		)
		(placement
			(enabled no)
			(sheetname "")
		)
		(fill
			(thermal_gap 0.5)
			(thermal_bridge_width 0.5)
			(island_removal_mode 0)
		)
		(polygon
			(pts
				(arc
					(start 415.488882 -394.385292)
					(mid 415.107882 -394.385292)
					(end 415.488882 -394.385292)
				)
			)
		)
	)
	(zone
		(layer "In1.Cu")
		(hatch none 0.5)
		(connect_pads
			(clearance 0)
		)
		(min_thickness 0.25)
		(keepout
			(tracks not_allowed)
			(vias allowed)
			(pads allowed)
			(copperpour not_allowed)
			(footprints allowed)
		)
		(placement
			(enabled no)
			(sheetname "")
		)
		(fill
			(thermal_gap 0.5)
			(thermal_bridge_width 0.5)
			(island_removal_mode 0)
		)
		(polygon
			(pts
				(arc
					(start 172.72127 -248.582434)
					(mid 172.71755 -248.591414)
					(end 172.70857 -248.595134)
				)
				(arc
					(start 171.23537 -248.595134)
					(mid 171.22639 -248.591414)
					(end 171.22267 -248.582434)
				)
				(arc
					(start 171.22267 -248.087896)
					(mid 171.22639 -248.078916)
					(end 171.23537 -248.075196)
				)
				(arc
					(start 172.70857 -248.075196)
					(mid 172.71755 -248.078916)
					(end 172.72127 -248.087896)
				)
			)
		)
	)
	(zone
		(layer "In1.Cu")
		(hatch none 0.5)
		(connect_pads
			(clearance 0)
		)
		(min_thickness 0.25)
		(keepout
			(tracks not_allowed)
			(vias allowed)
			(pads allowed)
			(copperpour not_allowed)
			(footprints allowed)
		)
		(placement
			(enabled no)
			(sheetname "")
		)
		(fill
			(thermal_gap 0.5)
			(thermal_bridge_width 0.5)
			(island_removal_mode 0)
		)
		(polygon
			(pts
				(arc
					(start 195.353432 -277.482554)
					(mid 195.349712 -277.491534)
					(end 195.340732 -277.495254)
				)
				(arc
					(start 193.867532 -277.495254)
					(mid 193.858552 -277.491534)
					(end 193.854832 -277.482554)
				)
				(arc
					(start 193.854832 -276.988016)
					(mid 193.858552 -276.979036)
					(end 193.867532 -276.975316)
				)
				(arc
					(start 195.340732 -276.975316)
					(mid 195.349712 -276.979036)
					(end 195.353432 -276.988016)
				)
			)
		)
	)
	(zone
		(layer "In1.Cu")
		(hatch none 0.5)
		(connect_pads
			(clearance 0)
		)
		(min_thickness 0.25)
		(keepout
			(tracks not_allowed)
			(vias allowed)
			(pads allowed)
			(copperpour not_allowed)
			(footprints allowed)
		)
		(placement
			(enabled no)
			(sheetname "")
		)
		(fill
			(thermal_gap 0.5)
			(thermal_bridge_width 0.5)
			(island_removal_mode 0)
		)
		(polygon
			(pts
				(arc
					(start 48.533304 -211.182458)
					(mid 48.529584 -211.191438)
					(end 48.520604 -211.195158)
				)
				(arc
					(start 47.047404 -211.195158)
					(mid 47.038424 -211.191438)
					(end 47.034704 -211.182458)
				)
				(arc
					(start 47.034704 -210.68792)
					(mid 47.038424 -210.67894)
					(end 47.047404 -210.67522)
				)
				(arc
					(start 48.520604 -210.67522)
					(mid 48.529584 -210.67894)
					(end 48.533304 -210.68792)
				)
			)
		)
	)
	(zone
		(layer "In1.Cu")
		(hatch none 0.5)
		(connect_pads
			(clearance 0)
		)
		(min_thickness 0.25)
		(keepout
			(tracks not_allowed)
			(vias allowed)
			(pads allowed)
			(copperpour not_allowed)
			(footprints allowed)
		)
		(placement
			(enabled no)
			(sheetname "")
		)
		(fill
			(thermal_gap 0.5)
			(thermal_bridge_width 0.5)
			(island_removal_mode 0)
		)
		(polygon
			(pts
				(arc
					(start 439.849514 -206.932276)
					(mid 439.845794 -206.941256)
					(end 439.836814 -206.944976)
				)
				(arc
					(start 438.363614 -206.944976)
					(mid 438.354634 -206.941256)
					(end 438.350914 -206.932276)
				)
				(arc
					(start 438.350914 -206.437738)
					(mid 438.354634 -206.428758)
					(end 438.363614 -206.425038)
				)
				(arc
					(start 439.836814 -206.425038)
					(mid 439.845794 -206.428758)
					(end 439.849514 -206.437738)
				)
			)
		)
	)
	(zone
		(layer "In1.Cu")
		(hatch none 0.5)
		(connect_pads
			(clearance 0)
		)
		(min_thickness 0.25)
		(keepout
			(tracks not_allowed)
			(vias allowed)
			(pads allowed)
			(copperpour not_allowed)
			(footprints allowed)
		)
		(placement
			(enabled no)
			(sheetname "")
		)
		(fill
			(thermal_gap 0.5)
			(thermal_bridge_width 0.5)
			(island_removal_mode 0)
		)
		(polygon
			(pts
				(arc
					(start 265.87831 -288.285174)
					(mid 265.21791 -288.285174)
					(end 265.87831 -288.285174)
				)
			)
		)
	)
	(zone
		(layer "In1.Cu")
		(hatch none 0.5)
		(connect_pads
			(clearance 0)
		)
		(min_thickness 0.25)
		(keepout
			(tracks not_allowed)
			(vias allowed)
			(pads allowed)
			(copperpour not_allowed)
			(footprints allowed)
		)
		(placement
			(enabled no)
			(sheetname "")
		)
		(fill
			(thermal_gap 0.5)
			(thermal_bridge_width 0.5)
			(island_removal_mode 0)
		)
		(polygon
			(pts
				(arc
					(start 25.901396 -220.532452)
					(mid 25.897676 -220.541432)
					(end 25.888696 -220.545152)
				)
				(arc
					(start 24.415496 -220.545152)
					(mid 24.406516 -220.541432)
					(end 24.402796 -220.532452)
				)
				(arc
					(start 24.402796 -220.037914)
					(mid 24.406516 -220.028934)
					(end 24.415496 -220.025214)
				)
				(arc
					(start 25.888696 -220.025214)
					(mid 25.897676 -220.028934)
					(end 25.901396 -220.037914)
				)
			)
		)
	)
	(zone
		(layer "In1.Cu")
		(hatch none 0.5)
		(connect_pads
			(clearance 0)
		)
		(min_thickness 0.25)
		(keepout
			(tracks not_allowed)
			(vias allowed)
			(pads allowed)
			(copperpour not_allowed)
			(footprints allowed)
		)
		(placement
			(enabled no)
			(sheetname "")
		)
		(fill
			(thermal_gap 0.5)
			(thermal_bridge_width 0.5)
			(island_removal_mode 0)
		)
		(polygon
			(pts
				(arc
					(start 45.089318 -222.232474)
					(mid 45.085598 -222.241454)
					(end 45.076618 -222.245174)
				)
				(arc
					(start 43.603418 -222.245174)
					(mid 43.594438 -222.241454)
					(end 43.590718 -222.232474)
				)
				(arc
					(start 43.590718 -221.737936)
					(mid 43.594438 -221.728956)
					(end 43.603418 -221.725236)
				)
				(arc
					(start 45.076618 -221.725236)
					(mid 45.085598 -221.728956)
					(end 45.089318 -221.737936)
				)
			)
		)
	)
	(zone
		(layer "In1.Cu")
		(hatch none 0.5)
		(connect_pads
			(clearance 0)
		)
		(min_thickness 0.25)
		(keepout
			(tracks not_allowed)
			(vias allowed)
			(pads allowed)
			(copperpour not_allowed)
			(footprints allowed)
		)
		(placement
			(enabled no)
			(sheetname "")
		)
		(fill
			(thermal_gap 0.5)
			(thermal_bridge_width 0.5)
			(island_removal_mode 0)
		)
		(polygon
			(pts
				(arc
					(start 337.416648 -384.288284)
					(mid 337.436572 -384.29752)
					(end 337.458304 -384.30073)
				)
				(arc
					(start 337.652868 -384.30073)
					(mid 337.70675 -384.278412)
					(end 337.729068 -384.22453)
				)
				(arc
					(start 337.729068 -383.53873)
					(mid 337.70675 -383.484848)
					(end 337.652868 -383.46253)
				)
				(arc
					(start 337.458304 -383.46253)
					(mid 337.43656 -383.465698)
					(end 337.416648 -383.474976)
				)
				(arc
					(start 337.120484 -383.667762)
					(mid 337.0788 -383.679984)
					(end 337.037172 -383.667508)
				)
				(arc
					(start 336.743548 -383.474976)
					(mid 336.723624 -383.46574)
					(end 336.701892 -383.46253)
				)
				(arc
					(start 336.507328 -383.46253)
					(mid 336.453446 -383.484848)
					(end 336.431128 -383.53873)
				)
				(arc
					(start 336.431128 -384.22453)
					(mid 336.453446 -384.278412)
					(end 336.507328 -384.30073)
				)
				(arc
					(start 336.703162 -384.30073)
					(mid 336.724906 -384.297562)
					(end 336.744818 -384.288284)
				)
				(arc
					(start 337.038442 -384.095752)
					(mid 337.080098 -384.08335)
					(end 337.121754 -384.095752)
				)
			)
		)
	)
	(zone
		(layer "In1.Cu")
		(hatch none 0.5)
		(connect_pads
			(clearance 0)
		)
		(min_thickness 0.25)
		(keepout
			(tracks not_allowed)
			(vias allowed)
			(pads allowed)
			(copperpour not_allowed)
			(footprints allowed)
		)
		(placement
			(enabled no)
			(sheetname "")
		)
		(fill
			(thermal_gap 0.5)
			(thermal_bridge_width 0.5)
			(island_removal_mode 0)
		)
		(polygon
			(pts
				(arc
					(start 48.533304 -201.832464)
					(mid 48.529584 -201.841444)
					(end 48.520604 -201.845164)
				)
				(arc
					(start 47.047404 -201.845164)
					(mid 47.038424 -201.841444)
					(end 47.034704 -201.832464)
				)
				(arc
					(start 47.034704 -201.337926)
					(mid 47.038424 -201.328946)
					(end 47.047404 -201.325226)
				)
				(arc
					(start 48.520604 -201.325226)
					(mid 48.529584 -201.328946)
					(end 48.533304 -201.337926)
				)
			)
		)
	)
	(zone
		(layer "In1.Cu")
		(hatch none 0.5)
		(connect_pads
			(clearance 0)
		)
		(min_thickness 0.25)
		(keepout
			(tracks not_allowed)
			(vias allowed)
			(pads allowed)
			(copperpour not_allowed)
			(footprints allowed)
		)
		(placement
			(enabled no)
			(sheetname "")
		)
		(fill
			(thermal_gap 0.5)
			(thermal_bridge_width 0.5)
			(island_removal_mode 0)
		)
		(polygon
			(pts
				(arc
					(start 266.29741 -221.382082)
					(mid 266.29369 -221.391062)
					(end 266.28471 -221.394782)
				)
				(arc
					(start 264.81151 -221.394782)
					(mid 264.80253 -221.391062)
					(end 264.79881 -221.382082)
				)
				(arc
					(start 264.79881 -220.887544)
					(mid 264.80253 -220.878564)
					(end 264.81151 -220.874844)
				)
				(arc
					(start 266.28471 -220.874844)
					(mid 266.29369 -220.878564)
					(end 266.29741 -220.887544)
				)
			)
		)
	)
	(zone
		(layer "In1.Cu")
		(hatch none 0.5)
		(connect_pads
			(clearance 0)
		)
		(min_thickness 0.25)
		(keepout
			(tracks not_allowed)
			(vias allowed)
			(pads allowed)
			(copperpour not_allowed)
			(footprints allowed)
		)
		(placement
			(enabled no)
			(sheetname "")
		)
		(fill
			(thermal_gap 0.5)
			(thermal_bridge_width 0.5)
			(island_removal_mode 0)
		)
		(polygon
			(pts
				(arc
					(start 172.72127 -316.582552)
					(mid 172.71755 -316.591532)
					(end 172.70857 -316.595252)
				)
				(arc
					(start 171.23537 -316.595252)
					(mid 171.22639 -316.591532)
					(end 171.22267 -316.582552)
				)
				(arc
					(start 171.22267 -316.088014)
					(mid 171.22639 -316.079034)
					(end 171.23537 -316.075314)
				)
				(arc
					(start 172.70857 -316.075314)
					(mid 172.71755 -316.079034)
					(end 172.72127 -316.088014)
				)
			)
		)
	)
	(zone
		(layer "In1.Cu")
		(hatch none 0.5)
		(connect_pads
			(clearance 0)
		)
		(min_thickness 0.25)
		(keepout
			(tracks not_allowed)
			(vias allowed)
			(pads allowed)
			(copperpour not_allowed)
			(footprints allowed)
		)
		(placement
			(enabled no)
			(sheetname "")
		)
		(fill
			(thermal_gap 0.5)
			(thermal_bridge_width 0.5)
			(island_removal_mode 0)
		)
		(polygon
			(pts
				(arc
					(start 273.841464 -305.532282)
					(mid 273.837744 -305.541262)
					(end 273.828764 -305.544982)
				)
				(arc
					(start 272.355564 -305.544982)
					(mid 272.346584 -305.541262)
					(end 272.342864 -305.532282)
				)
				(arc
					(start 272.342864 -305.037744)
					(mid 272.346584 -305.028764)
					(end 272.355564 -305.025044)
				)
				(arc
					(start 273.828764 -305.025044)
					(mid 273.837744 -305.028764)
					(end 273.841464 -305.037744)
				)
			)
		)
	)
	(zone
		(layer "In1.Cu")
		(hatch none 0.5)
		(connect_pads
			(clearance 0)
		)
		(min_thickness 0.25)
		(keepout
			(tracks not_allowed)
			(vias allowed)
			(pads allowed)
			(copperpour not_allowed)
			(footprints allowed)
		)
		(placement
			(enabled no)
			(sheetname "")
		)
		(fill
			(thermal_gap 0.5)
			(thermal_bridge_width 0.5)
			(island_removal_mode 0)
		)
		(polygon
			(pts
				(arc
					(start 33.445196 -296.182542)
					(mid 33.441476 -296.191522)
					(end 33.432496 -296.195242)
				)
				(arc
					(start 31.959296 -296.195242)
					(mid 31.950316 -296.191522)
					(end 31.946596 -296.182542)
				)
				(arc
					(start 31.946596 -295.688004)
					(mid 31.950316 -295.679024)
					(end 31.959296 -295.675304)
				)
				(arc
					(start 33.432496 -295.675304)
					(mid 33.441476 -295.679024)
					(end 33.445196 -295.688004)
				)
			)
		)
	)
	(zone
		(layer "In1.Cu")
		(hatch none 0.5)
		(connect_pads
			(clearance 0)
		)
		(min_thickness 0.25)
		(keepout
			(tracks not_allowed)
			(vias allowed)
			(pads allowed)
			(copperpour not_allowed)
			(footprints allowed)
		)
		(placement
			(enabled no)
			(sheetname "")
		)
		(fill
			(thermal_gap 0.5)
			(thermal_bridge_width 0.5)
			(island_removal_mode 0)
		)
		(polygon
			(pts
				(arc
					(start 172.72127 -312.33237)
					(mid 172.71755 -312.34135)
					(end 172.70857 -312.34507)
				)
				(arc
					(start 171.23537 -312.34507)
					(mid 171.22639 -312.34135)
					(end 171.22267 -312.33237)
				)
				(arc
					(start 171.22267 -311.837832)
					(mid 171.22639 -311.828852)
					(end 171.23537 -311.825132)
				)
				(arc
					(start 172.70857 -311.825132)
					(mid 172.71755 -311.828852)
					(end 172.72127 -311.837832)
				)
			)
		)
	)
	(zone
		(layer "In1.Cu")
		(hatch none 0.5)
		(connect_pads
			(clearance 0)
		)
		(min_thickness 0.25)
		(keepout
			(tracks not_allowed)
			(vias allowed)
			(pads allowed)
			(copperpour not_allowed)
			(footprints allowed)
		)
		(placement
			(enabled no)
			(sheetname "")
		)
		(fill
			(thermal_gap 0.5)
			(thermal_bridge_width 0.5)
			(island_removal_mode 0)
		)
		(polygon
			(pts
				(arc
					(start 420.28872 -397.849344)
					(mid 419.90772 -397.849344)
					(end 420.28872 -397.849344)
				)
			)
		)
	)
	(zone
		(layer "In1.Cu")
		(hatch none 0.5)
		(connect_pads
			(clearance 0)
		)
		(min_thickness 0.25)
		(keepout
			(tracks not_allowed)
			(vias allowed)
			(pads allowed)
			(copperpour not_allowed)
			(footprints allowed)
		)
		(placement
			(enabled no)
			(sheetname "")
		)
		(fill
			(thermal_gap 0.5)
			(thermal_bridge_width 0.5)
			(island_removal_mode 0)
		)
		(polygon
			(pts
				(arc
					(start 335.518506 -391.822686)
					(mid 335.645506 -391.949686)
					(end 335.772506 -391.822686)
				)
				(arc
					(start 335.772506 -391.746486)
					(mid 335.645506 -391.619486)
					(end 335.518506 -391.746486)
				)
			)
		)
	)
	(zone
		(layer "In1.Cu")
		(hatch none 0.5)
		(connect_pads
			(clearance 0)
		)
		(min_thickness 0.25)
		(keepout
			(tracks not_allowed)
			(vias allowed)
			(pads allowed)
			(copperpour not_allowed)
			(footprints allowed)
		)
		(placement
			(enabled no)
			(sheetname "")
		)
		(fill
			(thermal_gap 0.5)
			(thermal_bridge_width 0.5)
			(island_removal_mode 0)
		)
		(polygon
			(pts
				(arc
					(start 387.470396 -392.30427)
					(mid 387.165596 -392.30427)
					(end 387.470396 -392.30427)
				)
			)
		)
	)
	(zone
		(layer "In1.Cu")
		(hatch none 0.5)
		(connect_pads
			(clearance 0)
		)
		(min_thickness 0.25)
		(keepout
			(tracks not_allowed)
			(vias allowed)
			(pads allowed)
			(copperpour not_allowed)
			(footprints allowed)
		)
		(placement
			(enabled no)
			(sheetname "")
		)
		(fill
			(thermal_gap 0.5)
			(thermal_bridge_width 0.5)
			(island_removal_mode 0)
		)
		(polygon
			(pts
				(arc
					(start 176.821338 -199.282558)
					(mid 176.817618 -199.291538)
					(end 176.808638 -199.295258)
				)
				(arc
					(start 175.335438 -199.295258)
					(mid 175.326458 -199.291538)
					(end 175.322738 -199.282558)
				)
				(arc
					(start 175.322738 -198.78802)
					(mid 175.326458 -198.77904)
					(end 175.335438 -198.77532)
				)
				(arc
					(start 176.808638 -198.77532)
					(mid 176.817618 -198.77904)
					(end 176.821338 -198.78802)
				)
			)
		)
	)
	(zone
		(layer "In1.Cu")
		(hatch none 0.5)
		(connect_pads
			(clearance 0)
		)
		(min_thickness 0.25)
		(keepout
			(tracks not_allowed)
			(vias allowed)
			(pads allowed)
			(copperpour not_allowed)
			(footprints allowed)
		)
		(placement
			(enabled no)
			(sheetname "")
		)
		(fill
			(thermal_gap 0.5)
			(thermal_bridge_width 0.5)
			(island_removal_mode 0)
		)
		(polygon
			(pts
				(arc
					(start 288.929318 -254.53213)
					(mid 288.925598 -254.54111)
					(end 288.916618 -254.54483)
				)
				(arc
					(start 287.443418 -254.54483)
					(mid 287.434438 -254.54111)
					(end 287.430718 -254.53213)
				)
				(arc
					(start 287.430718 -254.037592)
					(mid 287.434438 -254.028612)
					(end 287.443418 -254.024892)
				)
				(arc
					(start 288.916618 -254.024892)
					(mid 288.925598 -254.028612)
					(end 288.929318 -254.037592)
				)
			)
		)
	)
	(zone
		(layer "In1.Cu")
		(hatch none 0.5)
		(connect_pads
			(clearance 0)
		)
		(min_thickness 0.25)
		(keepout
			(tracks not_allowed)
			(vias allowed)
			(pads allowed)
			(copperpour not_allowed)
			(footprints allowed)
		)
		(placement
			(enabled no)
			(sheetname "")
		)
		(fill
			(thermal_gap 0.5)
			(thermal_bridge_width 0.5)
			(island_removal_mode 0)
		)
		(polygon
			(pts
				(arc
					(start 128.961134 -385.31038)
					(mid 128.580134 -385.31038)
					(end 128.961134 -385.31038)
				)
			)
		)
	)
	(zone
		(layer "In1.Cu")
		(hatch none 0.5)
		(connect_pads
			(clearance 0)
		)
		(min_thickness 0.25)
		(keepout
			(tracks not_allowed)
			(vias allowed)
			(pads allowed)
			(copperpour not_allowed)
			(footprints allowed)
		)
		(placement
			(enabled no)
			(sheetname "")
		)
		(fill
			(thermal_gap 0.5)
			(thermal_bridge_width 0.5)
			(island_removal_mode 0)
		)
		(polygon
			(pts
				(arc
					(start 352.318574 -391.822686)
					(mid 352.445574 -391.949686)
					(end 352.572574 -391.822686)
				)
				(arc
					(start 352.572574 -391.746486)
					(mid 352.445574 -391.619486)
					(end 352.318574 -391.746486)
				)
			)
		)
	)
	(zone
		(layer "In1.Cu")
		(hatch none 0.5)
		(connect_pads
			(clearance 0)
		)
		(min_thickness 0.25)
		(keepout
			(tracks not_allowed)
			(vias allowed)
			(pads allowed)
			(copperpour not_allowed)
			(footprints allowed)
		)
		(placement
			(enabled no)
			(sheetname "")
		)
		(fill
			(thermal_gap 0.5)
			(thermal_bridge_width 0.5)
			(island_removal_mode 0)
		)
		(polygon
			(pts
				(arc
					(start 63.170308 -383.92227)
					(mid 62.865508 -383.92227)
					(end 63.170308 -383.92227)
				)
			)
		)
	)
	(zone
		(layer "In1.Cu")
		(hatch none 0.5)
		(connect_pads
			(clearance 0)
		)
		(min_thickness 0.25)
		(keepout
			(tracks not_allowed)
			(vias allowed)
			(pads allowed)
			(copperpour not_allowed)
			(footprints allowed)
		)
		(placement
			(enabled no)
			(sheetname "")
		)
		(fill
			(thermal_gap 0.5)
			(thermal_bridge_width 0.5)
			(island_removal_mode 0)
		)
		(polygon
			(pts
				(arc
					(start 176.821338 -246.032528)
					(mid 176.817618 -246.041508)
					(end 176.808638 -246.045228)
				)
				(arc
					(start 175.335438 -246.045228)
					(mid 175.326458 -246.041508)
					(end 175.322738 -246.032528)
				)
				(arc
					(start 175.322738 -245.53799)
					(mid 175.326458 -245.52901)
					(end 175.335438 -245.52529)
				)
				(arc
					(start 176.808638 -245.52529)
					(mid 176.817618 -245.52901)
					(end 176.821338 -245.53799)
				)
			)
		)
	)
	(zone
		(layer "In1.Cu")
		(hatch none 0.5)
		(connect_pads
			(clearance 0)
		)
		(min_thickness 0.25)
		(keepout
			(tracks not_allowed)
			(vias allowed)
			(pads allowed)
			(copperpour not_allowed)
			(footprints allowed)
		)
		(placement
			(enabled no)
			(sheetname "")
		)
		(fill
			(thermal_gap 0.5)
			(thermal_bridge_width 0.5)
			(island_removal_mode 0)
		)
		(polygon
			(pts
				(arc
					(start 184.365392 -276.632416)
					(mid 184.361672 -276.641396)
					(end 184.352692 -276.645116)
				)
				(arc
					(start 182.879492 -276.645116)
					(mid 182.870512 -276.641396)
					(end 182.866792 -276.632416)
				)
				(arc
					(start 182.866792 -276.137878)
					(mid 182.870512 -276.128898)
					(end 182.879492 -276.125178)
				)
				(arc
					(start 184.352692 -276.125178)
					(mid 184.361672 -276.128898)
					(end 184.365392 -276.137878)
				)
			)
		)
	)
	(zone
		(layer "In1.Cu")
		(hatch none 0.5)
		(connect_pads
			(clearance 0)
		)
		(min_thickness 0.25)
		(keepout
			(tracks not_allowed)
			(vias allowed)
			(pads allowed)
			(copperpour not_allowed)
			(footprints allowed)
		)
		(placement
			(enabled no)
			(sheetname "")
		)
		(fill
			(thermal_gap 0.5)
			(thermal_bridge_width 0.5)
			(island_removal_mode 0)
		)
		(polygon
			(pts
				(arc
					(start 92.388944 -389.467344)
					(mid 92.007944 -389.467344)
					(end 92.388944 -389.467344)
				)
			)
		)
	)
	(zone
		(layer "In1.Cu")
		(hatch none 0.5)
		(connect_pads
			(clearance 0)
		)
		(min_thickness 0.25)
		(keepout
			(tracks not_allowed)
			(vias allowed)
			(pads allowed)
			(copperpour not_allowed)
			(footprints allowed)
		)
		(placement
			(enabled no)
			(sheetname "")
		)
		(fill
			(thermal_gap 0.5)
			(thermal_bridge_width 0.5)
			(island_removal_mode 0)
		)
		(polygon
			(pts
				(arc
					(start 285.485332 -317.432182)
					(mid 285.481612 -317.441162)
					(end 285.472632 -317.444882)
				)
				(arc
					(start 283.999432 -317.444882)
					(mid 283.990452 -317.441162)
					(end 283.986732 -317.432182)
				)
				(arc
					(start 283.986732 -316.937644)
					(mid 283.990452 -316.928664)
					(end 283.999432 -316.924944)
				)
				(arc
					(start 285.472632 -316.924944)
					(mid 285.481612 -316.928664)
					(end 285.485332 -316.937644)
				)
			)
		)
	)
	(zone
		(layer "In1.Cu")
		(hatch none 0.5)
		(connect_pads
			(clearance 0)
		)
		(min_thickness 0.25)
		(keepout
			(tracks not_allowed)
			(vias allowed)
			(pads allowed)
			(copperpour not_allowed)
			(footprints allowed)
		)
		(placement
			(enabled no)
			(sheetname "")
		)
		(fill
			(thermal_gap 0.5)
			(thermal_bridge_width 0.5)
			(island_removal_mode 0)
		)
		(polygon
			(pts
				(arc
					(start 293.029386 -199.282304)
					(mid 293.025666 -199.291284)
					(end 293.016686 -199.295004)
				)
				(arc
					(start 291.543486 -199.295004)
					(mid 291.534506 -199.291284)
					(end 291.530786 -199.282304)
				)
				(arc
					(start 291.530786 -198.787766)
					(mid 291.534506 -198.778786)
					(end 291.543486 -198.775066)
				)
				(arc
					(start 293.016686 -198.775066)
					(mid 293.025666 -198.778786)
					(end 293.029386 -198.787766)
				)
			)
		)
	)
	(zone
		(layer "In1.Cu")
		(hatch none 0.5)
		(connect_pads
			(clearance 0)
		)
		(min_thickness 0.25)
		(keepout
			(tracks not_allowed)
			(vias allowed)
			(pads allowed)
			(copperpour not_allowed)
			(footprints allowed)
		)
		(placement
			(enabled no)
			(sheetname "")
		)
		(fill
			(thermal_gap 0.5)
			(thermal_bridge_width 0.5)
			(island_removal_mode 0)
		)
		(polygon
			(pts
				(arc
					(start 435.749446 -245.182136)
					(mid 435.745726 -245.191116)
					(end 435.736746 -245.194836)
				)
				(arc
					(start 434.263546 -245.194836)
					(mid 434.254566 -245.191116)
					(end 434.250846 -245.182136)
				)
				(arc
					(start 434.250846 -244.687598)
					(mid 434.254566 -244.678618)
					(end 434.263546 -244.674898)
				)
				(arc
					(start 435.736746 -244.674898)
					(mid 435.745726 -244.678618)
					(end 435.749446 -244.687598)
				)
			)
		)
	)
	(zone
		(layer "In1.Cu")
		(hatch none 0.5)
		(connect_pads
			(clearance 0)
		)
		(min_thickness 0.25)
		(keepout
			(tracks not_allowed)
			(vias allowed)
			(pads allowed)
			(copperpour not_allowed)
			(footprints allowed)
		)
		(placement
			(enabled no)
			(sheetname "")
		)
		(fill
			(thermal_gap 0.5)
			(thermal_bridge_width 0.5)
			(island_removal_mode 0)
		)
		(polygon
			(pts
				(arc
					(start 277.941532 -239.232186)
					(mid 277.937812 -239.241166)
					(end 277.928832 -239.244886)
				)
				(arc
					(start 276.455632 -239.244886)
					(mid 276.446652 -239.241166)
					(end 276.442932 -239.232186)
				)
				(arc
					(start 276.442932 -238.737648)
					(mid 276.446652 -238.728668)
					(end 276.455632 -238.724948)
				)
				(arc
					(start 277.928832 -238.724948)
					(mid 277.937812 -238.728668)
					(end 277.941532 -238.737648)
				)
			)
		)
	)
	(zone
		(layer "In1.Cu")
		(hatch none 0.5)
		(connect_pads
			(clearance 0)
		)
		(min_thickness 0.25)
		(keepout
			(tracks not_allowed)
			(vias allowed)
			(pads allowed)
			(copperpour not_allowed)
			(footprints allowed)
		)
		(placement
			(enabled no)
			(sheetname "")
		)
		(fill
			(thermal_gap 0.5)
			(thermal_bridge_width 0.5)
			(island_removal_mode 0)
		)
		(polygon
			(pts
				(arc
					(start 395.152118 -7.672324)
					(mid 395.174436 -7.618442)
					(end 395.228318 -7.596124)
				)
				(arc
					(start 396.264892 -7.596124)
					(mid 396.318774 -7.618442)
					(end 396.341092 -7.672324)
				)
				(arc
					(start 396.341092 -9.071864)
					(mid 396.318774 -9.125746)
					(end 396.264892 -9.148064)
				)
				(arc
					(start 395.228318 -9.148064)
					(mid 395.174436 -9.125746)
					(end 395.152118 -9.071864)
				)
			)
		)
	)
	(zone
		(layer "In1.Cu")
		(hatch none 0.5)
		(connect_pads
			(clearance 0)
		)
		(min_thickness 0.25)
		(keepout
			(tracks not_allowed)
			(vias allowed)
			(pads allowed)
			(copperpour not_allowed)
			(footprints allowed)
		)
		(placement
			(enabled no)
			(sheetname "")
		)
		(fill
			(thermal_gap 0.5)
			(thermal_bridge_width 0.5)
			(island_removal_mode 0)
		)
		(polygon
			(pts
				(arc
					(start 60.177426 -233.28249)
					(mid 60.173706 -233.29147)
					(end 60.164726 -233.29519)
				)
				(arc
					(start 58.691526 -233.29519)
					(mid 58.682546 -233.29147)
					(end 58.678826 -233.28249)
				)
				(arc
					(start 58.678826 -232.787952)
					(mid 58.682546 -232.778972)
					(end 58.691526 -232.775252)
				)
				(arc
					(start 60.164726 -232.775252)
					(mid 60.173706 -232.778972)
					(end 60.177426 -232.787952)
				)
			)
		)
	)
	(zone
		(layer "In1.Cu")
		(hatch none 0.5)
		(connect_pads
			(clearance 0)
		)
		(min_thickness 0.25)
		(keepout
			(tracks not_allowed)
			(vias allowed)
			(pads allowed)
			(copperpour not_allowed)
			(footprints allowed)
		)
		(placement
			(enabled no)
			(sheetname "")
		)
		(fill
			(thermal_gap 0.5)
			(thermal_bridge_width 0.5)
			(island_removal_mode 0)
		)
		(polygon
			(pts
				(arc
					(start 52.633372 -274.08251)
					(mid 52.629652 -274.09149)
					(end 52.620672 -274.09521)
				)
				(arc
					(start 51.147472 -274.09521)
					(mid 51.138492 -274.09149)
					(end 51.134772 -274.08251)
				)
				(arc
					(start 51.134772 -273.587972)
					(mid 51.138492 -273.578992)
					(end 51.147472 -273.575272)
				)
				(arc
					(start 52.620672 -273.575272)
					(mid 52.629652 -273.578992)
					(end 52.633372 -273.587972)
				)
			)
		)
	)
	(zone
		(layer "In1.Cu")
		(hatch none 0.5)
		(connect_pads
			(clearance 0)
		)
		(min_thickness 0.25)
		(keepout
			(tracks not_allowed)
			(vias allowed)
			(pads allowed)
			(copperpour not_allowed)
			(footprints allowed)
		)
		(placement
			(enabled no)
			(sheetname "")
		)
		(fill
			(thermal_gap 0.5)
			(thermal_bridge_width 0.5)
			(island_removal_mode 0)
		)
		(polygon
			(pts
				(arc
					(start 281.385264 -213.73211)
					(mid 281.381544 -213.74109)
					(end 281.372564 -213.74481)
				)
				(arc
					(start 279.899364 -213.74481)
					(mid 279.890384 -213.74109)
					(end 279.886664 -213.73211)
				)
				(arc
					(start 279.886664 -213.237572)
					(mid 279.890384 -213.228592)
					(end 279.899364 -213.224872)
				)
				(arc
					(start 281.372564 -213.224872)
					(mid 281.381544 -213.228592)
					(end 281.385264 -213.237572)
				)
			)
		)
	)
	(zone
		(layer "In1.Cu")
		(hatch none 0.5)
		(connect_pads
			(clearance 0)
		)
		(min_thickness 0.25)
		(keepout
			(tracks not_allowed)
			(vias allowed)
			(pads allowed)
			(copperpour not_allowed)
			(footprints allowed)
		)
		(placement
			(enabled no)
			(sheetname "")
		)
		(fill
			(thermal_gap 0.5)
			(thermal_bridge_width 0.5)
			(island_removal_mode 0)
		)
		(polygon
			(pts
				(arc
					(start 454.937368 -302.132238)
					(mid 454.933648 -302.141218)
					(end 454.924668 -302.144938)
				)
				(arc
					(start 453.451468 -302.144938)
					(mid 453.442488 -302.141218)
					(end 453.438768 -302.132238)
				)
				(arc
					(start 453.438768 -301.6377)
					(mid 453.442488 -301.62872)
					(end 453.451468 -301.625)
				)
				(arc
					(start 454.924668 -301.625)
					(mid 454.933648 -301.62872)
					(end 454.937368 -301.6377)
				)
			)
		)
	)
	(zone
		(layer "In1.Cu")
		(hatch none 0.5)
		(connect_pads
			(clearance 0)
		)
		(min_thickness 0.25)
		(keepout
			(tracks not_allowed)
			(vias allowed)
			(pads allowed)
			(copperpour not_allowed)
			(footprints allowed)
		)
		(placement
			(enabled no)
			(sheetname "")
		)
		(fill
			(thermal_gap 0.5)
			(thermal_bridge_width 0.5)
			(island_removal_mode 0)
		)
		(polygon
			(pts
				(arc
					(start 25.901396 -277.482554)
					(mid 25.897676 -277.491534)
					(end 25.888696 -277.495254)
				)
				(arc
					(start 24.415496 -277.495254)
					(mid 24.406516 -277.491534)
					(end 24.402796 -277.482554)
				)
				(arc
					(start 24.402796 -276.988016)
					(mid 24.406516 -276.979036)
					(end 24.415496 -276.975316)
				)
				(arc
					(start 25.888696 -276.975316)
					(mid 25.897676 -276.979036)
					(end 25.901396 -276.988016)
				)
			)
		)
	)
	(zone
		(layer "In1.Cu")
		(hatch none 0.5)
		(connect_pads
			(clearance 0)
		)
		(min_thickness 0.25)
		(keepout
			(tracks not_allowed)
			(vias allowed)
			(pads allowed)
			(copperpour not_allowed)
			(footprints allowed)
		)
		(placement
			(enabled no)
			(sheetname "")
		)
		(fill
			(thermal_gap 0.5)
			(thermal_bridge_width 0.5)
			(island_removal_mode 0)
		)
		(polygon
			(pts
				(arc
					(start 344.223848 -384.288284)
					(mid 344.243772 -384.29752)
					(end 344.265504 -384.30073)
				)
				(arc
					(start 344.460068 -384.30073)
					(mid 344.51395 -384.278412)
					(end 344.536268 -384.22453)
				)
				(arc
					(start 344.536268 -383.53873)
					(mid 344.51395 -383.484848)
					(end 344.460068 -383.46253)
				)
				(arc
					(start 344.265504 -383.46253)
					(mid 344.24376 -383.465698)
					(end 344.223848 -383.474976)
				)
				(arc
					(start 343.927684 -383.667762)
					(mid 343.886 -383.679984)
					(end 343.844372 -383.667508)
				)
				(arc
					(start 343.550748 -383.474976)
					(mid 343.530824 -383.46574)
					(end 343.509092 -383.46253)
				)
				(arc
					(start 343.314528 -383.46253)
					(mid 343.260646 -383.484848)
					(end 343.238328 -383.53873)
				)
				(arc
					(start 343.238328 -384.22453)
					(mid 343.260646 -384.278412)
					(end 343.314528 -384.30073)
				)
				(arc
					(start 343.510362 -384.30073)
					(mid 343.532106 -384.297562)
					(end 343.552018 -384.288284)
				)
				(arc
					(start 343.845642 -384.095752)
					(mid 343.887298 -384.08335)
					(end 343.928954 -384.095752)
				)
			)
		)
	)
	(zone
		(layer "In1.Cu")
		(hatch none 0.5)
		(connect_pads
			(clearance 0)
		)
		(min_thickness 0.25)
		(keepout
			(tracks not_allowed)
			(vias allowed)
			(pads allowed)
			(copperpour not_allowed)
			(footprints allowed)
		)
		(placement
			(enabled no)
			(sheetname "")
		)
		(fill
			(thermal_gap 0.5)
			(thermal_bridge_width 0.5)
			(island_removal_mode 0)
		)
		(polygon
			(pts
				(arc
					(start 191.909446 -281.732482)
					(mid 191.905726 -281.741462)
					(end 191.896746 -281.745182)
				)
				(arc
					(start 190.423546 -281.745182)
					(mid 190.414566 -281.741462)
					(end 190.410846 -281.732482)
				)
				(arc
					(start 190.410846 -281.237944)
					(mid 190.414566 -281.228964)
					(end 190.423546 -281.225244)
				)
				(arc
					(start 191.896746 -281.225244)
					(mid 191.905726 -281.228964)
					(end 191.909446 -281.237944)
				)
			)
		)
	)
	(zone
		(layer "In1.Cu")
		(hatch none 0.5)
		(connect_pads
			(clearance 0)
		)
		(min_thickness 0.25)
		(keepout
			(tracks not_allowed)
			(vias allowed)
			(pads allowed)
			(copperpour not_allowed)
			(footprints allowed)
		)
		(placement
			(enabled no)
			(sheetname "")
		)
		(fill
			(thermal_gap 0.5)
			(thermal_bridge_width 0.5)
			(island_removal_mode 0)
		)
		(polygon
			(pts
				(arc
					(start 382.961134 -394.385292)
					(mid 382.580134 -394.385292)
					(end 382.961134 -394.385292)
				)
			)
		)
	)
	(zone
		(layer "In1.Cu")
		(hatch none 0.5)
		(connect_pads
			(clearance 0)
		)
		(min_thickness 0.25)
		(keepout
			(tracks not_allowed)
			(vias allowed)
			(pads allowed)
			(copperpour not_allowed)
			(footprints allowed)
		)
		(placement
			(enabled no)
			(sheetname "")
		)
		(fill
			(thermal_gap 0.5)
			(thermal_bridge_width 0.5)
			(island_removal_mode 0)
		)
		(polygon
			(pts
				(arc
					(start 338.788502 -394.385292)
					(mid 338.407502 -394.385292)
					(end 338.788502 -394.385292)
				)
			)
		)
	)
	(zone
		(layer "In1.Cu")
		(hatch none 0.5)
		(connect_pads
			(clearance 0)
		)
		(min_thickness 0.25)
		(keepout
			(tracks not_allowed)
			(vias allowed)
			(pads allowed)
			(copperpour not_allowed)
			(footprints allowed)
		)
		(placement
			(enabled no)
			(sheetname "")
		)
		(fill
			(thermal_gap 0.5)
			(thermal_bridge_width 0.5)
			(island_removal_mode 0)
		)
		(polygon
			(pts
				(arc
					(start 163.088828 -386.003292)
					(mid 162.707828 -386.003292)
					(end 163.088828 -386.003292)
				)
			)
		)
	)
	(zone
		(layer "In1.Cu")
		(hatch none 0.5)
		(connect_pads
			(clearance 0)
		)
		(min_thickness 0.25)
		(keepout
			(tracks not_allowed)
			(vias allowed)
			(pads allowed)
			(copperpour not_allowed)
			(footprints allowed)
		)
		(placement
			(enabled no)
			(sheetname "")
		)
		(fill
			(thermal_gap 0.5)
			(thermal_bridge_width 0.5)
			(island_removal_mode 0)
		)
		(polygon
			(pts
				(arc
					(start 184.365392 -252.832362)
					(mid 184.361672 -252.841342)
					(end 184.352692 -252.845062)
				)
				(arc
					(start 182.879492 -252.845062)
					(mid 182.870512 -252.841342)
					(end 182.866792 -252.832362)
				)
				(arc
					(start 182.866792 -252.337824)
					(mid 182.870512 -252.328844)
					(end 182.879492 -252.325124)
				)
				(arc
					(start 184.352692 -252.325124)
					(mid 184.361672 -252.328844)
					(end 184.365392 -252.337824)
				)
			)
		)
	)
	(zone
		(layer "In1.Cu")
		(hatch none 0.5)
		(connect_pads
			(clearance 0)
		)
		(min_thickness 0.25)
		(keepout
			(tracks not_allowed)
			(vias allowed)
			(pads allowed)
			(copperpour not_allowed)
			(footprints allowed)
		)
		(placement
			(enabled no)
			(sheetname "")
		)
		(fill
			(thermal_gap 0.5)
			(thermal_bridge_width 0.5)
			(island_removal_mode 0)
		)
		(polygon
			(pts
				(arc
					(start 428.205392 -223.082104)
					(mid 428.201672 -223.091084)
					(end 428.192692 -223.094804)
				)
				(arc
					(start 426.719492 -223.094804)
					(mid 426.710512 -223.091084)
					(end 426.706792 -223.082104)
				)
				(arc
					(start 426.706792 -222.587566)
					(mid 426.710512 -222.578586)
					(end 426.719492 -222.574866)
				)
				(arc
					(start 428.192692 -222.574866)
					(mid 428.201672 -222.578586)
					(end 428.205392 -222.587566)
				)
			)
		)
	)
	(zone
		(layer "In1.Cu")
		(hatch none 0.5)
		(connect_pads
			(clearance 0)
		)
		(min_thickness 0.25)
		(keepout
			(tracks not_allowed)
			(vias allowed)
			(pads allowed)
			(copperpour not_allowed)
			(footprints allowed)
		)
		(placement
			(enabled no)
			(sheetname "")
		)
		(fill
			(thermal_gap 0.5)
			(thermal_bridge_width 0.5)
			(island_removal_mode 0)
		)
		(polygon
			(pts
				(arc
					(start 184.365392 -214.582502)
					(mid 184.361672 -214.591482)
					(end 184.352692 -214.595202)
				)
				(arc
					(start 182.879492 -214.595202)
					(mid 182.870512 -214.591482)
					(end 182.866792 -214.582502)
				)
				(arc
					(start 182.866792 -214.087964)
					(mid 182.870512 -214.078984)
					(end 182.879492 -214.075264)
				)
				(arc
					(start 184.352692 -214.075264)
					(mid 184.361672 -214.078984)
					(end 184.365392 -214.087964)
				)
			)
		)
	)
	(zone
		(layer "In1.Cu")
		(hatch none 0.5)
		(connect_pads
			(clearance 0)
		)
		(min_thickness 0.25)
		(keepout
			(tracks not_allowed)
			(vias allowed)
			(pads allowed)
			(copperpour not_allowed)
			(footprints allowed)
		)
		(placement
			(enabled no)
			(sheetname "")
		)
		(fill
			(thermal_gap 0.5)
			(thermal_bridge_width 0.5)
			(island_removal_mode 0)
		)
		(polygon
			(pts
				(arc
					(start 307.79085 -391.822686)
					(mid 307.91785 -391.949686)
					(end 308.04485 -391.822686)
				)
				(arc
					(start 308.04485 -391.746486)
					(mid 307.91785 -391.619486)
					(end 307.79085 -391.746486)
				)
			)
		)
	)
	(zone
		(layer "In1.Cu")
		(hatch none 0.5)
		(connect_pads
			(clearance 0)
		)
		(min_thickness 0.25)
		(keepout
			(tracks not_allowed)
			(vias allowed)
			(pads allowed)
			(copperpour not_allowed)
			(footprints allowed)
		)
		(placement
			(enabled no)
			(sheetname "")
		)
		(fill
			(thermal_gap 0.5)
			(thermal_bridge_width 0.5)
			(island_removal_mode 0)
		)
		(polygon
			(pts
				(arc
					(start 454.937368 -249.432318)
					(mid 454.933648 -249.441298)
					(end 454.924668 -249.445018)
				)
				(arc
					(start 453.451468 -249.445018)
					(mid 453.442488 -249.441298)
					(end 453.438768 -249.432318)
				)
				(arc
					(start 453.438768 -248.93778)
					(mid 453.442488 -248.9288)
					(end 453.451468 -248.92508)
				)
				(arc
					(start 454.924668 -248.92508)
					(mid 454.933648 -248.9288)
					(end 454.937368 -248.93778)
				)
			)
		)
	)
	(zone
		(layer "In1.Cu")
		(hatch none 0.5)
		(connect_pads
			(clearance 0)
		)
		(min_thickness 0.25)
		(keepout
			(tracks not_allowed)
			(vias allowed)
			(pads allowed)
			(copperpour not_allowed)
			(footprints allowed)
		)
		(placement
			(enabled no)
			(sheetname "")
		)
		(fill
			(thermal_gap 0.5)
			(thermal_bridge_width 0.5)
			(island_removal_mode 0)
		)
		(polygon
			(pts
				(arc
					(start 381.760984 -397.849344)
					(mid 381.379984 -397.849344)
					(end 381.760984 -397.849344)
				)
			)
		)
	)
	(zone
		(layer "In1.Cu")
		(hatch none 0.5)
		(connect_pads
			(clearance 0)
		)
		(min_thickness 0.25)
		(keepout
			(tracks not_allowed)
			(vias allowed)
			(pads allowed)
			(copperpour not_allowed)
			(footprints allowed)
		)
		(placement
			(enabled no)
			(sheetname "")
		)
		(fill
			(thermal_gap 0.5)
			(thermal_bridge_width 0.5)
			(island_removal_mode 0)
		)
		(polygon
			(pts
				(arc
					(start 285.485332 -211.182204)
					(mid 285.481612 -211.191184)
					(end 285.472632 -211.194904)
				)
				(arc
					(start 283.999432 -211.194904)
					(mid 283.990452 -211.191184)
					(end 283.986732 -211.182204)
				)
				(arc
					(start 283.986732 -210.687666)
					(mid 283.990452 -210.678686)
					(end 283.999432 -210.674966)
				)
				(arc
					(start 285.472632 -210.674966)
					(mid 285.481612 -210.678686)
					(end 285.485332 -210.687666)
				)
			)
		)
	)
	(zone
		(layer "In1.Cu")
		(hatch none 0.5)
		(connect_pads
			(clearance 0)
		)
		(min_thickness 0.25)
		(keepout
			(tracks not_allowed)
			(vias allowed)
			(pads allowed)
			(copperpour not_allowed)
			(footprints allowed)
		)
		(placement
			(enabled no)
			(sheetname "")
		)
		(fill
			(thermal_gap 0.5)
			(thermal_bridge_width 0.5)
			(island_removal_mode 0)
		)
		(polygon
			(pts
				(arc
					(start 380.161292 -397.156432)
					(mid 379.780292 -397.156432)
					(end 380.161292 -397.156432)
				)
			)
		)
	)
	(zone
		(layer "In1.Cu")
		(hatch none 0.5)
		(connect_pads
			(clearance 0)
		)
		(min_thickness 0.25)
		(keepout
			(tracks not_allowed)
			(vias allowed)
			(pads allowed)
			(copperpour not_allowed)
			(footprints allowed)
		)
		(placement
			(enabled no)
			(sheetname "")
		)
		(fill
			(thermal_gap 0.5)
			(thermal_bridge_width 0.5)
			(island_removal_mode 0)
		)
		(polygon
			(pts
				(arc
					(start 300.57344 -223.932242)
					(mid 300.56972 -223.941222)
					(end 300.56074 -223.944942)
				)
				(arc
					(start 299.08754 -223.944942)
					(mid 299.07856 -223.941222)
					(end 299.07484 -223.932242)
				)
				(arc
					(start 299.07484 -223.437704)
					(mid 299.07856 -223.428724)
					(end 299.08754 -223.425004)
				)
				(arc
					(start 300.56074 -223.425004)
					(mid 300.56972 -223.428724)
					(end 300.57344 -223.437704)
				)
			)
		)
	)
	(zone
		(layer "In1.Cu")
		(hatch none 0.5)
		(connect_pads
			(clearance 0)
		)
		(min_thickness 0.25)
		(keepout
			(tracks not_allowed)
			(vias allowed)
			(pads allowed)
			(copperpour not_allowed)
			(footprints allowed)
		)
		(placement
			(enabled no)
			(sheetname "")
		)
		(fill
			(thermal_gap 0.5)
			(thermal_bridge_width 0.5)
			(island_removal_mode 0)
		)
		(polygon
			(pts
				(arc
					(start 132.670296 -390.761474)
					(mid 132.365496 -390.761474)
					(end 132.670296 -390.761474)
				)
			)
		)
	)
	(zone
		(layer "In1.Cu")
		(hatch none 0.5)
		(connect_pads
			(clearance 0)
		)
		(min_thickness 0.25)
		(keepout
			(tracks not_allowed)
			(vias allowed)
			(pads allowed)
			(copperpour not_allowed)
			(footprints allowed)
		)
		(placement
			(enabled no)
			(sheetname "")
		)
		(fill
			(thermal_gap 0.5)
			(thermal_bridge_width 0.5)
			(island_removal_mode 0)
		)
		(polygon
			(pts
				(arc
					(start 120.561354 -385.31038)
					(mid 120.180354 -385.31038)
					(end 120.561354 -385.31038)
				)
			)
		)
	)
	(zone
		(layer "In1.Cu")
		(hatch none 0.5)
		(connect_pads
			(clearance 0)
		)
		(min_thickness 0.25)
		(keepout
			(tracks not_allowed)
			(vias allowed)
			(pads allowed)
			(copperpour not_allowed)
			(footprints allowed)
		)
		(placement
			(enabled no)
			(sheetname "")
		)
		(fill
			(thermal_gap 0.5)
			(thermal_bridge_width 0.5)
			(island_removal_mode 0)
		)
		(polygon
			(pts
				(arc
					(start 300.57344 -297.032172)
					(mid 300.56972 -297.041152)
					(end 300.56074 -297.044872)
				)
				(arc
					(start 299.08754 -297.044872)
					(mid 299.07856 -297.041152)
					(end 299.07484 -297.032172)
				)
				(arc
					(start 299.07484 -296.537634)
					(mid 299.07856 -296.528654)
					(end 299.08754 -296.524934)
				)
				(arc
					(start 300.56074 -296.524934)
					(mid 300.56972 -296.528654)
					(end 300.57344 -296.537634)
				)
			)
		)
	)
	(zone
		(layer "In1.Cu")
		(hatch none 0.5)
		(connect_pads
			(clearance 0)
		)
		(min_thickness 0.25)
		(keepout
			(tracks not_allowed)
			(vias allowed)
			(pads allowed)
			(copperpour not_allowed)
			(footprints allowed)
		)
		(placement
			(enabled no)
			(sheetname "")
		)
		(fill
			(thermal_gap 0.5)
			(thermal_bridge_width 0.5)
			(island_removal_mode 0)
		)
		(polygon
			(pts
				(arc
					(start 334.013048 -379.360684)
					(mid 334.032972 -379.36992)
					(end 334.054704 -379.37313)
				)
				(arc
					(start 334.249268 -379.37313)
					(mid 334.30315 -379.350812)
					(end 334.325468 -379.29693)
				)
				(arc
					(start 334.325468 -378.61113)
					(mid 334.30315 -378.557248)
					(end 334.249268 -378.53493)
				)
				(arc
					(start 334.054704 -378.53493)
					(mid 334.03296 -378.538098)
					(end 334.013048 -378.547376)
				)
				(arc
					(start 333.716884 -378.740162)
					(mid 333.6752 -378.752384)
					(end 333.633572 -378.739908)
				)
				(arc
					(start 333.339948 -378.547376)
					(mid 333.320024 -378.53814)
					(end 333.298292 -378.53493)
				)
				(arc
					(start 333.103728 -378.53493)
					(mid 333.049846 -378.557248)
					(end 333.027528 -378.61113)
				)
				(arc
					(start 333.027528 -379.29693)
					(mid 333.049846 -379.350812)
					(end 333.103728 -379.37313)
				)
				(arc
					(start 333.299562 -379.37313)
					(mid 333.321306 -379.369962)
					(end 333.341218 -379.360684)
				)
				(arc
					(start 333.634842 -379.168152)
					(mid 333.676498 -379.15575)
					(end 333.718154 -379.168152)
				)
			)
		)
	)
	(zone
		(layer "In1.Cu")
		(hatch none 0.5)
		(connect_pads
			(clearance 0)
		)
		(min_thickness 0.25)
		(keepout
			(tracks not_allowed)
			(vias allowed)
			(pads allowed)
			(copperpour not_allowed)
			(footprints allowed)
		)
		(placement
			(enabled no)
			(sheetname "")
		)
		(fill
			(thermal_gap 0.5)
			(thermal_bridge_width 0.5)
			(island_removal_mode 0)
		)
		(polygon
			(pts
				(arc
					(start 180.265324 -204.38237)
					(mid 180.261604 -204.39135)
					(end 180.252624 -204.39507)
				)
				(arc
					(start 178.779424 -204.39507)
					(mid 178.770444 -204.39135)
					(end 178.766724 -204.38237)
				)
				(arc
					(start 178.766724 -203.887832)
					(mid 178.770444 -203.878852)
					(end 178.779424 -203.875132)
				)
				(arc
					(start 180.252624 -203.875132)
					(mid 180.261604 -203.878852)
					(end 180.265324 -203.887832)
				)
			)
		)
	)
	(zone
		(layer "In1.Cu")
		(hatch none 0.5)
		(connect_pads
			(clearance 0)
		)
		(min_thickness 0.25)
		(keepout
			(tracks not_allowed)
			(vias allowed)
			(pads allowed)
			(copperpour not_allowed)
			(footprints allowed)
		)
		(placement
			(enabled no)
			(sheetname "")
		)
		(fill
			(thermal_gap 0.5)
			(thermal_bridge_width 0.5)
			(island_removal_mode 0)
		)
		(polygon
			(pts
				(arc
					(start 346.318586 -399.701258)
					(mid 346.445586 -399.828258)
					(end 346.572586 -399.701258)
				)
				(arc
					(start 346.572586 -399.625058)
					(mid 346.445586 -399.498058)
					(end 346.318586 -399.625058)
				)
			)
		)
	)
	(zone
		(layer "In1.Cu")
		(hatch none 0.5)
		(connect_pads
			(clearance 0)
		)
		(min_thickness 0.25)
		(keepout
			(tracks not_allowed)
			(vias allowed)
			(pads allowed)
			(copperpour not_allowed)
			(footprints allowed)
		)
		(placement
			(enabled no)
			(sheetname "")
		)
		(fill
			(thermal_gap 0.5)
			(thermal_bridge_width 0.5)
			(island_removal_mode 0)
		)
		(polygon
			(pts
				(arc
					(start 447.393568 -206.932276)
					(mid 447.389848 -206.941256)
					(end 447.380868 -206.944976)
				)
				(arc
					(start 445.907668 -206.944976)
					(mid 445.898688 -206.941256)
					(end 445.894968 -206.932276)
				)
				(arc
					(start 445.894968 -206.437738)
					(mid 445.898688 -206.428758)
					(end 445.907668 -206.425038)
				)
				(arc
					(start 447.380868 -206.425038)
					(mid 447.389848 -206.428758)
					(end 447.393568 -206.437738)
				)
			)
		)
	)
	(zone
		(layer "In1.Cu")
		(hatch none 0.5)
		(connect_pads
			(clearance 0)
		)
		(min_thickness 0.25)
		(keepout
			(tracks not_allowed)
			(vias allowed)
			(pads allowed)
			(copperpour not_allowed)
			(footprints allowed)
		)
		(placement
			(enabled no)
			(sheetname "")
		)
		(fill
			(thermal_gap 0.5)
			(thermal_bridge_width 0.5)
			(island_removal_mode 0)
		)
		(polygon
			(pts
				(arc
					(start 86.718902 -391.319258)
					(mid 86.845902 -391.446258)
					(end 86.972902 -391.319258)
				)
				(arc
					(start 86.972902 -391.243058)
					(mid 86.845902 -391.116058)
					(end 86.718902 -391.243058)
				)
			)
		)
	)
	(zone
		(layer "In1.Cu")
		(hatch none 0.5)
		(connect_pads
			(clearance 0)
		)
		(min_thickness 0.25)
		(keepout
			(tracks not_allowed)
			(vias allowed)
			(pads allowed)
			(copperpour not_allowed)
			(footprints allowed)
		)
		(placement
			(enabled no)
			(sheetname "")
		)
		(fill
			(thermal_gap 0.5)
			(thermal_bridge_width 0.5)
			(island_removal_mode 0)
		)
		(polygon
			(pts
				(arc
					(start 270.397478 -298.732194)
					(mid 270.393758 -298.741174)
					(end 270.384778 -298.744894)
				)
				(arc
					(start 268.911578 -298.744894)
					(mid 268.902598 -298.741174)
					(end 268.898878 -298.732194)
				)
				(arc
					(start 268.898878 -298.237656)
					(mid 268.902598 -298.228676)
					(end 268.911578 -298.224956)
				)
				(arc
					(start 270.384778 -298.224956)
					(mid 270.393758 -298.228676)
					(end 270.397478 -298.237656)
				)
			)
		)
	)
	(zone
		(layer "In1.Cu")
		(hatch none 0.5)
		(connect_pads
			(clearance 0)
		)
		(min_thickness 0.25)
		(keepout
			(tracks not_allowed)
			(vias allowed)
			(pads allowed)
			(copperpour not_allowed)
			(footprints allowed)
		)
		(placement
			(enabled no)
			(sheetname "")
		)
		(fill
			(thermal_gap 0.5)
			(thermal_bridge_width 0.5)
			(island_removal_mode 0)
		)
		(polygon
			(pts
				(arc
					(start 157.08884 -386.003292)
					(mid 156.70784 -386.003292)
					(end 157.08884 -386.003292)
				)
			)
		)
	)
	(zone
		(layer "In1.Cu")
		(hatch none 0.5)
		(connect_pads
			(clearance 0)
		)
		(min_thickness 0.25)
		(keepout
			(tracks not_allowed)
			(vias allowed)
			(pads allowed)
			(copperpour not_allowed)
			(footprints allowed)
		)
		(placement
			(enabled no)
			(sheetname "")
		)
		(fill
			(thermal_gap 0.5)
			(thermal_bridge_width 0.5)
			(island_removal_mode 0)
		)
		(polygon
			(pts
				(arc
					(start 424.761406 -291.082222)
					(mid 424.757686 -291.091202)
					(end 424.748706 -291.094922)
				)
				(arc
					(start 423.275506 -291.094922)
					(mid 423.266526 -291.091202)
					(end 423.262806 -291.082222)
				)
				(arc
					(start 423.262806 -290.587684)
					(mid 423.266526 -290.578704)
					(end 423.275506 -290.574984)
				)
				(arc
					(start 424.748706 -290.574984)
					(mid 424.757686 -290.578704)
					(end 424.761406 -290.587684)
				)
			)
		)
	)
	(zone
		(layer "In1.Cu")
		(hatch none 0.5)
		(connect_pads
			(clearance 0)
		)
		(min_thickness 0.25)
		(keepout
			(tracks not_allowed)
			(vias allowed)
			(pads allowed)
			(copperpour not_allowed)
			(footprints allowed)
		)
		(placement
			(enabled no)
			(sheetname "")
		)
		(fill
			(thermal_gap 0.5)
			(thermal_bridge_width 0.5)
			(island_removal_mode 0)
		)
		(polygon
			(pts
				(arc
					(start 184.365392 -229.032562)
					(mid 184.361672 -229.041542)
					(end 184.352692 -229.045262)
				)
				(arc
					(start 182.879492 -229.045262)
					(mid 182.870512 -229.041542)
					(end 182.866792 -229.032562)
				)
				(arc
					(start 182.866792 -228.538024)
					(mid 182.870512 -228.529044)
					(end 182.879492 -228.525324)
				)
				(arc
					(start 184.352692 -228.525324)
					(mid 184.361672 -228.529044)
					(end 184.365392 -228.538024)
				)
			)
		)
	)
	(zone
		(layer "In1.Cu")
		(hatch none 0.5)
		(connect_pads
			(clearance 0)
		)
		(min_thickness 0.25)
		(keepout
			(tracks not_allowed)
			(vias allowed)
			(pads allowed)
			(copperpour not_allowed)
			(footprints allowed)
		)
		(placement
			(enabled no)
			(sheetname "")
		)
		(fill
			(thermal_gap 0.5)
			(thermal_bridge_width 0.5)
			(island_removal_mode 0)
		)
		(polygon
			(pts
				(arc
					(start 52.633372 -222.232474)
					(mid 52.629652 -222.241454)
					(end 52.620672 -222.245174)
				)
				(arc
					(start 51.147472 -222.245174)
					(mid 51.138492 -222.241454)
					(end 51.134772 -222.232474)
				)
				(arc
					(start 51.134772 -221.737936)
					(mid 51.138492 -221.728956)
					(end 51.147472 -221.725236)
				)
				(arc
					(start 52.620672 -221.725236)
					(mid 52.629652 -221.728956)
					(end 52.633372 -221.737936)
				)
			)
		)
	)
	(zone
		(layer "In1.Cu")
		(hatch none 0.5)
		(connect_pads
			(clearance 0)
		)
		(min_thickness 0.25)
		(keepout
			(tracks not_allowed)
			(vias allowed)
			(pads allowed)
			(copperpour not_allowed)
			(footprints allowed)
		)
		(placement
			(enabled no)
			(sheetname "")
		)
		(fill
			(thermal_gap 0.5)
			(thermal_bridge_width 0.5)
			(island_removal_mode 0)
		)
		(polygon
			(pts
				(arc
					(start 432.30546 -234.982258)
					(mid 432.30174 -234.991238)
					(end 432.29276 -234.994958)
				)
				(arc
					(start 430.81956 -234.994958)
					(mid 430.81058 -234.991238)
					(end 430.80686 -234.982258)
				)
				(arc
					(start 430.80686 -234.48772)
					(mid 430.81058 -234.47874)
					(end 430.81956 -234.47502)
				)
				(arc
					(start 432.29276 -234.47502)
					(mid 432.30174 -234.47874)
					(end 432.30546 -234.48772)
				)
			)
		)
	)
	(zone
		(layer "In1.Cu")
		(hatch none 0.5)
		(connect_pads
			(clearance 0)
		)
		(min_thickness 0.25)
		(keepout
			(tracks not_allowed)
			(vias allowed)
			(pads allowed)
			(copperpour not_allowed)
			(footprints allowed)
		)
		(placement
			(enabled no)
			(sheetname "")
		)
		(fill
			(thermal_gap 0.5)
			(thermal_bridge_width 0.5)
			(island_removal_mode 0)
		)
		(polygon
			(pts
				(arc
					(start 169.277284 -251.13234)
					(mid 169.273564 -251.14132)
					(end 169.264584 -251.14504)
				)
				(arc
					(start 167.791384 -251.14504)
					(mid 167.782404 -251.14132)
					(end 167.778684 -251.13234)
				)
				(arc
					(start 167.778684 -250.637802)
					(mid 167.782404 -250.628822)
					(end 167.791384 -250.625102)
				)
				(arc
					(start 169.264584 -250.625102)
					(mid 169.273564 -250.628822)
					(end 169.277284 -250.637802)
				)
			)
		)
	)
	(zone
		(layer "In1.Cu")
		(hatch none 0.5)
		(connect_pads
			(clearance 0)
		)
		(min_thickness 0.25)
		(keepout
			(tracks not_allowed)
			(vias allowed)
			(pads allowed)
			(copperpour not_allowed)
			(footprints allowed)
		)
		(placement
			(enabled no)
			(sheetname "")
		)
		(fill
			(thermal_gap 0.5)
			(thermal_bridge_width 0.5)
			(island_removal_mode 0)
		)
		(polygon
			(pts
				(arc
					(start 199.4535 -263.032494)
					(mid 199.44978 -263.041474)
					(end 199.4408 -263.045194)
				)
				(arc
					(start 197.9676 -263.045194)
					(mid 197.95862 -263.041474)
					(end 197.9549 -263.032494)
				)
				(arc
					(start 197.9549 -262.537956)
					(mid 197.95862 -262.528976)
					(end 197.9676 -262.525256)
				)
				(arc
					(start 199.4408 -262.525256)
					(mid 199.44978 -262.528976)
					(end 199.4535 -262.537956)
				)
			)
		)
	)
	(zone
		(layer "In1.Cu")
		(hatch none 0.5)
		(connect_pads
			(clearance 0)
		)
		(min_thickness 0.25)
		(keepout
			(tracks not_allowed)
			(vias allowed)
			(pads allowed)
			(copperpour not_allowed)
			(footprints allowed)
		)
		(placement
			(enabled no)
			(sheetname "")
		)
		(fill
			(thermal_gap 0.5)
			(thermal_bridge_width 0.5)
			(island_removal_mode 0)
		)
		(polygon
			(pts
				(arc
					(start 428.205392 -198.432166)
					(mid 428.201672 -198.441146)
					(end 428.192692 -198.444866)
				)
				(arc
					(start 426.719492 -198.444866)
					(mid 426.710512 -198.441146)
					(end 426.706792 -198.432166)
				)
				(arc
					(start 426.706792 -197.937628)
					(mid 426.710512 -197.928648)
					(end 426.719492 -197.924928)
				)
				(arc
					(start 428.192692 -197.924928)
					(mid 428.201672 -197.928648)
					(end 428.205392 -197.937628)
				)
			)
		)
	)
	(zone
		(layer "In1.Cu")
		(hatch none 0.5)
		(connect_pads
			(clearance 0)
		)
		(min_thickness 0.25)
		(keepout
			(tracks not_allowed)
			(vias allowed)
			(pads allowed)
			(copperpour not_allowed)
			(footprints allowed)
		)
		(placement
			(enabled no)
			(sheetname "")
		)
		(fill
			(thermal_gap 0.5)
			(thermal_bridge_width 0.5)
			(island_removal_mode 0)
		)
		(polygon
			(pts
				(arc
					(start 206.5782 -245.785386)
					(mid 205.9178 -245.785386)
					(end 206.5782 -245.785386)
				)
			)
		)
	)
	(zone
		(layer "In1.Cu")
		(hatch none 0.5)
		(connect_pads
			(clearance 0)
		)
		(min_thickness 0.25)
		(keepout
			(tracks not_allowed)
			(vias allowed)
			(pads allowed)
			(copperpour not_allowed)
			(footprints allowed)
		)
		(placement
			(enabled no)
			(sheetname "")
		)
		(fill
			(thermal_gap 0.5)
			(thermal_bridge_width 0.5)
			(island_removal_mode 0)
		)
		(polygon
			(pts
				(arc
					(start 22.45741 -239.23244)
					(mid 22.45369 -239.24142)
					(end 22.44471 -239.24514)
				)
				(arc
					(start 20.97151 -239.24514)
					(mid 20.96253 -239.24142)
					(end 20.95881 -239.23244)
				)
				(arc
					(start 20.95881 -238.737902)
					(mid 20.96253 -238.728922)
					(end 20.97151 -238.725202)
				)
				(arc
					(start 22.44471 -238.725202)
					(mid 22.45369 -238.728922)
					(end 22.45741 -238.737902)
				)
			)
		)
	)
	(zone
		(layer "In1.Cu")
		(hatch none 0.5)
		(connect_pads
			(clearance 0)
		)
		(min_thickness 0.25)
		(keepout
			(tracks not_allowed)
			(vias allowed)
			(pads allowed)
			(copperpour not_allowed)
			(footprints allowed)
		)
		(placement
			(enabled no)
			(sheetname "")
		)
		(fill
			(thermal_gap 0.5)
			(thermal_bridge_width 0.5)
			(island_removal_mode 0)
		)
		(polygon
			(pts
				(arc
					(start 56.077358 -215.432386)
					(mid 56.073638 -215.441366)
					(end 56.064658 -215.445086)
				)
				(arc
					(start 54.591458 -215.445086)
					(mid 54.582478 -215.441366)
					(end 54.578758 -215.432386)
				)
				(arc
					(start 54.578758 -214.937848)
					(mid 54.582478 -214.928868)
					(end 54.591458 -214.925148)
				)
				(arc
					(start 56.064658 -214.925148)
					(mid 56.073638 -214.928868)
					(end 56.077358 -214.937848)
				)
			)
		)
	)
	(zone
		(layer "In1.Cu")
		(hatch none 0.5)
		(connect_pads
			(clearance 0)
		)
		(min_thickness 0.25)
		(keepout
			(tracks not_allowed)
			(vias allowed)
			(pads allowed)
			(copperpour not_allowed)
			(footprints allowed)
		)
		(placement
			(enabled no)
			(sheetname "")
		)
		(fill
			(thermal_gap 0.5)
			(thermal_bridge_width 0.5)
			(island_removal_mode 0)
		)
		(polygon
			(pts
				(arc
					(start 288.929318 -207.78216)
					(mid 288.925598 -207.79114)
					(end 288.916618 -207.79486)
				)
				(arc
					(start 287.443418 -207.79486)
					(mid 287.434438 -207.79114)
					(end 287.430718 -207.78216)
				)
				(arc
					(start 287.430718 -207.287622)
					(mid 287.434438 -207.278642)
					(end 287.443418 -207.274922)
				)
				(arc
					(start 288.916618 -207.274922)
					(mid 288.925598 -207.278642)
					(end 288.929318 -207.287622)
				)
			)
		)
	)
	(zone
		(layer "In1.Cu")
		(hatch none 0.5)
		(connect_pads
			(clearance 0)
		)
		(min_thickness 0.25)
		(keepout
			(tracks not_allowed)
			(vias allowed)
			(pads allowed)
			(copperpour not_allowed)
			(footprints allowed)
		)
		(placement
			(enabled no)
			(sheetname "")
		)
		(fill
			(thermal_gap 0.5)
			(thermal_bridge_width 0.5)
			(island_removal_mode 0)
		)
		(polygon
			(pts
				(arc
					(start 37.545264 -205.232508)
					(mid 37.541544 -205.241488)
					(end 37.532564 -205.245208)
				)
				(arc
					(start 36.059364 -205.245208)
					(mid 36.050384 -205.241488)
					(end 36.046664 -205.232508)
				)
				(arc
					(start 36.046664 -204.73797)
					(mid 36.050384 -204.72899)
					(end 36.059364 -204.72527)
				)
				(arc
					(start 37.532564 -204.72527)
					(mid 37.541544 -204.72899)
					(end 37.545264 -204.73797)
				)
			)
		)
	)
	(zone
		(layer "In1.Cu")
		(hatch none 0.5)
		(connect_pads
			(clearance 0)
		)
		(min_thickness 0.25)
		(keepout
			(tracks not_allowed)
			(vias allowed)
			(pads allowed)
			(copperpour not_allowed)
			(footprints allowed)
		)
		(placement
			(enabled no)
			(sheetname "")
		)
		(fill
			(thermal_gap 0.5)
			(thermal_bridge_width 0.5)
			(island_removal_mode 0)
		)
		(polygon
			(pts
				(arc
					(start 270.397478 -223.932242)
					(mid 270.393758 -223.941222)
					(end 270.384778 -223.944942)
				)
				(arc
					(start 268.911578 -223.944942)
					(mid 268.902598 -223.941222)
					(end 268.898878 -223.932242)
				)
				(arc
					(start 268.898878 -223.437704)
					(mid 268.902598 -223.428724)
					(end 268.911578 -223.425004)
				)
				(arc
					(start 270.384778 -223.425004)
					(mid 270.393758 -223.428724)
					(end 270.397478 -223.437704)
				)
			)
		)
	)
	(zone
		(layer "In1.Cu")
		(hatch none 0.5)
		(connect_pads
			(clearance 0)
		)
		(min_thickness 0.25)
		(keepout
			(tracks not_allowed)
			(vias allowed)
			(pads allowed)
			(copperpour not_allowed)
			(footprints allowed)
		)
		(placement
			(enabled no)
			(sheetname "")
		)
		(fill
			(thermal_gap 0.5)
			(thermal_bridge_width 0.5)
			(island_removal_mode 0)
		)
		(polygon
			(pts
				(arc
					(start 450.8373 -228.18217)
					(mid 450.83358 -228.19115)
					(end 450.8246 -228.19487)
				)
				(arc
					(start 449.3514 -228.19487)
					(mid 449.34242 -228.19115)
					(end 449.3387 -228.18217)
				)
				(arc
					(start 449.3387 -227.687632)
					(mid 449.34242 -227.678652)
					(end 449.3514 -227.674932)
				)
				(arc
					(start 450.8246 -227.674932)
					(mid 450.83358 -227.678652)
					(end 450.8373 -227.687632)
				)
			)
		)
	)
	(zone
		(layer "In1.Cu")
		(hatch none 0.5)
		(connect_pads
			(clearance 0)
		)
		(min_thickness 0.25)
		(keepout
			(tracks not_allowed)
			(vias allowed)
			(pads allowed)
			(copperpour not_allowed)
			(footprints allowed)
		)
		(placement
			(enabled no)
			(sheetname "")
		)
		(fill
			(thermal_gap 0.5)
			(thermal_bridge_width 0.5)
			(island_removal_mode 0)
		)
		(polygon
			(pts
				(arc
					(start 443.2935 -248.58218)
					(mid 443.28978 -248.59116)
					(end 443.2808 -248.59488)
				)
				(arc
					(start 441.8076 -248.59488)
					(mid 441.79862 -248.59116)
					(end 441.7949 -248.58218)
				)
				(arc
					(start 441.7949 -248.087642)
					(mid 441.79862 -248.078662)
					(end 441.8076 -248.074942)
				)
				(arc
					(start 443.2808 -248.074942)
					(mid 443.28978 -248.078662)
					(end 443.2935 -248.087642)
				)
			)
		)
	)
	(zone
		(layer "In1.Cu")
		(hatch none 0.5)
		(connect_pads
			(clearance 0)
		)
		(min_thickness 0.25)
		(keepout
			(tracks not_allowed)
			(vias allowed)
			(pads allowed)
			(copperpour not_allowed)
			(footprints allowed)
		)
		(placement
			(enabled no)
			(sheetname "")
		)
		(fill
			(thermal_gap 0.5)
			(thermal_bridge_width 0.5)
			(island_removal_mode 0)
		)
		(polygon
			(pts
				(arc
					(start 386.16128 -393.69238)
					(mid 385.78028 -393.69238)
					(end 386.16128 -393.69238)
				)
			)
		)
	)
	(zone
		(layer "In1.Cu")
		(hatch none 0.5)
		(connect_pads
			(clearance 0)
		)
		(min_thickness 0.25)
		(keepout
			(tracks not_allowed)
			(vias allowed)
			(pads allowed)
			(copperpour not_allowed)
			(footprints allowed)
		)
		(placement
			(enabled no)
			(sheetname "")
		)
		(fill
			(thermal_gap 0.5)
			(thermal_bridge_width 0.5)
			(island_removal_mode 0)
		)
		(polygon
			(pts
				(arc
					(start 52.633372 -229.032562)
					(mid 52.629652 -229.041542)
					(end 52.620672 -229.045262)
				)
				(arc
					(start 51.147472 -229.045262)
					(mid 51.138492 -229.041542)
					(end 51.134772 -229.032562)
				)
				(arc
					(start 51.134772 -228.538024)
					(mid 51.138492 -228.529044)
					(end 51.147472 -228.525324)
				)
				(arc
					(start 52.620672 -228.525324)
					(mid 52.629652 -228.529044)
					(end 52.633372 -228.538024)
				)
			)
		)
	)
	(zone
		(layer "In1.Cu")
		(hatch none 0.5)
		(connect_pads
			(clearance 0)
		)
		(min_thickness 0.25)
		(keepout
			(tracks not_allowed)
			(vias allowed)
			(pads allowed)
			(copperpour not_allowed)
			(footprints allowed)
		)
		(placement
			(enabled no)
			(sheetname "")
		)
		(fill
			(thermal_gap 0.5)
			(thermal_bridge_width 0.5)
			(island_removal_mode 0)
		)
		(polygon
			(pts
				(arc
					(start 420.661338 -220.532198)
					(mid 420.657618 -220.541178)
					(end 420.648638 -220.544898)
				)
				(arc
					(start 419.175438 -220.544898)
					(mid 419.166458 -220.541178)
					(end 419.162738 -220.532198)
				)
				(arc
					(start 419.162738 -220.03766)
					(mid 419.166458 -220.02868)
					(end 419.175438 -220.02496)
				)
				(arc
					(start 420.648638 -220.02496)
					(mid 420.657618 -220.02868)
					(end 420.661338 -220.03766)
				)
			)
		)
	)
	(zone
		(layer "In1.Cu")
		(hatch none 0.5)
		(connect_pads
			(clearance 0)
		)
		(min_thickness 0.25)
		(keepout
			(tracks not_allowed)
			(vias allowed)
			(pads allowed)
			(copperpour not_allowed)
			(footprints allowed)
		)
		(placement
			(enabled no)
			(sheetname "")
		)
		(fill
			(thermal_gap 0.5)
			(thermal_bridge_width 0.5)
			(island_removal_mode 0)
		)
		(polygon
			(pts
				(arc
					(start 447.393568 -274.082256)
					(mid 447.389848 -274.091236)
					(end 447.380868 -274.094956)
				)
				(arc
					(start 445.907668 -274.094956)
					(mid 445.898688 -274.091236)
					(end 445.894968 -274.082256)
				)
				(arc
					(start 445.894968 -273.587718)
					(mid 445.898688 -273.578738)
					(end 445.907668 -273.575018)
				)
				(arc
					(start 447.380868 -273.575018)
					(mid 447.389848 -273.578738)
					(end 447.393568 -273.587718)
				)
			)
		)
	)
	(zone
		(layer "In1.Cu")
		(hatch none 0.5)
		(connect_pads
			(clearance 0)
		)
		(min_thickness 0.25)
		(keepout
			(tracks not_allowed)
			(vias allowed)
			(pads allowed)
			(copperpour not_allowed)
			(footprints allowed)
		)
		(placement
			(enabled no)
			(sheetname "")
		)
		(fill
			(thermal_gap 0.5)
			(thermal_bridge_width 0.5)
			(island_removal_mode 0)
		)
		(polygon
			(pts
				(arc
					(start 450.8373 -274.93214)
					(mid 450.83358 -274.94112)
					(end 450.8246 -274.94484)
				)
				(arc
					(start 449.3514 -274.94484)
					(mid 449.34242 -274.94112)
					(end 449.3387 -274.93214)
				)
				(arc
					(start 449.3387 -274.437602)
					(mid 449.34242 -274.428622)
					(end 449.3514 -274.424902)
				)
				(arc
					(start 450.8246 -274.424902)
					(mid 450.83358 -274.428622)
					(end 450.8373 -274.437602)
				)
			)
		)
	)
	(zone
		(layer "In1.Cu")
		(hatch none 0.5)
		(connect_pads
			(clearance 0)
		)
		(min_thickness 0.25)
		(keepout
			(tracks not_allowed)
			(vias allowed)
			(pads allowed)
			(copperpour not_allowed)
			(footprints allowed)
		)
		(placement
			(enabled no)
			(sheetname "")
		)
		(fill
			(thermal_gap 0.5)
			(thermal_bridge_width 0.5)
			(island_removal_mode 0)
		)
		(polygon
			(pts
				(arc
					(start 199.4535 -294.48252)
					(mid 199.44978 -294.4915)
					(end 199.4408 -294.49522)
				)
				(arc
					(start 197.9676 -294.49522)
					(mid 197.95862 -294.4915)
					(end 197.9549 -294.48252)
				)
				(arc
					(start 197.9549 -293.987982)
					(mid 197.95862 -293.979002)
					(end 197.9676 -293.975282)
				)
				(arc
					(start 199.4408 -293.975282)
					(mid 199.44978 -293.979002)
					(end 199.4535 -293.987982)
				)
			)
		)
	)
	(zone
		(layer "In1.Cu")
		(hatch none 0.5)
		(connect_pads
			(clearance 0)
		)
		(min_thickness 0.25)
		(keepout
			(tracks not_allowed)
			(vias allowed)
			(pads allowed)
			(copperpour not_allowed)
			(footprints allowed)
		)
		(placement
			(enabled no)
			(sheetname "")
		)
		(fill
			(thermal_gap 0.5)
			(thermal_bridge_width 0.5)
			(island_removal_mode 0)
		)
		(polygon
			(pts
				(arc
					(start 94.788736 -386.003292)
					(mid 94.407736 -386.003292)
					(end 94.788736 -386.003292)
				)
			)
		)
	)
	(zone
		(layer "In1.Cu")
		(hatch none 0.5)
		(connect_pads
			(clearance 0)
		)
		(min_thickness 0.25)
		(keepout
			(tracks not_allowed)
			(vias allowed)
			(pads allowed)
			(copperpour not_allowed)
			(footprints allowed)
		)
		(placement
			(enabled no)
			(sheetname "")
		)
		(fill
			(thermal_gap 0.5)
			(thermal_bridge_width 0.5)
			(island_removal_mode 0)
		)
		(polygon
			(pts
				(arc
					(start 266.29741 -207.78216)
					(mid 266.29369 -207.79114)
					(end 266.28471 -207.79486)
				)
				(arc
					(start 264.81151 -207.79486)
					(mid 264.80253 -207.79114)
					(end 264.79881 -207.78216)
				)
				(arc
					(start 264.79881 -207.287622)
					(mid 264.80253 -207.278642)
					(end 264.81151 -207.274922)
				)
				(arc
					(start 266.28471 -207.274922)
					(mid 266.29369 -207.278642)
					(end 266.29741 -207.287622)
				)
			)
		)
	)
	(zone
		(layer "In1.Cu")
		(hatch none 0.5)
		(connect_pads
			(clearance 0)
		)
		(min_thickness 0.25)
		(keepout
			(tracks not_allowed)
			(vias allowed)
			(pads allowed)
			(copperpour not_allowed)
			(footprints allowed)
		)
		(placement
			(enabled no)
			(sheetname "")
		)
		(fill
			(thermal_gap 0.5)
			(thermal_bridge_width 0.5)
			(island_removal_mode 0)
		)
		(polygon
			(pts
				(arc
					(start 300.57344 -304.682144)
					(mid 300.56972 -304.691124)
					(end 300.56074 -304.694844)
				)
				(arc
					(start 299.08754 -304.694844)
					(mid 299.07856 -304.691124)
					(end 299.07484 -304.682144)
				)
				(arc
					(start 299.07484 -304.187606)
					(mid 299.07856 -304.178626)
					(end 299.08754 -304.174906)
				)
				(arc
					(start 300.56074 -304.174906)
					(mid 300.56972 -304.178626)
					(end 300.57344 -304.187606)
				)
			)
		)
	)
	(zone
		(layer "In1.Cu")
		(hatch none 0.5)
		(connect_pads
			(clearance 0)
		)
		(min_thickness 0.25)
		(keepout
			(tracks not_allowed)
			(vias allowed)
			(pads allowed)
			(copperpour not_allowed)
			(footprints allowed)
		)
		(placement
			(enabled no)
			(sheetname "")
		)
		(fill
			(thermal_gap 0.5)
			(thermal_bridge_width 0.5)
			(island_removal_mode 0)
		)
		(polygon
			(pts
				(arc
					(start 191.909446 -287.682432)
					(mid 191.905726 -287.691412)
					(end 191.896746 -287.695132)
				)
				(arc
					(start 190.423546 -287.695132)
					(mid 190.414566 -287.691412)
					(end 190.410846 -287.682432)
				)
				(arc
					(start 190.410846 -287.187894)
					(mid 190.414566 -287.178914)
					(end 190.423546 -287.175194)
				)
				(arc
					(start 191.896746 -287.175194)
					(mid 191.905726 -287.178914)
					(end 191.909446 -287.187894)
				)
			)
		)
	)
	(zone
		(layer "In1.Cu")
		(hatch none 0.5)
		(connect_pads
			(clearance 0)
		)
		(min_thickness 0.25)
		(keepout
			(tracks not_allowed)
			(vias allowed)
			(pads allowed)
			(copperpour not_allowed)
			(footprints allowed)
		)
		(placement
			(enabled no)
			(sheetname "")
		)
		(fill
			(thermal_gap 0.5)
			(thermal_bridge_width 0.5)
			(island_removal_mode 0)
		)
		(polygon
			(pts
				(arc
					(start 300.57344 -197.582282)
					(mid 300.56972 -197.591262)
					(end 300.56074 -197.594982)
				)
				(arc
					(start 299.08754 -197.594982)
					(mid 299.07856 -197.591262)
					(end 299.07484 -197.582282)
				)
				(arc
					(start 299.07484 -197.087744)
					(mid 299.07856 -197.078764)
					(end 299.08754 -197.075044)
				)
				(arc
					(start 300.56074 -197.075044)
					(mid 300.56972 -197.078764)
					(end 300.57344 -197.087744)
				)
			)
		)
	)
	(zone
		(layer "In1.Cu")
		(hatch none 0.5)
		(connect_pads
			(clearance 0)
		)
		(min_thickness 0.25)
		(keepout
			(tracks not_allowed)
			(vias allowed)
			(pads allowed)
			(copperpour not_allowed)
			(footprints allowed)
		)
		(placement
			(enabled no)
			(sheetname "")
		)
		(fill
			(thermal_gap 0.5)
			(thermal_bridge_width 0.5)
			(island_removal_mode 0)
		)
		(polygon
			(pts
				(arc
					(start 308.117494 -200.982326)
					(mid 308.113774 -200.991306)
					(end 308.104794 -200.995026)
				)
				(arc
					(start 306.631594 -200.995026)
					(mid 306.622614 -200.991306)
					(end 306.618894 -200.982326)
				)
				(arc
					(start 306.618894 -200.487788)
					(mid 306.622614 -200.478808)
					(end 306.631594 -200.475088)
				)
				(arc
					(start 308.104794 -200.475088)
					(mid 308.113774 -200.478808)
					(end 308.117494 -200.487788)
				)
			)
		)
	)
	(zone
		(layer "In1.Cu")
		(hatch none 0.5)
		(connect_pads
			(clearance 0)
		)
		(min_thickness 0.25)
		(keepout
			(tracks not_allowed)
			(vias allowed)
			(pads allowed)
			(copperpour not_allowed)
			(footprints allowed)
		)
		(placement
			(enabled no)
			(sheetname "")
		)
		(fill
			(thermal_gap 0.5)
			(thermal_bridge_width 0.5)
			(island_removal_mode 0)
		)
		(polygon
			(pts
				(arc
					(start 45.089318 -302.132492)
					(mid 45.085598 -302.141472)
					(end 45.076618 -302.145192)
				)
				(arc
					(start 43.603418 -302.145192)
					(mid 43.594438 -302.141472)
					(end 43.590718 -302.132492)
				)
				(arc
					(start 43.590718 -301.637954)
					(mid 43.594438 -301.628974)
					(end 43.603418 -301.625254)
				)
				(arc
					(start 45.076618 -301.625254)
					(mid 45.085598 -301.628974)
					(end 45.089318 -301.637954)
				)
			)
		)
	)
	(zone
		(layer "In1.Cu")
		(hatch none 0.5)
		(connect_pads
			(clearance 0)
		)
		(min_thickness 0.25)
		(keepout
			(tracks not_allowed)
			(vias allowed)
			(pads allowed)
			(copperpour not_allowed)
			(footprints allowed)
		)
		(placement
			(enabled no)
			(sheetname "")
		)
		(fill
			(thermal_gap 0.5)
			(thermal_bridge_width 0.5)
			(island_removal_mode 0)
		)
		(polygon
			(pts
				(arc
					(start 60.177426 -278.332438)
					(mid 60.173706 -278.341418)
					(end 60.164726 -278.345138)
				)
				(arc
					(start 58.691526 -278.345138)
					(mid 58.682546 -278.341418)
					(end 58.678826 -278.332438)
				)
				(arc
					(start 58.678826 -277.8379)
					(mid 58.682546 -277.82892)
					(end 58.691526 -277.8252)
				)
				(arc
					(start 60.164726 -277.8252)
					(mid 60.173706 -277.82892)
					(end 60.177426 -277.8379)
				)
			)
		)
	)
	(zone
		(layer "In1.Cu")
		(hatch none 0.5)
		(connect_pads
			(clearance 0)
		)
		(min_thickness 0.25)
		(keepout
			(tracks not_allowed)
			(vias allowed)
			(pads allowed)
			(copperpour not_allowed)
			(footprints allowed)
		)
		(placement
			(enabled no)
			(sheetname "")
		)
		(fill
			(thermal_gap 0.5)
			(thermal_bridge_width 0.5)
			(island_removal_mode 0)
		)
		(polygon
			(pts
				(arc
					(start 288.929318 -215.432132)
					(mid 288.925598 -215.441112)
					(end 288.916618 -215.444832)
				)
				(arc
					(start 287.443418 -215.444832)
					(mid 287.434438 -215.441112)
					(end 287.430718 -215.432132)
				)
				(arc
					(start 287.430718 -214.937594)
					(mid 287.434438 -214.928614)
					(end 287.443418 -214.924894)
				)
				(arc
					(start 288.916618 -214.924894)
					(mid 288.925598 -214.928614)
					(end 288.929318 -214.937594)
				)
			)
		)
	)
	(zone
		(layer "In1.Cu")
		(hatch none 0.5)
		(connect_pads
			(clearance 0)
		)
		(min_thickness 0.25)
		(keepout
			(tracks not_allowed)
			(vias allowed)
			(pads allowed)
			(copperpour not_allowed)
			(footprints allowed)
		)
		(placement
			(enabled no)
			(sheetname "")
		)
		(fill
			(thermal_gap 0.5)
			(thermal_bridge_width 0.5)
			(island_removal_mode 0)
		)
		(polygon
			(pts
				(arc
					(start 95.58909 -385.31038)
					(mid 95.20809 -385.31038)
					(end 95.58909 -385.31038)
				)
			)
		)
	)
	(zone
		(layer "In1.Cu")
		(hatch none 0.5)
		(connect_pads
			(clearance 0)
		)
		(min_thickness 0.25)
		(keepout
			(tracks not_allowed)
			(vias allowed)
			(pads allowed)
			(copperpour not_allowed)
			(footprints allowed)
		)
		(placement
			(enabled no)
			(sheetname "")
		)
		(fill
			(thermal_gap 0.5)
			(thermal_bridge_width 0.5)
			(island_removal_mode 0)
		)
		(polygon
			(pts
				(arc
					(start 315.314584 -4.526026)
					(mid 315.336902 -4.472144)
					(end 315.390784 -4.449826)
				)
				(arc
					(start 316.002924 -4.449826)
					(mid 316.056806 -4.472144)
					(end 316.079124 -4.526026)
				)
				(arc
					(start 316.079124 -5.623306)
					(mid 316.056806 -5.677188)
					(end 316.002924 -5.699506)
				)
				(arc
					(start 315.390784 -5.699506)
					(mid 315.336902 -5.677188)
					(end 315.314584 -5.623306)
				)
			)
		)
	)
	(zone
		(layer "In1.Cu")
		(hatch none 0.5)
		(connect_pads
			(clearance 0)
		)
		(min_thickness 0.25)
		(keepout
			(tracks not_allowed)
			(vias allowed)
			(pads allowed)
			(copperpour not_allowed)
			(footprints allowed)
		)
		(placement
			(enabled no)
			(sheetname "")
		)
		(fill
			(thermal_gap 0.5)
			(thermal_bridge_width 0.5)
			(island_removal_mode 0)
		)
		(polygon
			(pts
				(arc
					(start 371.870224 -399.143474)
					(mid 371.565424 -399.143474)
					(end 371.870224 -399.143474)
				)
			)
		)
	)
	(zone
		(layer "In1.Cu")
		(hatch none 0.5)
		(connect_pads
			(clearance 0)
		)
		(min_thickness 0.25)
		(keepout
			(tracks not_allowed)
			(vias allowed)
			(pads allowed)
			(copperpour not_allowed)
			(footprints allowed)
		)
		(placement
			(enabled no)
			(sheetname "")
		)
		(fill
			(thermal_gap 0.5)
			(thermal_bridge_width 0.5)
			(island_removal_mode 0)
		)
		(polygon
			(pts
				(arc
					(start 296.473372 -262.182102)
					(mid 296.469652 -262.191082)
					(end 296.460672 -262.194802)
				)
				(arc
					(start 294.987472 -262.194802)
					(mid 294.978492 -262.191082)
					(end 294.974772 -262.182102)
				)
				(arc
					(start 294.974772 -261.687564)
					(mid 294.978492 -261.678584)
					(end 294.987472 -261.674864)
				)
				(arc
					(start 296.460672 -261.674864)
					(mid 296.469652 -261.678584)
					(end 296.473372 -261.687564)
				)
			)
		)
	)
	(zone
		(layer "In1.Cu")
		(hatch none 0.5)
		(connect_pads
			(clearance 0)
		)
		(min_thickness 0.25)
		(keepout
			(tracks not_allowed)
			(vias allowed)
			(pads allowed)
			(copperpour not_allowed)
			(footprints allowed)
		)
		(placement
			(enabled no)
			(sheetname "")
		)
		(fill
			(thermal_gap 0.5)
			(thermal_bridge_width 0.5)
			(island_removal_mode 0)
		)
		(polygon
			(pts
				(arc
					(start 447.393568 -197.582282)
					(mid 447.389848 -197.591262)
					(end 447.380868 -197.594982)
				)
				(arc
					(start 445.907668 -197.594982)
					(mid 445.898688 -197.591262)
					(end 445.894968 -197.582282)
				)
				(arc
					(start 445.894968 -197.087744)
					(mid 445.898688 -197.078764)
					(end 445.907668 -197.075044)
				)
				(arc
					(start 447.380868 -197.075044)
					(mid 447.389848 -197.078764)
					(end 447.393568 -197.087744)
				)
			)
		)
	)
	(zone
		(layer "In1.Cu")
		(hatch none 0.5)
		(connect_pads
			(clearance 0)
		)
		(min_thickness 0.25)
		(keepout
			(tracks not_allowed)
			(vias allowed)
			(pads allowed)
			(copperpour not_allowed)
			(footprints allowed)
		)
		(placement
			(enabled no)
			(sheetname "")
		)
		(fill
			(thermal_gap 0.5)
			(thermal_bridge_width 0.5)
			(island_removal_mode 0)
		)
		(polygon
			(pts
				(arc
					(start 435.749446 -318.28232)
					(mid 435.745726 -318.2913)
					(end 435.736746 -318.29502)
				)
				(arc
					(start 434.263546 -318.29502)
					(mid 434.254566 -318.2913)
					(end 434.250846 -318.28232)
				)
				(arc
					(start 434.250846 -317.787782)
					(mid 434.254566 -317.778802)
					(end 434.263546 -317.775082)
				)
				(arc
					(start 435.736746 -317.775082)
					(mid 435.745726 -317.778802)
					(end 435.749446 -317.787782)
				)
			)
		)
	)
	(zone
		(layer "In1.Cu")
		(hatch none 0.5)
		(connect_pads
			(clearance 0)
		)
		(min_thickness 0.25)
		(keepout
			(tracks not_allowed)
			(vias allowed)
			(pads allowed)
			(copperpour not_allowed)
			(footprints allowed)
		)
		(placement
			(enabled no)
			(sheetname "")
		)
		(fill
			(thermal_gap 0.5)
			(thermal_bridge_width 0.5)
			(island_removal_mode 0)
		)
		(polygon
			(pts
				(arc
					(start 45.089318 -298.732448)
					(mid 45.085598 -298.741428)
					(end 45.076618 -298.745148)
				)
				(arc
					(start 43.603418 -298.745148)
					(mid 43.594438 -298.741428)
					(end 43.590718 -298.732448)
				)
				(arc
					(start 43.590718 -298.23791)
					(mid 43.594438 -298.22893)
					(end 43.603418 -298.22521)
				)
				(arc
					(start 45.076618 -298.22521)
					(mid 45.085598 -298.22893)
					(end 45.089318 -298.23791)
				)
			)
		)
	)
	(zone
		(layer "In1.Cu")
		(hatch none 0.5)
		(connect_pads
			(clearance 0)
		)
		(min_thickness 0.25)
		(keepout
			(tracks not_allowed)
			(vias allowed)
			(pads allowed)
			(copperpour not_allowed)
			(footprints allowed)
		)
		(placement
			(enabled no)
			(sheetname "")
		)
		(fill
			(thermal_gap 0.5)
			(thermal_bridge_width 0.5)
			(island_removal_mode 0)
		)
		(polygon
			(pts
				(arc
					(start 420.661338 -230.73233)
					(mid 420.657618 -230.74131)
					(end 420.648638 -230.74503)
				)
				(arc
					(start 419.175438 -230.74503)
					(mid 419.166458 -230.74131)
					(end 419.162738 -230.73233)
				)
				(arc
					(start 419.162738 -230.237792)
					(mid 419.166458 -230.228812)
					(end 419.175438 -230.225092)
				)
				(arc
					(start 420.648638 -230.225092)
					(mid 420.657618 -230.228812)
					(end 420.661338 -230.237792)
				)
			)
		)
	)
	(zone
		(layer "In1.Cu")
		(hatch none 0.5)
		(connect_pads
			(clearance 0)
		)
		(min_thickness 0.25)
		(keepout
			(tracks not_allowed)
			(vias allowed)
			(pads allowed)
			(copperpour not_allowed)
			(footprints allowed)
		)
		(placement
			(enabled no)
			(sheetname "")
		)
		(fill
			(thermal_gap 0.5)
			(thermal_bridge_width 0.5)
			(island_removal_mode 0)
		)
		(polygon
			(pts
				(arc
					(start 18.357342 -276.632416)
					(mid 18.353622 -276.641396)
					(end 18.344642 -276.645116)
				)
				(arc
					(start 16.871442 -276.645116)
					(mid 16.862462 -276.641396)
					(end 16.858742 -276.632416)
				)
				(arc
					(start 16.858742 -276.137878)
					(mid 16.862462 -276.128898)
					(end 16.871442 -276.125178)
				)
				(arc
					(start 18.344642 -276.125178)
					(mid 18.353622 -276.128898)
					(end 18.357342 -276.137878)
				)
			)
		)
	)
	(zone
		(layer "In1.Cu")
		(hatch none 0.5)
		(connect_pads
			(clearance 0)
		)
		(min_thickness 0.25)
		(keepout
			(tracks not_allowed)
			(vias allowed)
			(pads allowed)
			(copperpour not_allowed)
			(footprints allowed)
		)
		(placement
			(enabled no)
			(sheetname "")
		)
		(fill
			(thermal_gap 0.5)
			(thermal_bridge_width 0.5)
			(island_removal_mode 0)
		)
		(polygon
			(pts
				(arc
					(start 180.265324 -312.33237)
					(mid 180.261604 -312.34135)
					(end 180.252624 -312.34507)
				)
				(arc
					(start 178.779424 -312.34507)
					(mid 178.770444 -312.34135)
					(end 178.766724 -312.33237)
				)
				(arc
					(start 178.766724 -311.837832)
					(mid 178.770444 -311.828852)
					(end 178.779424 -311.825132)
				)
				(arc
					(start 180.252624 -311.825132)
					(mid 180.261604 -311.828852)
					(end 180.265324 -311.837832)
				)
			)
		)
	)
	(zone
		(layer "In1.Cu")
		(hatch none 0.5)
		(connect_pads
			(clearance 0)
		)
		(min_thickness 0.25)
		(keepout
			(tracks not_allowed)
			(vias allowed)
			(pads allowed)
			(copperpour not_allowed)
			(footprints allowed)
		)
		(placement
			(enabled no)
			(sheetname "")
		)
		(fill
			(thermal_gap 0.5)
			(thermal_bridge_width 0.5)
			(island_removal_mode 0)
		)
		(polygon
			(pts
				(arc
					(start 52.633372 -309.782464)
					(mid 52.629652 -309.791444)
					(end 52.620672 -309.795164)
				)
				(arc
					(start 51.147472 -309.795164)
					(mid 51.138492 -309.791444)
					(end 51.134772 -309.782464)
				)
				(arc
					(start 51.134772 -309.287926)
					(mid 51.138492 -309.278946)
					(end 51.147472 -309.275226)
				)
				(arc
					(start 52.620672 -309.275226)
					(mid 52.629652 -309.278946)
					(end 52.633372 -309.287926)
				)
			)
		)
	)
	(zone
		(layer "In1.Cu")
		(hatch none 0.5)
		(connect_pads
			(clearance 0)
		)
		(min_thickness 0.25)
		(keepout
			(tracks not_allowed)
			(vias allowed)
			(pads allowed)
			(copperpour not_allowed)
			(footprints allowed)
		)
		(placement
			(enabled no)
			(sheetname "")
		)
		(fill
			(thermal_gap 0.5)
			(thermal_bridge_width 0.5)
			(island_removal_mode 0)
		)
		(polygon
			(pts
				(arc
					(start 417.217352 -249.432318)
					(mid 417.213632 -249.441298)
					(end 417.204652 -249.445018)
				)
				(arc
					(start 415.731452 -249.445018)
					(mid 415.722472 -249.441298)
					(end 415.718752 -249.432318)
				)
				(arc
					(start 415.718752 -248.93778)
					(mid 415.722472 -248.9288)
					(end 415.731452 -248.92508)
				)
				(arc
					(start 417.204652 -248.92508)
					(mid 417.213632 -248.9288)
					(end 417.217352 -248.93778)
				)
			)
		)
	)
	(zone
		(layer "In1.Cu")
		(hatch none 0.5)
		(connect_pads
			(clearance 0)
		)
		(min_thickness 0.25)
		(keepout
			(tracks not_allowed)
			(vias allowed)
			(pads allowed)
			(copperpour not_allowed)
			(footprints allowed)
		)
		(placement
			(enabled no)
			(sheetname "")
		)
		(fill
			(thermal_gap 0.5)
			(thermal_bridge_width 0.5)
			(island_removal_mode 0)
		)
		(polygon
			(pts
				(arc
					(start 413.117284 -274.93214)
					(mid 413.113564 -274.94112)
					(end 413.104584 -274.94484)
				)
				(arc
					(start 411.631384 -274.94484)
					(mid 411.622404 -274.94112)
					(end 411.618684 -274.93214)
				)
				(arc
					(start 411.618684 -274.437602)
					(mid 411.622404 -274.428622)
					(end 411.631384 -274.424902)
				)
				(arc
					(start 413.104584 -274.424902)
					(mid 413.113564 -274.428622)
					(end 413.117284 -274.437602)
				)
			)
		)
	)
	(zone
		(layer "In1.Cu")
		(hatch none 0.5)
		(connect_pads
			(clearance 0)
		)
		(min_thickness 0.25)
		(keepout
			(tracks not_allowed)
			(vias allowed)
			(pads allowed)
			(copperpour not_allowed)
			(footprints allowed)
		)
		(placement
			(enabled no)
			(sheetname "")
		)
		(fill
			(thermal_gap 0.5)
			(thermal_bridge_width 0.5)
			(island_removal_mode 0)
		)
		(polygon
			(pts
				(arc
					(start 300.57344 -233.282236)
					(mid 300.56972 -233.291216)
					(end 300.56074 -233.294936)
				)
				(arc
					(start 299.08754 -233.294936)
					(mid 299.07856 -233.291216)
					(end 299.07484 -233.282236)
				)
				(arc
					(start 299.07484 -232.787698)
					(mid 299.07856 -232.778718)
					(end 299.08754 -232.774998)
				)
				(arc
					(start 300.56074 -232.774998)
					(mid 300.56972 -232.778718)
					(end 300.57344 -232.787698)
				)
			)
		)
	)
	(zone
		(layer "In1.Cu")
		(hatch none 0.5)
		(connect_pads
			(clearance 0)
		)
		(min_thickness 0.25)
		(keepout
			(tracks not_allowed)
			(vias allowed)
			(pads allowed)
			(copperpour not_allowed)
			(footprints allowed)
		)
		(placement
			(enabled no)
			(sheetname "")
		)
		(fill
			(thermal_gap 0.5)
			(thermal_bridge_width 0.5)
			(island_removal_mode 0)
		)
		(polygon
			(pts
				(arc
					(start 48.533304 -240.082578)
					(mid 48.529584 -240.091558)
					(end 48.520604 -240.095278)
				)
				(arc
					(start 47.047404 -240.095278)
					(mid 47.038424 -240.091558)
					(end 47.034704 -240.082578)
				)
				(arc
					(start 47.034704 -239.58804)
					(mid 47.038424 -239.57906)
					(end 47.047404 -239.57534)
				)
				(arc
					(start 48.520604 -239.57534)
					(mid 48.529584 -239.57906)
					(end 48.533304 -239.58804)
				)
			)
		)
	)
	(zone
		(layer "In1.Cu")
		(hatch none 0.5)
		(connect_pads
			(clearance 0)
		)
		(min_thickness 0.25)
		(keepout
			(tracks not_allowed)
			(vias allowed)
			(pads allowed)
			(copperpour not_allowed)
			(footprints allowed)
		)
		(placement
			(enabled no)
			(sheetname "")
		)
		(fill
			(thermal_gap 0.5)
			(thermal_bridge_width 0.5)
			(island_removal_mode 0)
		)
		(polygon
			(pts
				(arc
					(start 129.428494 -34.784538)
					(mid 129.482376 -34.806856)
					(end 129.504694 -34.860738)
				)
				(arc
					(start 129.504694 -35.286188)
					(mid 129.482376 -35.34007)
					(end 129.428494 -35.362388)
				)
				(arc
					(start 128.260094 -35.362388)
					(mid 128.206212 -35.34007)
					(end 128.183894 -35.286188)
				)
				(arc
					(start 128.183894 -34.860738)
					(mid 128.206212 -34.806856)
					(end 128.260094 -34.784538)
				)
			)
		)
	)
	(zone
		(layer "In1.Cu")
		(hatch none 0.5)
		(connect_pads
			(clearance 0)
		)
		(min_thickness 0.25)
		(keepout
			(tracks not_allowed)
			(vias allowed)
			(pads allowed)
			(copperpour not_allowed)
			(footprints allowed)
		)
		(placement
			(enabled no)
			(sheetname "")
		)
		(fill
			(thermal_gap 0.5)
			(thermal_bridge_width 0.5)
			(island_removal_mode 0)
		)
		(polygon
			(pts
				(arc
					(start 56.590946 -383.440686)
					(mid 56.717946 -383.567686)
					(end 56.844946 -383.440686)
				)
				(arc
					(start 56.844946 -383.364486)
					(mid 56.717946 -383.237486)
					(end 56.590946 -383.364486)
				)
			)
		)
	)
	(zone
		(layer "In1.Cu")
		(hatch none 0.5)
		(connect_pads
			(clearance 0)
		)
		(min_thickness 0.25)
		(keepout
			(tracks not_allowed)
			(vias allowed)
			(pads allowed)
			(copperpour not_allowed)
			(footprints allowed)
		)
		(placement
			(enabled no)
			(sheetname "")
		)
		(fill
			(thermal_gap 0.5)
			(thermal_bridge_width 0.5)
			(island_removal_mode 0)
		)
		(polygon
			(pts
				(arc
					(start 439.849514 -309.78221)
					(mid 439.845794 -309.79119)
					(end 439.836814 -309.79491)
				)
				(arc
					(start 438.363614 -309.79491)
					(mid 438.354634 -309.79119)
					(end 438.350914 -309.78221)
				)
				(arc
					(start 438.350914 -309.287672)
					(mid 438.354634 -309.278692)
					(end 438.363614 -309.274972)
				)
				(arc
					(start 439.836814 -309.274972)
					(mid 439.845794 -309.278692)
					(end 439.849514 -309.287672)
				)
			)
		)
	)
	(zone
		(layer "In1.Cu")
		(hatch none 0.5)
		(connect_pads
			(clearance 0)
		)
		(min_thickness 0.25)
		(keepout
			(tracks not_allowed)
			(vias allowed)
			(pads allowed)
			(copperpour not_allowed)
			(footprints allowed)
		)
		(placement
			(enabled no)
			(sheetname "")
		)
		(fill
			(thermal_gap 0.5)
			(thermal_bridge_width 0.5)
			(island_removal_mode 0)
		)
		(polygon
			(pts
				(arc
					(start 195.353432 -239.23244)
					(mid 195.349712 -239.24142)
					(end 195.340732 -239.24514)
				)
				(arc
					(start 193.867532 -239.24514)
					(mid 193.858552 -239.24142)
					(end 193.854832 -239.23244)
				)
				(arc
					(start 193.854832 -238.737902)
					(mid 193.858552 -238.728922)
					(end 193.867532 -238.725202)
				)
				(arc
					(start 195.340732 -238.725202)
					(mid 195.349712 -238.728922)
					(end 195.353432 -238.737902)
				)
			)
		)
	)
	(zone
		(layer "In1.Cu")
		(hatch none 0.5)
		(connect_pads
			(clearance 0)
		)
		(min_thickness 0.25)
		(keepout
			(tracks not_allowed)
			(vias allowed)
			(pads allowed)
			(copperpour not_allowed)
			(footprints allowed)
		)
		(placement
			(enabled no)
			(sheetname "")
		)
		(fill
			(thermal_gap 0.5)
			(thermal_bridge_width 0.5)
			(island_removal_mode 0)
		)
		(polygon
			(pts
				(arc
					(start 320.3702 -392.30427)
					(mid 320.0654 -392.30427)
					(end 320.3702 -392.30427)
				)
			)
		)
	)
	(zone
		(layer "In1.Cu")
		(hatch none 0.5)
		(connect_pads
			(clearance 0)
		)
		(min_thickness 0.25)
		(keepout
			(tracks not_allowed)
			(vias allowed)
			(pads allowed)
			(copperpour not_allowed)
			(footprints allowed)
		)
		(placement
			(enabled no)
			(sheetname "")
		)
		(fill
			(thermal_gap 0.5)
			(thermal_bridge_width 0.5)
			(island_removal_mode 0)
		)
		(polygon
			(pts
				(arc
					(start 40.98925 -304.682398)
					(mid 40.98553 -304.691378)
					(end 40.97655 -304.695098)
				)
				(arc
					(start 39.50335 -304.695098)
					(mid 39.49437 -304.691378)
					(end 39.49065 -304.682398)
				)
				(arc
					(start 39.49065 -304.18786)
					(mid 39.49437 -304.17888)
					(end 39.50335 -304.17516)
				)
				(arc
					(start 40.97655 -304.17516)
					(mid 40.98553 -304.17888)
					(end 40.98925 -304.18786)
				)
			)
		)
	)
	(zone
		(layer "In1.Cu")
		(hatch none 0.5)
		(connect_pads
			(clearance 0)
		)
		(min_thickness 0.25)
		(keepout
			(tracks not_allowed)
			(vias allowed)
			(pads allowed)
			(copperpour not_allowed)
			(footprints allowed)
		)
		(placement
			(enabled no)
			(sheetname "")
		)
		(fill
			(thermal_gap 0.5)
			(thermal_bridge_width 0.5)
			(island_removal_mode 0)
		)
		(polygon
			(pts
				(arc
					(start 432.30546 -274.082256)
					(mid 432.30174 -274.091236)
					(end 432.29276 -274.094956)
				)
				(arc
					(start 430.81956 -274.094956)
					(mid 430.81058 -274.091236)
					(end 430.80686 -274.082256)
				)
				(arc
					(start 430.80686 -273.587718)
					(mid 430.81058 -273.578738)
					(end 430.81956 -273.575018)
				)
				(arc
					(start 432.29276 -273.575018)
					(mid 432.30174 -273.578738)
					(end 432.30546 -273.587718)
				)
			)
		)
	)
	(zone
		(layer "In1.Cu")
		(hatch none 0.5)
		(connect_pads
			(clearance 0)
		)
		(min_thickness 0.25)
		(keepout
			(tracks not_allowed)
			(vias allowed)
			(pads allowed)
			(copperpour not_allowed)
			(footprints allowed)
		)
		(placement
			(enabled no)
			(sheetname "")
		)
		(fill
			(thermal_gap 0.5)
			(thermal_bridge_width 0.5)
			(island_removal_mode 0)
		)
		(polygon
			(pts
				(arc
					(start 60.177426 -208.632552)
					(mid 60.173706 -208.641532)
					(end 60.164726 -208.645252)
				)
				(arc
					(start 58.691526 -208.645252)
					(mid 58.682546 -208.641532)
					(end 58.678826 -208.632552)
				)
				(arc
					(start 58.678826 -208.138014)
					(mid 58.682546 -208.129034)
					(end 58.691526 -208.125314)
				)
				(arc
					(start 60.164726 -208.125314)
					(mid 60.173706 -208.129034)
					(end 60.177426 -208.138014)
				)
			)
		)
	)
	(zone
		(layer "In1.Cu")
		(hatch none 0.5)
		(connect_pads
			(clearance 0)
		)
		(min_thickness 0.25)
		(keepout
			(tracks not_allowed)
			(vias allowed)
			(pads allowed)
			(copperpour not_allowed)
			(footprints allowed)
		)
		(placement
			(enabled no)
			(sheetname "")
		)
		(fill
			(thermal_gap 0.5)
			(thermal_bridge_width 0.5)
			(island_removal_mode 0)
		)
		(polygon
			(pts
				(arc
					(start 405.018748 -399.701258)
					(mid 405.145748 -399.828258)
					(end 405.272748 -399.701258)
				)
				(arc
					(start 405.272748 -399.625058)
					(mid 405.145748 -399.498058)
					(end 405.018748 -399.625058)
				)
			)
		)
	)
	(zone
		(layer "In1.Cu")
		(hatch none 0.5)
		(connect_pads
			(clearance 0)
		)
		(min_thickness 0.25)
		(keepout
			(tracks not_allowed)
			(vias allowed)
			(pads allowed)
			(copperpour not_allowed)
			(footprints allowed)
		)
		(placement
			(enabled no)
			(sheetname "")
		)
		(fill
			(thermal_gap 0.5)
			(thermal_bridge_width 0.5)
			(island_removal_mode 0)
		)
		(polygon
			(pts
				(arc
					(start 412.798006 -399.143474)
					(mid 412.493206 -399.143474)
					(end 412.798006 -399.143474)
				)
			)
		)
	)
	(zone
		(layer "In1.Cu")
		(hatch none 0.5)
		(connect_pads
			(clearance 0)
		)
		(min_thickness 0.25)
		(keepout
			(tracks not_allowed)
			(vias allowed)
			(pads allowed)
			(copperpour not_allowed)
			(footprints allowed)
		)
		(placement
			(enabled no)
			(sheetname "")
		)
		(fill
			(thermal_gap 0.5)
			(thermal_bridge_width 0.5)
			(island_removal_mode 0)
		)
		(polygon
			(pts
				(arc
					(start 48.533304 -207.782414)
					(mid 48.529584 -207.791394)
					(end 48.520604 -207.795114)
				)
				(arc
					(start 47.047404 -207.795114)
					(mid 47.038424 -207.791394)
					(end 47.034704 -207.782414)
				)
				(arc
					(start 47.034704 -207.287876)
					(mid 47.038424 -207.278896)
					(end 47.047404 -207.275176)
				)
				(arc
					(start 48.520604 -207.275176)
					(mid 48.529584 -207.278896)
					(end 48.533304 -207.287876)
				)
			)
		)
	)
	(zone
		(layer "In1.Cu")
		(hatch none 0.5)
		(connect_pads
			(clearance 0)
		)
		(min_thickness 0.25)
		(keepout
			(tracks not_allowed)
			(vias allowed)
			(pads allowed)
			(copperpour not_allowed)
			(footprints allowed)
		)
		(placement
			(enabled no)
			(sheetname "")
		)
		(fill
			(thermal_gap 0.5)
			(thermal_bridge_width 0.5)
			(island_removal_mode 0)
		)
		(polygon
			(pts
				(arc
					(start 365.939578 -0.548386)
					(mid 365.91726 -0.602268)
					(end 365.863378 -0.624586)
				)
				(arc
					(start 365.251238 -0.624586)
					(mid 365.197356 -0.602268)
					(end 365.175038 -0.548386)
				)
				(arc
					(start 365.175038 0.548894)
					(mid 365.197356 0.602776)
					(end 365.251238 0.625094)
				)
				(arc
					(start 365.863378 0.625094)
					(mid 365.91726 0.602776)
					(end 365.939578 0.548894)
				)
			)
		)
	)
	(zone
		(layer "In1.Cu")
		(hatch none 0.5)
		(connect_pads
			(clearance 0)
		)
		(min_thickness 0.25)
		(keepout
			(tracks not_allowed)
			(vias allowed)
			(pads allowed)
			(copperpour not_allowed)
			(footprints allowed)
		)
		(placement
			(enabled no)
			(sheetname "")
		)
		(fill
			(thermal_gap 0.5)
			(thermal_bridge_width 0.5)
			(island_removal_mode 0)
		)
		(polygon
			(pts
				(arc
					(start 206.9973 -292.782498)
					(mid 206.99358 -292.791478)
					(end 206.9846 -292.795198)
				)
				(arc
					(start 205.5114 -292.795198)
					(mid 205.50242 -292.791478)
					(end 205.4987 -292.782498)
				)
				(arc
					(start 205.4987 -292.28796)
					(mid 205.50242 -292.27898)
					(end 205.5114 -292.27526)
				)
				(arc
					(start 206.9846 -292.27526)
					(mid 206.99358 -292.27898)
					(end 206.9973 -292.28796)
				)
			)
		)
	)
	(zone
		(layer "In1.Cu")
		(hatch none 0.5)
		(connect_pads
			(clearance 0)
		)
		(min_thickness 0.25)
		(keepout
			(tracks not_allowed)
			(vias allowed)
			(pads allowed)
			(copperpour not_allowed)
			(footprints allowed)
		)
		(placement
			(enabled no)
			(sheetname "")
		)
		(fill
			(thermal_gap 0.5)
			(thermal_bridge_width 0.5)
			(island_removal_mode 0)
		)
		(polygon
			(pts
				(arc
					(start 443.2935 -308.932326)
					(mid 443.28978 -308.941306)
					(end 443.2808 -308.945026)
				)
				(arc
					(start 441.8076 -308.945026)
					(mid 441.79862 -308.941306)
					(end 441.7949 -308.932326)
				)
				(arc
					(start 441.7949 -308.437788)
					(mid 441.79862 -308.428808)
					(end 441.8076 -308.425088)
				)
				(arc
					(start 443.2808 -308.425088)
					(mid 443.28978 -308.428808)
					(end 443.2935 -308.437788)
				)
			)
		)
	)
	(zone
		(layer "In1.Cu")
		(hatch none 0.5)
		(connect_pads
			(clearance 0)
		)
		(min_thickness 0.25)
		(keepout
			(tracks not_allowed)
			(vias allowed)
			(pads allowed)
			(copperpour not_allowed)
			(footprints allowed)
		)
		(placement
			(enabled no)
			(sheetname "")
		)
		(fill
			(thermal_gap 0.5)
			(thermal_bridge_width 0.5)
			(island_removal_mode 0)
		)
		(polygon
			(pts
				(arc
					(start 25.901396 -239.23244)
					(mid 25.897676 -239.24142)
					(end 25.888696 -239.24514)
				)
				(arc
					(start 24.415496 -239.24514)
					(mid 24.406516 -239.24142)
					(end 24.402796 -239.23244)
				)
				(arc
					(start 24.402796 -238.737902)
					(mid 24.406516 -238.728922)
					(end 24.415496 -238.725202)
				)
				(arc
					(start 25.888696 -238.725202)
					(mid 25.897676 -238.728922)
					(end 25.901396 -238.737902)
				)
			)
		)
	)
	(zone
		(layer "In1.Cu")
		(hatch none 0.5)
		(connect_pads
			(clearance 0)
		)
		(min_thickness 0.25)
		(keepout
			(tracks not_allowed)
			(vias allowed)
			(pads allowed)
			(copperpour not_allowed)
			(footprints allowed)
		)
		(placement
			(enabled no)
			(sheetname "")
		)
		(fill
			(thermal_gap 0.5)
			(thermal_bridge_width 0.5)
			(island_removal_mode 0)
		)
		(polygon
			(pts
				(arc
					(start 354.097844 -392.30427)
					(mid 353.793044 -392.30427)
					(end 354.097844 -392.30427)
				)
			)
		)
	)
	(zone
		(layer "In1.Cu")
		(hatch none 0.5)
		(connect_pads
			(clearance 0)
		)
		(min_thickness 0.25)
		(keepout
			(tracks not_allowed)
			(vias allowed)
			(pads allowed)
			(copperpour not_allowed)
			(footprints allowed)
		)
		(placement
			(enabled no)
			(sheetname "")
		)
		(fill
			(thermal_gap 0.5)
			(thermal_bridge_width 0.5)
			(island_removal_mode 0)
		)
		(polygon
			(pts
				(arc
					(start 352.788728 -397.156432)
					(mid 352.407728 -397.156432)
					(end 352.788728 -397.156432)
				)
			)
		)
	)
	(zone
		(layer "In1.Cu")
		(hatch none 0.5)
		(connect_pads
			(clearance 0)
		)
		(min_thickness 0.25)
		(keepout
			(tracks not_allowed)
			(vias allowed)
			(pads allowed)
			(copperpour not_allowed)
			(footprints allowed)
		)
		(placement
			(enabled no)
			(sheetname "")
		)
		(fill
			(thermal_gap 0.5)
			(thermal_bridge_width 0.5)
			(island_removal_mode 0)
		)
		(polygon
			(pts
				(arc
					(start 187.809378 -265.5824)
					(mid 187.805658 -265.59138)
					(end 187.796678 -265.5951)
				)
				(arc
					(start 186.323478 -265.5951)
					(mid 186.314498 -265.59138)
					(end 186.310778 -265.5824)
				)
				(arc
					(start 186.310778 -265.087862)
					(mid 186.314498 -265.078882)
					(end 186.323478 -265.075162)
				)
				(arc
					(start 187.796678 -265.075162)
					(mid 187.805658 -265.078882)
					(end 187.809378 -265.087862)
				)
			)
		)
	)
	(zone
		(layer "In1.Cu")
		(hatch none 0.5)
		(connect_pads
			(clearance 0)
		)
		(min_thickness 0.25)
		(keepout
			(tracks not_allowed)
			(vias allowed)
			(pads allowed)
			(copperpour not_allowed)
			(footprints allowed)
		)
		(placement
			(enabled no)
			(sheetname "")
		)
		(fill
			(thermal_gap 0.5)
			(thermal_bridge_width 0.5)
			(island_removal_mode 0)
		)
		(polygon
			(pts
				(arc
					(start 25.901396 -200.132442)
					(mid 25.897676 -200.141422)
					(end 25.888696 -200.145142)
				)
				(arc
					(start 24.415496 -200.145142)
					(mid 24.406516 -200.141422)
					(end 24.402796 -200.132442)
				)
				(arc
					(start 24.402796 -199.637904)
					(mid 24.406516 -199.628924)
					(end 24.415496 -199.625204)
				)
				(arc
					(start 25.888696 -199.625204)
					(mid 25.897676 -199.628924)
					(end 25.901396 -199.637904)
				)
			)
		)
	)
	(zone
		(layer "In1.Cu")
		(hatch none 0.5)
		(connect_pads
			(clearance 0)
		)
		(min_thickness 0.25)
		(keepout
			(tracks not_allowed)
			(vias allowed)
			(pads allowed)
			(copperpour not_allowed)
			(footprints allowed)
		)
		(placement
			(enabled no)
			(sheetname "")
		)
		(fill
			(thermal_gap 0.5)
			(thermal_bridge_width 0.5)
			(island_removal_mode 0)
		)
		(polygon
			(pts
				(arc
					(start 172.72127 -226.482402)
					(mid 172.71755 -226.491382)
					(end 172.70857 -226.495102)
				)
				(arc
					(start 171.23537 -226.495102)
					(mid 171.22639 -226.491382)
					(end 171.22267 -226.482402)
				)
				(arc
					(start 171.22267 -225.987864)
					(mid 171.22639 -225.978884)
					(end 171.23537 -225.975164)
				)
				(arc
					(start 172.70857 -225.975164)
					(mid 172.71755 -225.978884)
					(end 172.72127 -225.987864)
				)
			)
		)
	)
	(zone
		(layer "In1.Cu")
		(hatch none 0.5)
		(connect_pads
			(clearance 0)
		)
		(min_thickness 0.25)
		(keepout
			(tracks not_allowed)
			(vias allowed)
			(pads allowed)
			(copperpour not_allowed)
			(footprints allowed)
		)
		(placement
			(enabled no)
			(sheetname "")
		)
		(fill
			(thermal_gap 0.5)
			(thermal_bridge_width 0.5)
			(island_removal_mode 0)
		)
		(polygon
			(pts
				(arc
					(start 37.545264 -306.38242)
					(mid 37.541544 -306.3914)
					(end 37.532564 -306.39512)
				)
				(arc
					(start 36.059364 -306.39512)
					(mid 36.050384 -306.3914)
					(end 36.046664 -306.38242)
				)
				(arc
					(start 36.046664 -305.887882)
					(mid 36.050384 -305.878902)
					(end 36.059364 -305.875182)
				)
				(arc
					(start 37.532564 -305.875182)
					(mid 37.541544 -305.878902)
					(end 37.545264 -305.887882)
				)
			)
		)
	)
	(zone
		(layer "In1.Cu")
		(hatch none 0.5)
		(connect_pads
			(clearance 0)
		)
		(min_thickness 0.25)
		(keepout
			(tracks not_allowed)
			(vias allowed)
			(pads allowed)
			(copperpour not_allowed)
			(footprints allowed)
		)
		(placement
			(enabled no)
			(sheetname "")
		)
		(fill
			(thermal_gap 0.5)
			(thermal_bridge_width 0.5)
			(island_removal_mode 0)
		)
		(polygon
			(pts
				(arc
					(start 48.533304 -302.982376)
					(mid 48.529584 -302.991356)
					(end 48.520604 -302.995076)
				)
				(arc
					(start 47.047404 -302.995076)
					(mid 47.038424 -302.991356)
					(end 47.034704 -302.982376)
				)
				(arc
					(start 47.034704 -302.487838)
					(mid 47.038424 -302.478858)
					(end 47.047404 -302.475138)
				)
				(arc
					(start 48.520604 -302.475138)
					(mid 48.529584 -302.478858)
					(end 48.533304 -302.487838)
				)
			)
		)
	)
	(zone
		(layer "In1.Cu")
		(hatch none 0.5)
		(connect_pads
			(clearance 0)
		)
		(min_thickness 0.25)
		(keepout
			(tracks not_allowed)
			(vias allowed)
			(pads allowed)
			(copperpour not_allowed)
			(footprints allowed)
		)
		(placement
			(enabled no)
			(sheetname "")
		)
		(fill
			(thermal_gap 0.5)
			(thermal_bridge_width 0.5)
			(island_removal_mode 0)
		)
		(polygon
			(pts
				(arc
					(start 277.941532 -211.182204)
					(mid 277.937812 -211.191184)
					(end 277.928832 -211.194904)
				)
				(arc
					(start 276.455632 -211.194904)
					(mid 276.446652 -211.191184)
					(end 276.442932 -211.182204)
				)
				(arc
					(start 276.442932 -210.687666)
					(mid 276.446652 -210.678686)
					(end 276.455632 -210.674966)
				)
				(arc
					(start 277.928832 -210.674966)
					(mid 277.937812 -210.678686)
					(end 277.941532 -210.687666)
				)
			)
		)
	)
	(zone
		(layer "In1.Cu")
		(hatch none 0.5)
		(connect_pads
			(clearance 0)
		)
		(min_thickness 0.25)
		(keepout
			(tracks not_allowed)
			(vias allowed)
			(pads allowed)
			(copperpour not_allowed)
			(footprints allowed)
		)
		(placement
			(enabled no)
			(sheetname "")
		)
		(fill
			(thermal_gap 0.5)
			(thermal_bridge_width 0.5)
			(island_removal_mode 0)
		)
		(polygon
			(pts
				(arc
					(start 341.988902 -393.69238)
					(mid 341.607902 -393.69238)
					(end 341.988902 -393.69238)
				)
			)
		)
	)
	(zone
		(layer "In1.Cu")
		(hatch none 0.5)
		(connect_pads
			(clearance 0)
		)
		(min_thickness 0.25)
		(keepout
			(tracks not_allowed)
			(vias allowed)
			(pads allowed)
			(copperpour not_allowed)
			(footprints allowed)
		)
		(placement
			(enabled no)
			(sheetname "")
		)
		(fill
			(thermal_gap 0.5)
			(thermal_bridge_width 0.5)
			(island_removal_mode 0)
		)
		(polygon
			(pts
				(arc
					(start 277.941532 -251.132086)
					(mid 277.937812 -251.141066)
					(end 277.928832 -251.144786)
				)
				(arc
					(start 276.455632 -251.144786)
					(mid 276.446652 -251.141066)
					(end 276.442932 -251.132086)
				)
				(arc
					(start 276.442932 -250.637548)
					(mid 276.446652 -250.628568)
					(end 276.455632 -250.624848)
				)
				(arc
					(start 277.928832 -250.624848)
					(mid 277.937812 -250.628568)
					(end 277.941532 -250.637548)
				)
			)
		)
	)
	(zone
		(layer "In1.Cu")
		(hatch none 0.5)
		(connect_pads
			(clearance 0)
		)
		(min_thickness 0.25)
		(keepout
			(tracks not_allowed)
			(vias allowed)
			(pads allowed)
			(copperpour not_allowed)
			(footprints allowed)
		)
		(placement
			(enabled no)
			(sheetname "")
		)
		(fill
			(thermal_gap 0.5)
			(thermal_bridge_width 0.5)
			(island_removal_mode 0)
		)
		(polygon
			(pts
				(arc
					(start 403.198076 -392.30427)
					(mid 402.893276 -392.30427)
					(end 403.198076 -392.30427)
				)
			)
		)
	)
	(zone
		(layer "In1.Cu")
		(hatch none 0.5)
		(connect_pads
			(clearance 0)
		)
		(min_thickness 0.25)
		(keepout
			(tracks not_allowed)
			(vias allowed)
			(pads allowed)
			(copperpour not_allowed)
			(footprints allowed)
		)
		(placement
			(enabled no)
			(sheetname "")
		)
		(fill
			(thermal_gap 0.5)
			(thermal_bridge_width 0.5)
			(island_removal_mode 0)
		)
		(polygon
			(pts
				(arc
					(start 374.5611 -394.385292)
					(mid 374.1801 -394.385292)
					(end 374.5611 -394.385292)
				)
			)
		)
	)
	(zone
		(layer "In1.Cu")
		(hatch none 0.5)
		(connect_pads
			(clearance 0)
		)
		(min_thickness 0.25)
		(keepout
			(tracks not_allowed)
			(vias allowed)
			(pads allowed)
			(copperpour not_allowed)
			(footprints allowed)
		)
		(placement
			(enabled no)
			(sheetname "")
		)
		(fill
			(thermal_gap 0.5)
			(thermal_bridge_width 0.5)
			(island_removal_mode 0)
		)
		(polygon
			(pts
				(arc
					(start 30.001464 -223.932496)
					(mid 29.997744 -223.941476)
					(end 29.988764 -223.945196)
				)
				(arc
					(start 28.515564 -223.945196)
					(mid 28.506584 -223.941476)
					(end 28.502864 -223.932496)
				)
				(arc
					(start 28.502864 -223.437958)
					(mid 28.506584 -223.428978)
					(end 28.515564 -223.425258)
				)
				(arc
					(start 29.988764 -223.425258)
					(mid 29.997744 -223.428978)
					(end 30.001464 -223.437958)
				)
			)
		)
	)
	(zone
		(layer "In1.Cu")
		(hatch none 0.5)
		(connect_pads
			(clearance 0)
		)
		(min_thickness 0.25)
		(keepout
			(tracks not_allowed)
			(vias allowed)
			(pads allowed)
			(copperpour not_allowed)
			(footprints allowed)
		)
		(placement
			(enabled no)
			(sheetname "")
		)
		(fill
			(thermal_gap 0.5)
			(thermal_bridge_width 0.5)
			(island_removal_mode 0)
		)
		(polygon
			(pts
				(arc
					(start 22.45741 -234.982512)
					(mid 22.45369 -234.991492)
					(end 22.44471 -234.995212)
				)
				(arc
					(start 20.97151 -234.995212)
					(mid 20.96253 -234.991492)
					(end 20.95881 -234.982512)
				)
				(arc
					(start 20.95881 -234.487974)
					(mid 20.96253 -234.478994)
					(end 20.97151 -234.475274)
				)
				(arc
					(start 22.44471 -234.475274)
					(mid 22.45369 -234.478994)
					(end 22.45741 -234.487974)
				)
			)
		)
	)
	(zone
		(layer "In1.Cu")
		(hatch none 0.5)
		(connect_pads
			(clearance 0)
		)
		(min_thickness 0.25)
		(keepout
			(tracks not_allowed)
			(vias allowed)
			(pads allowed)
			(copperpour not_allowed)
			(footprints allowed)
		)
		(placement
			(enabled no)
			(sheetname "")
		)
		(fill
			(thermal_gap 0.5)
			(thermal_bridge_width 0.5)
			(island_removal_mode 0)
		)
		(polygon
			(pts
				(arc
					(start 202.897232 -286.832548)
					(mid 202.893512 -286.841528)
					(end 202.884532 -286.845248)
				)
				(arc
					(start 201.411332 -286.845248)
					(mid 201.402352 -286.841528)
					(end 201.398632 -286.832548)
				)
				(arc
					(start 201.398632 -286.33801)
					(mid 201.402352 -286.32903)
					(end 201.411332 -286.32531)
				)
				(arc
					(start 202.884532 -286.32531)
					(mid 202.893512 -286.32903)
					(end 202.897232 -286.33801)
				)
			)
		)
	)
	(zone
		(layer "In1.Cu")
		(hatch none 0.5)
		(connect_pads
			(clearance 0)
		)
		(min_thickness 0.25)
		(keepout
			(tracks not_allowed)
			(vias allowed)
			(pads allowed)
			(copperpour not_allowed)
			(footprints allowed)
		)
		(placement
			(enabled no)
			(sheetname "")
		)
		(fill
			(thermal_gap 0.5)
			(thermal_bridge_width 0.5)
			(island_removal_mode 0)
		)
		(polygon
			(pts
				(arc
					(start 86.388956 -386.003292)
					(mid 86.007956 -386.003292)
					(end 86.388956 -386.003292)
				)
			)
		)
	)
	(zone
		(layer "In1.Cu")
		(hatch none 0.5)
		(connect_pads
			(clearance 0)
		)
		(min_thickness 0.25)
		(keepout
			(tracks not_allowed)
			(vias allowed)
			(pads allowed)
			(copperpour not_allowed)
			(footprints allowed)
		)
		(placement
			(enabled no)
			(sheetname "")
		)
		(fill
			(thermal_gap 0.5)
			(thermal_bridge_width 0.5)
			(island_removal_mode 0)
		)
		(polygon
			(pts
				(arc
					(start 49.391062 -383.440686)
					(mid 49.518062 -383.567686)
					(end 49.645062 -383.440686)
				)
				(arc
					(start 49.645062 -383.364486)
					(mid 49.518062 -383.237486)
					(end 49.391062 -383.364486)
				)
			)
		)
	)
	(zone
		(layer "In1.Cu")
		(hatch none 0.5)
		(connect_pads
			(clearance 0)
		)
		(min_thickness 0.25)
		(keepout
			(tracks not_allowed)
			(vias allowed)
			(pads allowed)
			(copperpour not_allowed)
			(footprints allowed)
		)
		(placement
			(enabled no)
			(sheetname "")
		)
		(fill
			(thermal_gap 0.5)
			(thermal_bridge_width 0.5)
			(island_removal_mode 0)
		)
		(polygon
			(pts
				(arc
					(start 300.57344 -292.782244)
					(mid 300.56972 -292.791224)
					(end 300.56074 -292.794944)
				)
				(arc
					(start 299.08754 -292.794944)
					(mid 299.07856 -292.791224)
					(end 299.07484 -292.782244)
				)
				(arc
					(start 299.07484 -292.287706)
					(mid 299.07856 -292.278726)
					(end 299.08754 -292.275006)
				)
				(arc
					(start 300.56074 -292.275006)
					(mid 300.56972 -292.278726)
					(end 300.57344 -292.287706)
				)
			)
		)
	)
	(zone
		(layer "In1.Cu")
		(hatch none 0.5)
		(connect_pads
			(clearance 0)
		)
		(min_thickness 0.25)
		(keepout
			(tracks not_allowed)
			(vias allowed)
			(pads allowed)
			(copperpour not_allowed)
			(footprints allowed)
		)
		(placement
			(enabled no)
			(sheetname "")
		)
		(fill
			(thermal_gap 0.5)
			(thermal_bridge_width 0.5)
			(island_removal_mode 0)
		)
		(polygon
			(pts
				(arc
					(start 443.2935 -276.632162)
					(mid 443.28978 -276.641142)
					(end 443.2808 -276.644862)
				)
				(arc
					(start 441.8076 -276.644862)
					(mid 441.79862 -276.641142)
					(end 441.7949 -276.632162)
				)
				(arc
					(start 441.7949 -276.137624)
					(mid 441.79862 -276.128644)
					(end 441.8076 -276.124924)
				)
				(arc
					(start 443.2808 -276.124924)
					(mid 443.28978 -276.128644)
					(end 443.2935 -276.137624)
				)
			)
		)
	)
	(zone
		(layer "In1.Cu")
		(hatch none 0.5)
		(connect_pads
			(clearance 0)
		)
		(min_thickness 0.25)
		(keepout
			(tracks not_allowed)
			(vias allowed)
			(pads allowed)
			(copperpour not_allowed)
			(footprints allowed)
		)
		(placement
			(enabled no)
			(sheetname "")
		)
		(fill
			(thermal_gap 0.5)
			(thermal_bridge_width 0.5)
			(island_removal_mode 0)
		)
		(polygon
			(pts
				(arc
					(start 37.545264 -222.232474)
					(mid 37.541544 -222.241454)
					(end 37.532564 -222.245174)
				)
				(arc
					(start 36.059364 -222.245174)
					(mid 36.050384 -222.241454)
					(end 36.046664 -222.232474)
				)
				(arc
					(start 36.046664 -221.737936)
					(mid 36.050384 -221.728956)
					(end 36.059364 -221.725236)
				)
				(arc
					(start 37.532564 -221.725236)
					(mid 37.541544 -221.728956)
					(end 37.545264 -221.737936)
				)
			)
		)
	)
	(zone
		(layer "In1.Cu")
		(hatch none 0.5)
		(connect_pads
			(clearance 0)
		)
		(min_thickness 0.25)
		(keepout
			(tracks not_allowed)
			(vias allowed)
			(pads allowed)
			(copperpour not_allowed)
			(footprints allowed)
		)
		(placement
			(enabled no)
			(sheetname "")
		)
		(fill
			(thermal_gap 0.5)
			(thermal_bridge_width 0.5)
			(island_removal_mode 0)
		)
		(polygon
			(pts
				(arc
					(start 81.298034 -383.92227)
					(mid 80.993234 -383.92227)
					(end 81.298034 -383.92227)
				)
			)
		)
	)
	(zone
		(layer "In1.Cu")
		(hatch none 0.5)
		(connect_pads
			(clearance 0)
		)
		(min_thickness 0.25)
		(keepout
			(tracks not_allowed)
			(vias allowed)
			(pads allowed)
			(copperpour not_allowed)
			(footprints allowed)
		)
		(placement
			(enabled no)
			(sheetname "")
		)
		(fill
			(thermal_gap 0.5)
			(thermal_bridge_width 0.5)
			(island_removal_mode 0)
		)
		(polygon
			(pts
				(arc
					(start 160.688782 -389.467344)
					(mid 160.307782 -389.467344)
					(end 160.688782 -389.467344)
				)
			)
		)
	)
	(zone
		(layer "In1.Cu")
		(hatch none 0.5)
		(connect_pads
			(clearance 0)
		)
		(min_thickness 0.25)
		(keepout
			(tracks not_allowed)
			(vias allowed)
			(pads allowed)
			(copperpour not_allowed)
			(footprints allowed)
		)
		(placement
			(enabled no)
			(sheetname "")
		)
		(fill
			(thermal_gap 0.5)
			(thermal_bridge_width 0.5)
			(island_removal_mode 0)
		)
		(polygon
			(pts
				(arc
					(start 52.991004 -383.440686)
					(mid 53.118004 -383.567686)
					(end 53.245004 -383.440686)
				)
				(arc
					(start 53.245004 -383.364486)
					(mid 53.118004 -383.237486)
					(end 52.991004 -383.364486)
				)
			)
		)
	)
	(zone
		(layer "In1.Cu")
		(hatch none 0.5)
		(connect_pads
			(clearance 0)
		)
		(min_thickness 0.25)
		(keepout
			(tracks not_allowed)
			(vias allowed)
			(pads allowed)
			(copperpour not_allowed)
			(footprints allowed)
		)
		(placement
			(enabled no)
			(sheetname "")
		)
		(fill
			(thermal_gap 0.5)
			(thermal_bridge_width 0.5)
			(island_removal_mode 0)
		)
		(polygon
			(pts
				(arc
					(start 33.445196 -314.032392)
					(mid 33.441476 -314.041372)
					(end 33.432496 -314.045092)
				)
				(arc
					(start 31.959296 -314.045092)
					(mid 31.950316 -314.041372)
					(end 31.946596 -314.032392)
				)
				(arc
					(start 31.946596 -313.537854)
					(mid 31.950316 -313.528874)
					(end 31.959296 -313.525154)
				)
				(arc
					(start 33.432496 -313.525154)
					(mid 33.441476 -313.528874)
					(end 33.445196 -313.537854)
				)
			)
		)
	)
	(zone
		(layer "In1.Cu")
		(hatch none 0.5)
		(connect_pads
			(clearance 0)
		)
		(min_thickness 0.25)
		(keepout
			(tracks not_allowed)
			(vias allowed)
			(pads allowed)
			(copperpour not_allowed)
			(footprints allowed)
		)
		(placement
			(enabled no)
			(sheetname "")
		)
		(fill
			(thermal_gap 0.5)
			(thermal_bridge_width 0.5)
			(island_removal_mode 0)
		)
		(polygon
			(pts
				(arc
					(start 165.488874 -389.467344)
					(mid 165.107874 -389.467344)
					(end 165.488874 -389.467344)
				)
			)
		)
	)
	(zone
		(layer "In1.Cu")
		(hatch none 0.5)
		(connect_pads
			(clearance 0)
		)
		(min_thickness 0.25)
		(keepout
			(tracks not_allowed)
			(vias allowed)
			(pads allowed)
			(copperpour not_allowed)
			(footprints allowed)
		)
		(placement
			(enabled no)
			(sheetname "")
		)
		(fill
			(thermal_gap 0.5)
			(thermal_bridge_width 0.5)
			(island_removal_mode 0)
		)
		(polygon
			(pts
				(arc
					(start 199.4535 -240.932462)
					(mid 199.44978 -240.941442)
					(end 199.4408 -240.945162)
				)
				(arc
					(start 197.9676 -240.945162)
					(mid 197.95862 -240.941442)
					(end 197.9549 -240.932462)
				)
				(arc
					(start 197.9549 -240.437924)
					(mid 197.95862 -240.428944)
					(end 197.9676 -240.425224)
				)
				(arc
					(start 199.4408 -240.425224)
					(mid 199.44978 -240.428944)
					(end 199.4535 -240.437924)
				)
			)
		)
	)
	(zone
		(layer "In1.Cu")
		(hatch none 0.5)
		(connect_pads
			(clearance 0)
		)
		(min_thickness 0.25)
		(keepout
			(tracks not_allowed)
			(vias allowed)
			(pads allowed)
			(copperpour not_allowed)
			(footprints allowed)
		)
		(placement
			(enabled no)
			(sheetname "")
		)
		(fill
			(thermal_gap 0.5)
			(thermal_bridge_width 0.5)
			(island_removal_mode 0)
		)
		(polygon
			(pts
				(arc
					(start 300.57344 -289.3822)
					(mid 300.56972 -289.39118)
					(end 300.56074 -289.3949)
				)
				(arc
					(start 299.08754 -289.3949)
					(mid 299.07856 -289.39118)
					(end 299.07484 -289.3822)
				)
				(arc
					(start 299.07484 -288.887662)
					(mid 299.07856 -288.878682)
					(end 299.08754 -288.874962)
				)
				(arc
					(start 300.56074 -288.874962)
					(mid 300.56972 -288.878682)
					(end 300.57344 -288.887662)
				)
			)
		)
	)
	(zone
		(layer "In1.Cu")
		(hatch none 0.5)
		(connect_pads
			(clearance 0)
		)
		(min_thickness 0.25)
		(keepout
			(tracks not_allowed)
			(vias allowed)
			(pads allowed)
			(copperpour not_allowed)
			(footprints allowed)
		)
		(placement
			(enabled no)
			(sheetname "")
		)
		(fill
			(thermal_gap 0.5)
			(thermal_bridge_width 0.5)
			(island_removal_mode 0)
		)
		(polygon
			(pts
				(arc
					(start 285.485332 -246.032274)
					(mid 285.481612 -246.041254)
					(end 285.472632 -246.044974)
				)
				(arc
					(start 283.999432 -246.044974)
					(mid 283.990452 -246.041254)
					(end 283.986732 -246.032274)
				)
				(arc
					(start 283.986732 -245.537736)
					(mid 283.990452 -245.528756)
					(end 283.999432 -245.525036)
				)
				(arc
					(start 285.472632 -245.525036)
					(mid 285.481612 -245.528756)
					(end 285.485332 -245.537736)
				)
			)
		)
	)
	(zone
		(layer "In1.Cu")
		(hatch none 0.5)
		(connect_pads
			(clearance 0)
		)
		(min_thickness 0.25)
		(keepout
			(tracks not_allowed)
			(vias allowed)
			(pads allowed)
			(copperpour not_allowed)
			(footprints allowed)
		)
		(placement
			(enabled no)
			(sheetname "")
		)
		(fill
			(thermal_gap 0.5)
			(thermal_bridge_width 0.5)
			(island_removal_mode 0)
		)
		(polygon
			(pts
				(arc
					(start 191.909446 -246.032528)
					(mid 191.905726 -246.041508)
					(end 191.896746 -246.045228)
				)
				(arc
					(start 190.423546 -246.045228)
					(mid 190.414566 -246.041508)
					(end 190.410846 -246.032528)
				)
				(arc
					(start 190.410846 -245.53799)
					(mid 190.414566 -245.52901)
					(end 190.423546 -245.52529)
				)
				(arc
					(start 191.896746 -245.52529)
					(mid 191.905726 -245.52901)
					(end 191.909446 -245.53799)
				)
			)
		)
	)
	(zone
		(layer "In1.Cu")
		(hatch none 0.5)
		(connect_pads
			(clearance 0)
		)
		(min_thickness 0.25)
		(keepout
			(tracks not_allowed)
			(vias allowed)
			(pads allowed)
			(copperpour not_allowed)
			(footprints allowed)
		)
		(placement
			(enabled no)
			(sheetname "")
		)
		(fill
			(thermal_gap 0.5)
			(thermal_bridge_width 0.5)
			(island_removal_mode 0)
		)
		(polygon
			(pts
				(arc
					(start 304.017426 -279.182322)
					(mid 304.013706 -279.191302)
					(end 304.004726 -279.195022)
				)
				(arc
					(start 302.531526 -279.195022)
					(mid 302.522546 -279.191302)
					(end 302.518826 -279.182322)
				)
				(arc
					(start 302.518826 -278.687784)
					(mid 302.522546 -278.678804)
					(end 302.531526 -278.675084)
				)
				(arc
					(start 304.004726 -278.675084)
					(mid 304.013706 -278.678804)
					(end 304.017426 -278.687784)
				)
			)
		)
	)
	(zone
		(layer "In1.Cu")
		(hatch none 0.5)
		(connect_pads
			(clearance 0)
		)
		(min_thickness 0.25)
		(keepout
			(tracks not_allowed)
			(vias allowed)
			(pads allowed)
			(copperpour not_allowed)
			(footprints allowed)
		)
		(placement
			(enabled no)
			(sheetname "")
		)
		(fill
			(thermal_gap 0.5)
			(thermal_bridge_width 0.5)
			(island_removal_mode 0)
		)
		(polygon
			(pts
				(arc
					(start 58.990992 -391.319258)
					(mid 59.117992 -391.446258)
					(end 59.244992 -391.319258)
				)
				(arc
					(start 59.244992 -391.243058)
					(mid 59.117992 -391.116058)
					(end 58.990992 -391.243058)
				)
			)
		)
	)
	(zone
		(layer "In1.Cu")
		(hatch none 0.5)
		(connect_pads
			(clearance 0)
		)
		(min_thickness 0.25)
		(keepout
			(tracks not_allowed)
			(vias allowed)
			(pads allowed)
			(copperpour not_allowed)
			(footprints allowed)
		)
		(placement
			(enabled no)
			(sheetname "")
		)
		(fill
			(thermal_gap 0.5)
			(thermal_bridge_width 0.5)
			(island_removal_mode 0)
		)
		(polygon
			(pts
				(arc
					(start 154.288998 -385.31038)
					(mid 153.907998 -385.31038)
					(end 154.288998 -385.31038)
				)
			)
		)
	)
	(zone
		(layer "In1.Cu")
		(hatch none 0.5)
		(connect_pads
			(clearance 0)
		)
		(min_thickness 0.25)
		(keepout
			(tracks not_allowed)
			(vias allowed)
			(pads allowed)
			(copperpour not_allowed)
			(footprints allowed)
		)
		(placement
			(enabled no)
			(sheetname "")
		)
		(fill
			(thermal_gap 0.5)
			(thermal_bridge_width 0.5)
			(island_removal_mode 0)
		)
		(polygon
			(pts
				(arc
					(start 45.089318 -225.632518)
					(mid 45.085598 -225.641498)
					(end 45.076618 -225.645218)
				)
				(arc
					(start 43.603418 -225.645218)
					(mid 43.594438 -225.641498)
					(end 43.590718 -225.632518)
				)
				(arc
					(start 43.590718 -225.13798)
					(mid 43.594438 -225.129)
					(end 43.603418 -225.12528)
				)
				(arc
					(start 45.076618 -225.12528)
					(mid 45.085598 -225.129)
					(end 45.089318 -225.13798)
				)
			)
		)
	)
	(zone
		(layer "In1.Cu")
		(hatch none 0.5)
		(connect_pads
			(clearance 0)
		)
		(min_thickness 0.25)
		(keepout
			(tracks not_allowed)
			(vias allowed)
			(pads allowed)
			(copperpour not_allowed)
			(footprints allowed)
		)
		(placement
			(enabled no)
			(sheetname "")
		)
		(fill
			(thermal_gap 0.5)
			(thermal_bridge_width 0.5)
			(island_removal_mode 0)
		)
		(polygon
			(pts
				(arc
					(start 199.4535 -247.73255)
					(mid 199.44978 -247.74153)
					(end 199.4408 -247.74525)
				)
				(arc
					(start 197.9676 -247.74525)
					(mid 197.95862 -247.74153)
					(end 197.9549 -247.73255)
				)
				(arc
					(start 197.9549 -247.238012)
					(mid 197.95862 -247.229032)
					(end 197.9676 -247.225312)
				)
				(arc
					(start 199.4408 -247.225312)
					(mid 199.44978 -247.229032)
					(end 199.4535 -247.238012)
				)
			)
		)
	)
	(zone
		(layer "In1.Cu")
		(hatch none 0.5)
		(connect_pads
			(clearance 0)
		)
		(min_thickness 0.25)
		(keepout
			(tracks not_allowed)
			(vias allowed)
			(pads allowed)
			(copperpour not_allowed)
			(footprints allowed)
		)
		(placement
			(enabled no)
			(sheetname "")
		)
		(fill
			(thermal_gap 0.5)
			(thermal_bridge_width 0.5)
			(island_removal_mode 0)
		)
		(polygon
			(pts
				(arc
					(start 52.633372 -283.432504)
					(mid 52.629652 -283.441484)
					(end 52.620672 -283.445204)
				)
				(arc
					(start 51.147472 -283.445204)
					(mid 51.138492 -283.441484)
					(end 51.134772 -283.432504)
				)
				(arc
					(start 51.134772 -282.937966)
					(mid 51.138492 -282.928986)
					(end 51.147472 -282.925266)
				)
				(arc
					(start 52.620672 -282.925266)
					(mid 52.629652 -282.928986)
					(end 52.633372 -282.937966)
				)
			)
		)
	)
	(zone
		(layer "In1.Cu")
		(hatch none 0.5)
		(connect_pads
			(clearance 0)
		)
		(min_thickness 0.25)
		(keepout
			(tracks not_allowed)
			(vias allowed)
			(pads allowed)
			(copperpour not_allowed)
			(footprints allowed)
		)
		(placement
			(enabled no)
			(sheetname "")
		)
		(fill
			(thermal_gap 0.5)
			(thermal_bridge_width 0.5)
			(island_removal_mode 0)
		)
		(polygon
			(pts
				(arc
					(start 420.661338 -288.532316)
					(mid 420.657618 -288.541296)
					(end 420.648638 -288.545016)
				)
				(arc
					(start 419.175438 -288.545016)
					(mid 419.166458 -288.541296)
					(end 419.162738 -288.532316)
				)
				(arc
					(start 419.162738 -288.037778)
					(mid 419.166458 -288.028798)
					(end 419.175438 -288.025078)
				)
				(arc
					(start 420.648638 -288.025078)
					(mid 420.657618 -288.028798)
					(end 420.661338 -288.037778)
				)
			)
		)
	)
	(zone
		(layer "In1.Cu")
		(hatch none 0.5)
		(connect_pads
			(clearance 0)
		)
		(min_thickness 0.25)
		(keepout
			(tracks not_allowed)
			(vias allowed)
			(pads allowed)
			(copperpour not_allowed)
			(footprints allowed)
		)
		(placement
			(enabled no)
			(sheetname "")
		)
		(fill
			(thermal_gap 0.5)
			(thermal_bridge_width 0.5)
			(island_removal_mode 0)
		)
		(polygon
			(pts
				(arc
					(start 406.689052 -397.156432)
					(mid 406.308052 -397.156432)
					(end 406.689052 -397.156432)
				)
			)
		)
	)
	(zone
		(layer "In1.Cu")
		(hatch none 0.5)
		(connect_pads
			(clearance 0)
		)
		(min_thickness 0.25)
		(keepout
			(tracks not_allowed)
			(vias allowed)
			(pads allowed)
			(copperpour not_allowed)
			(footprints allowed)
		)
		(placement
			(enabled no)
			(sheetname "")
		)
		(fill
			(thermal_gap 0.5)
			(thermal_bridge_width 0.5)
			(island_removal_mode 0)
		)
		(polygon
			(pts
				(arc
					(start 191.909446 -272.382488)
					(mid 191.905726 -272.391468)
					(end 191.896746 -272.395188)
				)
				(arc
					(start 190.423546 -272.395188)
					(mid 190.414566 -272.391468)
					(end 190.410846 -272.382488)
				)
				(arc
					(start 190.410846 -271.88795)
					(mid 190.414566 -271.87897)
					(end 190.423546 -271.87525)
				)
				(arc
					(start 191.896746 -271.87525)
					(mid 191.905726 -271.87897)
					(end 191.909446 -271.88795)
				)
			)
		)
	)
	(zone
		(layer "In1.Cu")
		(hatch none 0.5)
		(connect_pads
			(clearance 0)
		)
		(min_thickness 0.25)
		(keepout
			(tracks not_allowed)
			(vias allowed)
			(pads allowed)
			(copperpour not_allowed)
			(footprints allowed)
		)
		(placement
			(enabled no)
			(sheetname "")
		)
		(fill
			(thermal_gap 0.5)
			(thermal_bridge_width 0.5)
			(island_removal_mode 0)
		)
		(polygon
			(pts
				(arc
					(start 59.417966 -383.76987)
					(mid 59.417966 -384.07467)
					(end 59.417966 -383.76987)
				)
			)
		)
	)
	(zone
		(layer "In1.Cu")
		(hatch none 0.5)
		(connect_pads
			(clearance 0)
		)
		(min_thickness 0.25)
		(keepout
			(tracks not_allowed)
			(vias allowed)
			(pads allowed)
			(copperpour not_allowed)
			(footprints allowed)
		)
		(placement
			(enabled no)
			(sheetname "")
		)
		(fill
			(thermal_gap 0.5)
			(thermal_bridge_width 0.5)
			(island_removal_mode 0)
		)
		(polygon
			(pts
				(arc
					(start 172.72127 -228.182424)
					(mid 172.71755 -228.191404)
					(end 172.70857 -228.195124)
				)
				(arc
					(start 171.23537 -228.195124)
					(mid 171.22639 -228.191404)
					(end 171.22267 -228.182424)
				)
				(arc
					(start 171.22267 -227.687886)
					(mid 171.22639 -227.678906)
					(end 171.23537 -227.675186)
				)
				(arc
					(start 172.70857 -227.675186)
					(mid 172.71755 -227.678906)
					(end 172.72127 -227.687886)
				)
			)
		)
	)
	(zone
		(layer "In1.Cu")
		(hatch none 0.5)
		(connect_pads
			(clearance 0)
		)
		(min_thickness 0.25)
		(keepout
			(tracks not_allowed)
			(vias allowed)
			(pads allowed)
			(copperpour not_allowed)
			(footprints allowed)
		)
		(placement
			(enabled no)
			(sheetname "")
		)
		(fill
			(thermal_gap 0.5)
			(thermal_bridge_width 0.5)
			(island_removal_mode 0)
		)
		(polygon
			(pts
				(arc
					(start 277.941532 -314.032138)
					(mid 277.937812 -314.041118)
					(end 277.928832 -314.044838)
				)
				(arc
					(start 276.455632 -314.044838)
					(mid 276.446652 -314.041118)
					(end 276.442932 -314.032138)
				)
				(arc
					(start 276.442932 -313.5376)
					(mid 276.446652 -313.52862)
					(end 276.455632 -313.5249)
				)
				(arc
					(start 277.928832 -313.5249)
					(mid 277.937812 -313.52862)
					(end 277.941532 -313.5376)
				)
			)
		)
	)
	(zone
		(layer "In1.Cu")
		(hatch none 0.5)
		(connect_pads
			(clearance 0)
		)
		(min_thickness 0.25)
		(keepout
			(tracks not_allowed)
			(vias allowed)
			(pads allowed)
			(copperpour not_allowed)
			(footprints allowed)
		)
		(placement
			(enabled no)
			(sheetname "")
		)
		(fill
			(thermal_gap 0.5)
			(thermal_bridge_width 0.5)
			(island_removal_mode 0)
		)
		(polygon
			(pts
				(arc
					(start 443.2935 -221.382082)
					(mid 443.28978 -221.391062)
					(end 443.2808 -221.394782)
				)
				(arc
					(start 441.8076 -221.394782)
					(mid 441.79862 -221.391062)
					(end 441.7949 -221.382082)
				)
				(arc
					(start 441.7949 -220.887544)
					(mid 441.79862 -220.878564)
					(end 441.8076 -220.874844)
				)
				(arc
					(start 443.2808 -220.874844)
					(mid 443.28978 -220.878564)
					(end 443.2935 -220.887544)
				)
			)
		)
	)
	(zone
		(layer "In1.Cu")
		(hatch none 0.5)
		(connect_pads
			(clearance 0)
		)
		(min_thickness 0.25)
		(keepout
			(tracks not_allowed)
			(vias allowed)
			(pads allowed)
			(copperpour not_allowed)
			(footprints allowed)
		)
		(placement
			(enabled no)
			(sheetname "")
		)
		(fill
			(thermal_gap 0.5)
			(thermal_bridge_width 0.5)
			(island_removal_mode 0)
		)
		(polygon
			(pts
				(arc
					(start 300.57344 -203.532232)
					(mid 300.56972 -203.541212)
					(end 300.56074 -203.544932)
				)
				(arc
					(start 299.08754 -203.544932)
					(mid 299.07856 -203.541212)
					(end 299.07484 -203.532232)
				)
				(arc
					(start 299.07484 -203.037694)
					(mid 299.07856 -203.028714)
					(end 299.08754 -203.024994)
				)
				(arc
					(start 300.56074 -203.024994)
					(mid 300.56972 -203.028714)
					(end 300.57344 -203.037694)
				)
			)
		)
	)
	(zone
		(layer "In1.Cu")
		(hatch none 0.5)
		(connect_pads
			(clearance 0)
		)
		(min_thickness 0.25)
		(keepout
			(tracks not_allowed)
			(vias allowed)
			(pads allowed)
			(copperpour not_allowed)
			(footprints allowed)
		)
		(placement
			(enabled no)
			(sheetname "")
		)
		(fill
			(thermal_gap 0.5)
			(thermal_bridge_width 0.5)
			(island_removal_mode 0)
		)
		(polygon
			(pts
				(arc
					(start 296.473372 -314.032138)
					(mid 296.469652 -314.041118)
					(end 296.460672 -314.044838)
				)
				(arc
					(start 294.987472 -314.044838)
					(mid 294.978492 -314.041118)
					(end 294.974772 -314.032138)
				)
				(arc
					(start 294.974772 -313.5376)
					(mid 294.978492 -313.52862)
					(end 294.987472 -313.5249)
				)
				(arc
					(start 296.460672 -313.5249)
					(mid 296.469652 -313.52862)
					(end 296.473372 -313.5376)
				)
			)
		)
	)
	(zone
		(layer "In1.Cu")
		(hatch none 0.5)
		(connect_pads
			(clearance 0)
		)
		(min_thickness 0.25)
		(keepout
			(tracks not_allowed)
			(vias allowed)
			(pads allowed)
			(copperpour not_allowed)
			(footprints allowed)
		)
		(placement
			(enabled no)
			(sheetname "")
		)
		(fill
			(thermal_gap 0.5)
			(thermal_bridge_width 0.5)
			(island_removal_mode 0)
		)
		(polygon
			(pts
				(arc
					(start 95.698056 -390.761474)
					(mid 95.393256 -390.761474)
					(end 95.698056 -390.761474)
				)
			)
		)
	)
	(zone
		(layer "In1.Cu")
		(hatch none 0.5)
		(connect_pads
			(clearance 0)
		)
		(min_thickness 0.25)
		(keepout
			(tracks not_allowed)
			(vias allowed)
			(pads allowed)
			(copperpour not_allowed)
			(footprints allowed)
		)
		(placement
			(enabled no)
			(sheetname "")
		)
		(fill
			(thermal_gap 0.5)
			(thermal_bridge_width 0.5)
			(island_removal_mode 0)
		)
		(polygon
			(pts
				(arc
					(start 403.488906 -394.385292)
					(mid 403.107906 -394.385292)
					(end 403.488906 -394.385292)
				)
			)
		)
	)
	(zone
		(layer "In1.Cu")
		(hatch none 0.5)
		(connect_pads
			(clearance 0)
		)
		(min_thickness 0.25)
		(keepout
			(tracks not_allowed)
			(vias allowed)
			(pads allowed)
			(copperpour not_allowed)
			(footprints allowed)
		)
		(placement
			(enabled no)
			(sheetname "")
		)
		(fill
			(thermal_gap 0.5)
			(thermal_bridge_width 0.5)
			(island_removal_mode 0)
		)
		(polygon
			(pts
				(arc
					(start 281.385264 -251.982224)
					(mid 281.381544 -251.991204)
					(end 281.372564 -251.994924)
				)
				(arc
					(start 279.899364 -251.994924)
					(mid 279.890384 -251.991204)
					(end 279.886664 -251.982224)
				)
				(arc
					(start 279.886664 -251.487686)
					(mid 279.890384 -251.478706)
					(end 279.899364 -251.474986)
				)
				(arc
					(start 281.372564 -251.474986)
					(mid 281.381544 -251.478706)
					(end 281.385264 -251.487686)
				)
			)
		)
	)
	(zone
		(layer "In1.Cu")
		(hatch none 0.5)
		(connect_pads
			(clearance 0)
		)
		(min_thickness 0.25)
		(keepout
			(tracks not_allowed)
			(vias allowed)
			(pads allowed)
			(copperpour not_allowed)
			(footprints allowed)
		)
		(placement
			(enabled no)
			(sheetname "")
		)
		(fill
			(thermal_gap 0.5)
			(thermal_bridge_width 0.5)
			(island_removal_mode 0)
		)
		(polygon
			(pts
				(arc
					(start 270.397478 -275.782278)
					(mid 270.393758 -275.791258)
					(end 270.384778 -275.794978)
				)
				(arc
					(start 268.911578 -275.794978)
					(mid 268.902598 -275.791258)
					(end 268.898878 -275.782278)
				)
				(arc
					(start 268.898878 -275.28774)
					(mid 268.902598 -275.27876)
					(end 268.911578 -275.27504)
				)
				(arc
					(start 270.384778 -275.27504)
					(mid 270.393758 -275.27876)
					(end 270.397478 -275.28774)
				)
			)
		)
	)
	(zone
		(layer "In1.Cu")
		(hatch none 0.5)
		(connect_pads
			(clearance 0)
		)
		(min_thickness 0.25)
		(keepout
			(tracks not_allowed)
			(vias allowed)
			(pads allowed)
			(copperpour not_allowed)
			(footprints allowed)
		)
		(placement
			(enabled no)
			(sheetname "")
		)
		(fill
			(thermal_gap 0.5)
			(thermal_bridge_width 0.5)
			(island_removal_mode 0)
		)
		(polygon
			(pts
				(arc
					(start 132.961126 -389.467344)
					(mid 132.580126 -389.467344)
					(end 132.961126 -389.467344)
				)
			)
		)
	)
	(zone
		(layer "In1.Cu")
		(hatch none 0.5)
		(connect_pads
			(clearance 0)
		)
		(min_thickness 0.25)
		(keepout
			(tracks not_allowed)
			(vias allowed)
			(pads allowed)
			(copperpour not_allowed)
			(footprints allowed)
		)
		(placement
			(enabled no)
			(sheetname "")
		)
		(fill
			(thermal_gap 0.5)
			(thermal_bridge_width 0.5)
			(island_removal_mode 0)
		)
		(polygon
			(pts
				(arc
					(start 296.473372 -234.13212)
					(mid 296.469652 -234.1411)
					(end 296.460672 -234.14482)
				)
				(arc
					(start 294.987472 -234.14482)
					(mid 294.978492 -234.1411)
					(end 294.974772 -234.13212)
				)
				(arc
					(start 294.974772 -233.637582)
					(mid 294.978492 -233.628602)
					(end 294.987472 -233.624882)
				)
				(arc
					(start 296.460672 -233.624882)
					(mid 296.469652 -233.628602)
					(end 296.473372 -233.637582)
				)
			)
		)
	)
	(zone
		(layer "In1.Cu")
		(hatch none 0.5)
		(connect_pads
			(clearance 0)
		)
		(min_thickness 0.25)
		(keepout
			(tracks not_allowed)
			(vias allowed)
			(pads allowed)
			(copperpour not_allowed)
			(footprints allowed)
		)
		(placement
			(enabled no)
			(sheetname "")
		)
		(fill
			(thermal_gap 0.5)
			(thermal_bridge_width 0.5)
			(island_removal_mode 0)
		)
		(polygon
			(pts
				(arc
					(start 187.809378 -215.432386)
					(mid 187.805658 -215.441366)
					(end 187.796678 -215.445086)
				)
				(arc
					(start 186.323478 -215.445086)
					(mid 186.314498 -215.441366)
					(end 186.310778 -215.432386)
				)
				(arc
					(start 186.310778 -214.937848)
					(mid 186.314498 -214.928868)
					(end 186.323478 -214.925148)
				)
				(arc
					(start 187.796678 -214.925148)
					(mid 187.805658 -214.928868)
					(end 187.809378 -214.937848)
				)
			)
		)
	)
	(zone
		(layer "In1.Cu")
		(hatch none 0.5)
		(connect_pads
			(clearance 0)
		)
		(min_thickness 0.25)
		(keepout
			(tracks not_allowed)
			(vias allowed)
			(pads allowed)
			(copperpour not_allowed)
			(footprints allowed)
		)
		(placement
			(enabled no)
			(sheetname "")
		)
		(fill
			(thermal_gap 0.5)
			(thermal_bridge_width 0.5)
			(island_removal_mode 0)
		)
		(polygon
			(pts
				(arc
					(start 199.4535 -261.332472)
					(mid 199.44978 -261.341452)
					(end 199.4408 -261.345172)
				)
				(arc
					(start 197.9676 -261.345172)
					(mid 197.95862 -261.341452)
					(end 197.9549 -261.332472)
				)
				(arc
					(start 197.9549 -260.837934)
					(mid 197.95862 -260.828954)
					(end 197.9676 -260.825234)
				)
				(arc
					(start 199.4408 -260.825234)
					(mid 199.44978 -260.828954)
					(end 199.4535 -260.837934)
				)
			)
		)
	)
	(zone
		(layer "In1.Cu")
		(hatch none 0.5)
		(connect_pads
			(clearance 0)
		)
		(min_thickness 0.25)
		(keepout
			(tracks not_allowed)
			(vias allowed)
			(pads allowed)
			(copperpour not_allowed)
			(footprints allowed)
		)
		(placement
			(enabled no)
			(sheetname "")
		)
		(fill
			(thermal_gap 0.5)
			(thermal_bridge_width 0.5)
			(island_removal_mode 0)
		)
		(polygon
			(pts
				(arc
					(start 117.6909 -391.319258)
					(mid 117.8179 -391.446258)
					(end 117.9449 -391.319258)
				)
				(arc
					(start 117.9449 -391.243058)
					(mid 117.8179 -391.116058)
					(end 117.6909 -391.243058)
				)
			)
		)
	)
	(zone
		(layer "In1.Cu")
		(hatch none 0.5)
		(connect_pads
			(clearance 0)
		)
		(min_thickness 0.25)
		(keepout
			(tracks not_allowed)
			(vias allowed)
			(pads allowed)
			(copperpour not_allowed)
			(footprints allowed)
		)
		(placement
			(enabled no)
			(sheetname "")
		)
		(fill
			(thermal_gap 0.5)
			(thermal_bridge_width 0.5)
			(island_removal_mode 0)
		)
		(polygon
			(pts
				(arc
					(start 300.57344 -247.732296)
					(mid 300.56972 -247.741276)
					(end 300.56074 -247.744996)
				)
				(arc
					(start 299.08754 -247.744996)
					(mid 299.07856 -247.741276)
					(end 299.07484 -247.732296)
				)
				(arc
					(start 299.07484 -247.237758)
					(mid 299.07856 -247.228778)
					(end 299.08754 -247.225058)
				)
				(arc
					(start 300.56074 -247.225058)
					(mid 300.56972 -247.228778)
					(end 300.57344 -247.237758)
				)
			)
		)
	)
	(zone
		(layer "In1.Cu")
		(hatch none 0.5)
		(connect_pads
			(clearance 0)
		)
		(min_thickness 0.25)
		(keepout
			(tracks not_allowed)
			(vias allowed)
			(pads allowed)
			(copperpour not_allowed)
			(footprints allowed)
		)
		(placement
			(enabled no)
			(sheetname "")
		)
		(fill
			(thermal_gap 0.5)
			(thermal_bridge_width 0.5)
			(island_removal_mode 0)
		)
		(polygon
			(pts
				(arc
					(start 308.117494 -263.03224)
					(mid 308.113774 -263.04122)
					(end 308.104794 -263.04494)
				)
				(arc
					(start 306.631594 -263.04494)
					(mid 306.622614 -263.04122)
					(end 306.618894 -263.03224)
				)
				(arc
					(start 306.618894 -262.537702)
					(mid 306.622614 -262.528722)
					(end 306.631594 -262.525002)
				)
				(arc
					(start 308.104794 -262.525002)
					(mid 308.113774 -262.528722)
					(end 308.117494 -262.537702)
				)
			)
		)
	)
	(zone
		(layer "In1.Cu")
		(hatch none 0.5)
		(connect_pads
			(clearance 0)
		)
		(min_thickness 0.25)
		(keepout
			(tracks not_allowed)
			(vias allowed)
			(pads allowed)
			(copperpour not_allowed)
			(footprints allowed)
		)
		(placement
			(enabled no)
			(sheetname "")
		)
		(fill
			(thermal_gap 0.5)
			(thermal_bridge_width 0.5)
			(island_removal_mode 0)
		)
		(polygon
			(pts
				(arc
					(start 270.397478 -239.232186)
					(mid 270.393758 -239.241166)
					(end 270.384778 -239.244886)
				)
				(arc
					(start 268.911578 -239.244886)
					(mid 268.902598 -239.241166)
					(end 268.898878 -239.232186)
				)
				(arc
					(start 268.898878 -238.737648)
					(mid 268.902598 -238.728668)
					(end 268.911578 -238.724948)
				)
				(arc
					(start 270.384778 -238.724948)
					(mid 270.393758 -238.728668)
					(end 270.397478 -238.737648)
				)
			)
		)
	)
	(zone
		(layer "In1.Cu")
		(hatch none 0.5)
		(connect_pads
			(clearance 0)
		)
		(min_thickness 0.25)
		(keepout
			(tracks not_allowed)
			(vias allowed)
			(pads allowed)
			(copperpour not_allowed)
			(footprints allowed)
		)
		(placement
			(enabled no)
			(sheetname "")
		)
		(fill
			(thermal_gap 0.5)
			(thermal_bridge_width 0.5)
			(island_removal_mode 0)
		)
		(polygon
			(pts
				(arc
					(start 48.533304 -235.832396)
					(mid 48.529584 -235.841376)
					(end 48.520604 -235.845096)
				)
				(arc
					(start 47.047404 -235.845096)
					(mid 47.038424 -235.841376)
					(end 47.034704 -235.832396)
				)
				(arc
					(start 47.034704 -235.337858)
					(mid 47.038424 -235.328878)
					(end 47.047404 -235.325158)
				)
				(arc
					(start 48.520604 -235.325158)
					(mid 48.529584 -235.328878)
					(end 48.533304 -235.337858)
				)
			)
		)
	)
	(zone
		(layer "In1.Cu")
		(hatch none 0.5)
		(connect_pads
			(clearance 0)
		)
		(min_thickness 0.25)
		(keepout
			(tracks not_allowed)
			(vias allowed)
			(pads allowed)
			(copperpour not_allowed)
			(footprints allowed)
		)
		(placement
			(enabled no)
			(sheetname "")
		)
		(fill
			(thermal_gap 0.5)
			(thermal_bridge_width 0.5)
			(island_removal_mode 0)
		)
		(polygon
			(pts
				(arc
					(start 162.689032 -385.31038)
					(mid 162.308032 -385.31038)
					(end 162.689032 -385.31038)
				)
			)
		)
	)
	(zone
		(layer "In1.Cu")
		(hatch none 0.5)
		(connect_pads
			(clearance 0)
		)
		(min_thickness 0.25)
		(keepout
			(tracks not_allowed)
			(vias allowed)
			(pads allowed)
			(copperpour not_allowed)
			(footprints allowed)
		)
		(placement
			(enabled no)
			(sheetname "")
		)
		(fill
			(thermal_gap 0.5)
			(thermal_bridge_width 0.5)
			(island_removal_mode 0)
		)
		(polygon
			(pts
				(arc
					(start 180.265324 -284.282388)
					(mid 180.261604 -284.291368)
					(end 180.252624 -284.295088)
				)
				(arc
					(start 178.779424 -284.295088)
					(mid 178.770444 -284.291368)
					(end 178.766724 -284.282388)
				)
				(arc
					(start 178.766724 -283.78785)
					(mid 178.770444 -283.77887)
					(end 178.779424 -283.77515)
				)
				(arc
					(start 180.252624 -283.77515)
					(mid 180.261604 -283.77887)
					(end 180.265324 -283.78785)
				)
			)
		)
	)
	(zone
		(layer "In1.Cu")
		(hatch none 0.5)
		(connect_pads
			(clearance 0)
		)
		(min_thickness 0.25)
		(keepout
			(tracks not_allowed)
			(vias allowed)
			(pads allowed)
			(copperpour not_allowed)
			(footprints allowed)
		)
		(placement
			(enabled no)
			(sheetname "")
		)
		(fill
			(thermal_gap 0.5)
			(thermal_bridge_width 0.5)
			(island_removal_mode 0)
		)
		(polygon
			(pts
				(arc
					(start 447.393568 -212.882226)
					(mid 447.389848 -212.891206)
					(end 447.380868 -212.894926)
				)
				(arc
					(start 445.907668 -212.894926)
					(mid 445.898688 -212.891206)
					(end 445.894968 -212.882226)
				)
				(arc
					(start 445.894968 -212.387688)
					(mid 445.898688 -212.378708)
					(end 445.907668 -212.374988)
				)
				(arc
					(start 447.380868 -212.374988)
					(mid 447.389848 -212.378708)
					(end 447.393568 -212.387688)
				)
			)
		)
	)
	(zone
		(layer "In1.Cu")
		(hatch none 0.5)
		(connect_pads
			(clearance 0)
		)
		(min_thickness 0.25)
		(keepout
			(tracks not_allowed)
			(vias allowed)
			(pads allowed)
			(copperpour not_allowed)
			(footprints allowed)
		)
		(placement
			(enabled no)
			(sheetname "")
		)
		(fill
			(thermal_gap 0.5)
			(thermal_bridge_width 0.5)
			(island_removal_mode 0)
		)
		(polygon
			(pts
				(arc
					(start 270.397478 -287.682178)
					(mid 270.393758 -287.691158)
					(end 270.384778 -287.694878)
				)
				(arc
					(start 268.911578 -287.694878)
					(mid 268.902598 -287.691158)
					(end 268.898878 -287.682178)
				)
				(arc
					(start 268.898878 -287.18764)
					(mid 268.902598 -287.17866)
					(end 268.911578 -287.17494)
				)
				(arc
					(start 270.384778 -287.17494)
					(mid 270.393758 -287.17866)
					(end 270.397478 -287.18764)
				)
			)
		)
	)
	(zone
		(layer "In1.Cu")
		(hatch none 0.5)
		(connect_pads
			(clearance 0)
		)
		(min_thickness 0.25)
		(keepout
			(tracks not_allowed)
			(vias allowed)
			(pads allowed)
			(copperpour not_allowed)
			(footprints allowed)
		)
		(placement
			(enabled no)
			(sheetname "")
		)
		(fill
			(thermal_gap 0.5)
			(thermal_bridge_width 0.5)
			(island_removal_mode 0)
		)
		(polygon
			(pts
				(arc
					(start 424.761406 -270.682212)
					(mid 424.757686 -270.691192)
					(end 424.748706 -270.694912)
				)
				(arc
					(start 423.275506 -270.694912)
					(mid 423.266526 -270.691192)
					(end 423.262806 -270.682212)
				)
				(arc
					(start 423.262806 -270.187674)
					(mid 423.266526 -270.178694)
					(end 423.275506 -270.174974)
				)
				(arc
					(start 424.748706 -270.174974)
					(mid 424.757686 -270.178694)
					(end 424.761406 -270.187674)
				)
			)
		)
	)
	(zone
		(layer "In1.Cu")
		(hatch none 0.5)
		(connect_pads
			(clearance 0)
		)
		(min_thickness 0.25)
		(keepout
			(tracks not_allowed)
			(vias allowed)
			(pads allowed)
			(copperpour not_allowed)
			(footprints allowed)
		)
		(placement
			(enabled no)
			(sheetname "")
		)
		(fill
			(thermal_gap 0.5)
			(thermal_bridge_width 0.5)
			(island_removal_mode 0)
		)
		(polygon
			(pts
				(arc
					(start 202.897232 -304.682398)
					(mid 202.893512 -304.691378)
					(end 202.884532 -304.695098)
				)
				(arc
					(start 201.411332 -304.695098)
					(mid 201.402352 -304.691378)
					(end 201.398632 -304.682398)
				)
				(arc
					(start 201.398632 -304.18786)
					(mid 201.402352 -304.17888)
					(end 201.411332 -304.17516)
				)
				(arc
					(start 202.884532 -304.17516)
					(mid 202.893512 -304.17888)
					(end 202.897232 -304.18786)
				)
			)
		)
	)
	(zone
		(layer "In1.Cu")
		(hatch none 0.5)
		(connect_pads
			(clearance 0)
		)
		(min_thickness 0.25)
		(keepout
			(tracks not_allowed)
			(vias allowed)
			(pads allowed)
			(copperpour not_allowed)
			(footprints allowed)
		)
		(placement
			(enabled no)
			(sheetname "")
		)
		(fill
			(thermal_gap 0.5)
			(thermal_bridge_width 0.5)
			(island_removal_mode 0)
		)
		(polygon
			(pts
				(arc
					(start 180.265324 -224.78238)
					(mid 180.261604 -224.79136)
					(end 180.252624 -224.79508)
				)
				(arc
					(start 178.779424 -224.79508)
					(mid 178.770444 -224.79136)
					(end 178.766724 -224.78238)
				)
				(arc
					(start 178.766724 -224.287842)
					(mid 178.770444 -224.278862)
					(end 178.779424 -224.275142)
				)
				(arc
					(start 180.252624 -224.275142)
					(mid 180.261604 -224.278862)
					(end 180.265324 -224.287842)
				)
			)
		)
	)
	(zone
		(layer "In1.Cu")
		(hatch none 0.5)
		(connect_pads
			(clearance 0)
		)
		(min_thickness 0.25)
		(keepout
			(tracks not_allowed)
			(vias allowed)
			(pads allowed)
			(copperpour not_allowed)
			(footprints allowed)
		)
		(placement
			(enabled no)
			(sheetname "")
		)
		(fill
			(thermal_gap 0.5)
			(thermal_bridge_width 0.5)
			(island_removal_mode 0)
		)
		(polygon
			(pts
				(arc
					(start 300.189392 -0.548386)
					(mid 300.167074 -0.602268)
					(end 300.113192 -0.624586)
				)
				(arc
					(start 299.501052 -0.624586)
					(mid 299.44717 -0.602268)
					(end 299.424852 -0.548386)
				)
				(arc
					(start 299.424852 0.548894)
					(mid 299.44717 0.602776)
					(end 299.501052 0.625094)
				)
				(arc
					(start 300.113192 0.625094)
					(mid 300.167074 0.602776)
					(end 300.189392 0.548894)
				)
			)
		)
	)
	(zone
		(layer "In1.Cu")
		(hatch none 0.5)
		(connect_pads
			(clearance 0)
		)
		(min_thickness 0.25)
		(keepout
			(tracks not_allowed)
			(vias allowed)
			(pads allowed)
			(copperpour not_allowed)
			(footprints allowed)
		)
		(placement
			(enabled no)
			(sheetname "")
		)
		(fill
			(thermal_gap 0.5)
			(thermal_bridge_width 0.5)
			(island_removal_mode 0)
		)
		(polygon
			(pts
				(arc
					(start 165.177216 -276.632416)
					(mid 165.173496 -276.641396)
					(end 165.164516 -276.645116)
				)
				(arc
					(start 163.691316 -276.645116)
					(mid 163.682336 -276.641396)
					(end 163.678616 -276.632416)
				)
				(arc
					(start 163.678616 -276.137878)
					(mid 163.682336 -276.128898)
					(end 163.691316 -276.125178)
				)
				(arc
					(start 165.164516 -276.125178)
					(mid 165.173496 -276.128898)
					(end 165.177216 -276.137878)
				)
			)
		)
	)
	(zone
		(layer "In1.Cu")
		(hatch none 0.5)
		(connect_pads
			(clearance 0)
		)
		(min_thickness 0.25)
		(keepout
			(tracks not_allowed)
			(vias allowed)
			(pads allowed)
			(copperpour not_allowed)
			(footprints allowed)
		)
		(placement
			(enabled no)
			(sheetname "")
		)
		(fill
			(thermal_gap 0.5)
			(thermal_bridge_width 0.5)
			(island_removal_mode 0)
		)
		(polygon
			(pts
				(arc
					(start 45.089318 -269.832582)
					(mid 45.085598 -269.841562)
					(end 45.076618 -269.845282)
				)
				(arc
					(start 43.603418 -269.845282)
					(mid 43.594438 -269.841562)
					(end 43.590718 -269.832582)
				)
				(arc
					(start 43.590718 -269.338044)
					(mid 43.594438 -269.329064)
					(end 43.603418 -269.325344)
				)
				(arc
					(start 45.076618 -269.325344)
					(mid 45.085598 -269.329064)
					(end 45.089318 -269.338044)
				)
			)
		)
	)
	(zone
		(layer "In1.Cu")
		(hatch none 0.5)
		(connect_pads
			(clearance 0)
		)
		(min_thickness 0.25)
		(keepout
			(tracks not_allowed)
			(vias allowed)
			(pads allowed)
			(copperpour not_allowed)
			(footprints allowed)
		)
		(placement
			(enabled no)
			(sheetname "")
		)
		(fill
			(thermal_gap 0.5)
			(thermal_bridge_width 0.5)
			(island_removal_mode 0)
		)
		(polygon
			(pts
				(arc
					(start 304.017426 -296.182288)
					(mid 304.013706 -296.191268)
					(end 304.004726 -296.194988)
				)
				(arc
					(start 302.531526 -296.194988)
					(mid 302.522546 -296.191268)
					(end 302.518826 -296.182288)
				)
				(arc
					(start 302.518826 -295.68775)
					(mid 302.522546 -295.67877)
					(end 302.531526 -295.67505)
				)
				(arc
					(start 304.004726 -295.67505)
					(mid 304.013706 -295.67877)
					(end 304.017426 -295.68775)
				)
			)
		)
	)
	(zone
		(layer "In1.Cu")
		(hatch none 0.5)
		(connect_pads
			(clearance 0)
		)
		(min_thickness 0.25)
		(keepout
			(tracks not_allowed)
			(vias allowed)
			(pads allowed)
			(copperpour not_allowed)
			(footprints allowed)
		)
		(placement
			(enabled no)
			(sheetname "")
		)
		(fill
			(thermal_gap 0.5)
			(thermal_bridge_width 0.5)
			(island_removal_mode 0)
		)
		(polygon
			(pts
				(arc
					(start 277.941532 -199.282304)
					(mid 277.937812 -199.291284)
					(end 277.928832 -199.295004)
				)
				(arc
					(start 276.455632 -199.295004)
					(mid 276.446652 -199.291284)
					(end 276.442932 -199.282304)
				)
				(arc
					(start 276.442932 -198.787766)
					(mid 276.446652 -198.778786)
					(end 276.455632 -198.775066)
				)
				(arc
					(start 277.928832 -198.775066)
					(mid 277.937812 -198.778786)
					(end 277.941532 -198.787766)
				)
			)
		)
	)
	(zone
		(layer "In1.Cu")
		(hatch none 0.5)
		(connect_pads
			(clearance 0)
		)
		(min_thickness 0.25)
		(keepout
			(tracks not_allowed)
			(vias allowed)
			(pads allowed)
			(copperpour not_allowed)
			(footprints allowed)
		)
		(placement
			(enabled no)
			(sheetname "")
		)
		(fill
			(thermal_gap 0.5)
			(thermal_bridge_width 0.5)
			(island_removal_mode 0)
		)
		(polygon
			(pts
				(arc
					(start 273.841464 -251.982224)
					(mid 273.837744 -251.991204)
					(end 273.828764 -251.994924)
				)
				(arc
					(start 272.355564 -251.994924)
					(mid 272.346584 -251.991204)
					(end 272.342864 -251.982224)
				)
				(arc
					(start 272.342864 -251.487686)
					(mid 272.346584 -251.478706)
					(end 272.355564 -251.474986)
				)
				(arc
					(start 273.828764 -251.474986)
					(mid 273.837744 -251.478706)
					(end 273.841464 -251.487686)
				)
			)
		)
	)
	(zone
		(layer "In1.Cu")
		(hatch none 0.5)
		(connect_pads
			(clearance 0)
		)
		(min_thickness 0.25)
		(keepout
			(tracks not_allowed)
			(vias allowed)
			(pads allowed)
			(copperpour not_allowed)
			(footprints allowed)
		)
		(placement
			(enabled no)
			(sheetname "")
		)
		(fill
			(thermal_gap 0.5)
			(thermal_bridge_width 0.5)
			(island_removal_mode 0)
		)
		(polygon
			(pts
				(arc
					(start 117.360954 -389.467344)
					(mid 116.979954 -389.467344)
					(end 117.360954 -389.467344)
				)
			)
		)
	)
	(zone
		(layer "In1.Cu")
		(hatch none 0.5)
		(connect_pads
			(clearance 0)
		)
		(min_thickness 0.25)
		(keepout
			(tracks not_allowed)
			(vias allowed)
			(pads allowed)
			(copperpour not_allowed)
			(footprints allowed)
		)
		(placement
			(enabled no)
			(sheetname "")
		)
		(fill
			(thermal_gap 0.5)
			(thermal_bridge_width 0.5)
			(island_removal_mode 0)
		)
		(polygon
			(pts
				(arc
					(start 413.117284 -316.582298)
					(mid 413.113564 -316.591278)
					(end 413.104584 -316.594998)
				)
				(arc
					(start 411.631384 -316.594998)
					(mid 411.622404 -316.591278)
					(end 411.618684 -316.582298)
				)
				(arc
					(start 411.618684 -316.08776)
					(mid 411.622404 -316.07878)
					(end 411.631384 -316.07506)
				)
				(arc
					(start 413.104584 -316.07506)
					(mid 413.113564 -316.07878)
					(end 413.117284 -316.08776)
				)
			)
		)
	)
	(zone
		(layer "In1.Cu")
		(hatch none 0.5)
		(connect_pads
			(clearance 0)
		)
		(min_thickness 0.25)
		(keepout
			(tracks not_allowed)
			(vias allowed)
			(pads allowed)
			(copperpour not_allowed)
			(footprints allowed)
		)
		(placement
			(enabled no)
			(sheetname "")
		)
		(fill
			(thermal_gap 0.5)
			(thermal_bridge_width 0.5)
			(island_removal_mode 0)
		)
		(polygon
			(pts
				(arc
					(start 417.217352 -285.132272)
					(mid 417.213632 -285.141252)
					(end 417.204652 -285.144972)
				)
				(arc
					(start 415.731452 -285.144972)
					(mid 415.722472 -285.141252)
					(end 415.718752 -285.132272)
				)
				(arc
					(start 415.718752 -284.637734)
					(mid 415.722472 -284.628754)
					(end 415.731452 -284.625034)
				)
				(arc
					(start 417.204652 -284.625034)
					(mid 417.213632 -284.628754)
					(end 417.217352 -284.637734)
				)
			)
		)
	)
	(zone
		(layer "In1.Cu")
		(hatch none 0.5)
		(connect_pads
			(clearance 0)
		)
		(min_thickness 0.25)
		(keepout
			(tracks not_allowed)
			(vias allowed)
			(pads allowed)
			(copperpour not_allowed)
			(footprints allowed)
		)
		(placement
			(enabled no)
			(sheetname "")
		)
		(fill
			(thermal_gap 0.5)
			(thermal_bridge_width 0.5)
			(island_removal_mode 0)
		)
		(polygon
			(pts
				(arc
					(start 191.909446 -220.532452)
					(mid 191.905726 -220.541432)
					(end 191.896746 -220.545152)
				)
				(arc
					(start 190.423546 -220.545152)
					(mid 190.414566 -220.541432)
					(end 190.410846 -220.532452)
				)
				(arc
					(start 190.410846 -220.037914)
					(mid 190.414566 -220.028934)
					(end 190.423546 -220.025214)
				)
				(arc
					(start 191.896746 -220.025214)
					(mid 191.905726 -220.028934)
					(end 191.909446 -220.037914)
				)
			)
		)
	)
	(zone
		(layer "In1.Cu")
		(hatch none 0.5)
		(connect_pads
			(clearance 0)
		)
		(min_thickness 0.25)
		(keepout
			(tracks not_allowed)
			(vias allowed)
			(pads allowed)
			(copperpour not_allowed)
			(footprints allowed)
		)
		(placement
			(enabled no)
			(sheetname "")
		)
		(fill
			(thermal_gap 0.5)
			(thermal_bridge_width 0.5)
			(island_removal_mode 0)
		)
		(polygon
			(pts
				(arc
					(start 435.749446 -224.782126)
					(mid 435.745726 -224.791106)
					(end 435.736746 -224.794826)
				)
				(arc
					(start 434.263546 -224.794826)
					(mid 434.254566 -224.791106)
					(end 434.250846 -224.782126)
				)
				(arc
					(start 434.250846 -224.287588)
					(mid 434.254566 -224.278608)
					(end 434.263546 -224.274888)
				)
				(arc
					(start 435.736746 -224.274888)
					(mid 435.745726 -224.278608)
					(end 435.749446 -224.287588)
				)
			)
		)
	)
	(zone
		(layer "In1.Cu")
		(hatch none 0.5)
		(connect_pads
			(clearance 0)
		)
		(min_thickness 0.25)
		(keepout
			(tracks not_allowed)
			(vias allowed)
			(pads allowed)
			(copperpour not_allowed)
			(footprints allowed)
		)
		(placement
			(enabled no)
			(sheetname "")
		)
		(fill
			(thermal_gap 0.5)
			(thermal_bridge_width 0.5)
			(island_removal_mode 0)
		)
		(polygon
			(pts
				(arc
					(start 428.205392 -290.232338)
					(mid 428.201672 -290.241318)
					(end 428.192692 -290.245038)
				)
				(arc
					(start 426.719492 -290.245038)
					(mid 426.710512 -290.241318)
					(end 426.706792 -290.232338)
				)
				(arc
					(start 426.706792 -289.7378)
					(mid 426.710512 -289.72882)
					(end 426.719492 -289.7251)
				)
				(arc
					(start 428.192692 -289.7251)
					(mid 428.201672 -289.72882)
					(end 428.205392 -289.7378)
				)
			)
		)
	)
	(zone
		(layer "In1.Cu")
		(hatch none 0.5)
		(connect_pads
			(clearance 0)
		)
		(min_thickness 0.25)
		(keepout
			(tracks not_allowed)
			(vias allowed)
			(pads allowed)
			(copperpour not_allowed)
			(footprints allowed)
		)
		(placement
			(enabled no)
			(sheetname "")
		)
		(fill
			(thermal_gap 0.5)
			(thermal_bridge_width 0.5)
			(island_removal_mode 0)
		)
		(polygon
			(pts
				(arc
					(start 63.170308 -390.761474)
					(mid 62.865508 -390.761474)
					(end 63.170308 -390.761474)
				)
			)
		)
	)
	(zone
		(layer "In1.Cu")
		(hatch none 0.5)
		(connect_pads
			(clearance 0)
		)
		(min_thickness 0.25)
		(keepout
			(tracks not_allowed)
			(vias allowed)
			(pads allowed)
			(copperpour not_allowed)
			(footprints allowed)
		)
		(placement
			(enabled no)
			(sheetname "")
		)
		(fill
			(thermal_gap 0.5)
			(thermal_bridge_width 0.5)
			(island_removal_mode 0)
		)
		(polygon
			(pts
				(arc
					(start 206.5782 -269.58544)
					(mid 205.9178 -269.58544)
					(end 206.5782 -269.58544)
				)
			)
		)
	)
	(zone
		(layer "In1.Cu")
		(hatch none 0.5)
		(connect_pads
			(clearance 0)
		)
		(min_thickness 0.25)
		(keepout
			(tracks not_allowed)
			(vias allowed)
			(pads allowed)
			(copperpour not_allowed)
			(footprints allowed)
		)
		(placement
			(enabled no)
			(sheetname "")
		)
		(fill
			(thermal_gap 0.5)
			(thermal_bridge_width 0.5)
			(island_removal_mode 0)
		)
		(polygon
			(pts
				(arc
					(start 40.98925 -273.232372)
					(mid 40.98553 -273.241352)
					(end 40.97655 -273.245072)
				)
				(arc
					(start 39.50335 -273.245072)
					(mid 39.49437 -273.241352)
					(end 39.49065 -273.232372)
				)
				(arc
					(start 39.49065 -272.737834)
					(mid 39.49437 -272.728854)
					(end 39.50335 -272.725134)
				)
				(arc
					(start 40.97655 -272.725134)
					(mid 40.98553 -272.728854)
					(end 40.98925 -272.737834)
				)
			)
		)
	)
	(zone
		(layer "In1.Cu")
		(hatch none 0.5)
		(connect_pads
			(clearance 0)
		)
		(min_thickness 0.25)
		(keepout
			(tracks not_allowed)
			(vias allowed)
			(pads allowed)
			(copperpour not_allowed)
			(footprints allowed)
		)
		(placement
			(enabled no)
			(sheetname "")
		)
		(fill
			(thermal_gap 0.5)
			(thermal_bridge_width 0.5)
			(island_removal_mode 0)
		)
		(polygon
			(pts
				(arc
					(start 180.265324 -316.582552)
					(mid 180.261604 -316.591532)
					(end 180.252624 -316.595252)
				)
				(arc
					(start 178.779424 -316.595252)
					(mid 178.770444 -316.591532)
					(end 178.766724 -316.582552)
				)
				(arc
					(start 178.766724 -316.088014)
					(mid 178.770444 -316.079034)
					(end 178.779424 -316.075314)
				)
				(arc
					(start 180.252624 -316.075314)
					(mid 180.261604 -316.079034)
					(end 180.265324 -316.088014)
				)
			)
		)
	)
	(zone
		(layer "In1.Cu")
		(hatch none 0.5)
		(connect_pads
			(clearance 0)
		)
		(min_thickness 0.25)
		(keepout
			(tracks not_allowed)
			(vias allowed)
			(pads allowed)
			(copperpour not_allowed)
			(footprints allowed)
		)
		(placement
			(enabled no)
			(sheetname "")
		)
		(fill
			(thermal_gap 0.5)
			(thermal_bridge_width 0.5)
			(island_removal_mode 0)
		)
		(polygon
			(pts
				(arc
					(start 18.357342 -232.432352)
					(mid 18.353622 -232.441332)
					(end 18.344642 -232.445052)
				)
				(arc
					(start 16.871442 -232.445052)
					(mid 16.862462 -232.441332)
					(end 16.858742 -232.432352)
				)
				(arc
					(start 16.858742 -231.937814)
					(mid 16.862462 -231.928834)
					(end 16.871442 -231.925114)
				)
				(arc
					(start 18.344642 -231.925114)
					(mid 18.353622 -231.928834)
					(end 18.357342 -231.937814)
				)
			)
		)
	)
	(zone
		(layer "In1.Cu")
		(hatch none 0.5)
		(connect_pads
			(clearance 0)
		)
		(min_thickness 0.25)
		(keepout
			(tracks not_allowed)
			(vias allowed)
			(pads allowed)
			(copperpour not_allowed)
			(footprints allowed)
		)
		(placement
			(enabled no)
			(sheetname "")
		)
		(fill
			(thermal_gap 0.5)
			(thermal_bridge_width 0.5)
			(island_removal_mode 0)
		)
		(polygon
			(pts
				(arc
					(start 158.288736 -386.003292)
					(mid 157.907736 -386.003292)
					(end 158.288736 -386.003292)
				)
			)
		)
	)
	(zone
		(layer "In1.Cu")
		(hatch none 0.5)
		(connect_pads
			(clearance 0)
		)
		(min_thickness 0.25)
		(keepout
			(tracks not_allowed)
			(vias allowed)
			(pads allowed)
			(copperpour not_allowed)
			(footprints allowed)
		)
		(placement
			(enabled no)
			(sheetname "")
		)
		(fill
			(thermal_gap 0.5)
			(thermal_bridge_width 0.5)
			(island_removal_mode 0)
		)
		(polygon
			(pts
				(arc
					(start 435.749446 -229.882192)
					(mid 435.745726 -229.891172)
					(end 435.736746 -229.894892)
				)
				(arc
					(start 434.263546 -229.894892)
					(mid 434.254566 -229.891172)
					(end 434.250846 -229.882192)
				)
				(arc
					(start 434.250846 -229.387654)
					(mid 434.254566 -229.378674)
					(end 434.263546 -229.374954)
				)
				(arc
					(start 435.736746 -229.374954)
					(mid 435.745726 -229.378674)
					(end 435.749446 -229.387654)
				)
			)
		)
	)
	(zone
		(layer "In1.Cu")
		(hatch none 0.5)
		(connect_pads
			(clearance 0)
		)
		(min_thickness 0.25)
		(keepout
			(tracks not_allowed)
			(vias allowed)
			(pads allowed)
			(copperpour not_allowed)
			(footprints allowed)
		)
		(placement
			(enabled no)
			(sheetname "")
		)
		(fill
			(thermal_gap 0.5)
			(thermal_bridge_width 0.5)
			(island_removal_mode 0)
		)
		(polygon
			(pts
				(arc
					(start 199.4535 -278.332438)
					(mid 199.44978 -278.341418)
					(end 199.4408 -278.345138)
				)
				(arc
					(start 197.9676 -278.345138)
					(mid 197.95862 -278.341418)
					(end 197.9549 -278.332438)
				)
				(arc
					(start 197.9549 -277.8379)
					(mid 197.95862 -277.82892)
					(end 197.9676 -277.8252)
				)
				(arc
					(start 199.4408 -277.8252)
					(mid 199.44978 -277.82892)
					(end 199.4535 -277.8379)
				)
			)
		)
	)
	(zone
		(layer "In1.Cu")
		(hatch none 0.5)
		(connect_pads
			(clearance 0)
		)
		(min_thickness 0.25)
		(keepout
			(tracks not_allowed)
			(vias allowed)
			(pads allowed)
			(copperpour not_allowed)
			(footprints allowed)
		)
		(placement
			(enabled no)
			(sheetname "")
		)
		(fill
			(thermal_gap 0.5)
			(thermal_bridge_width 0.5)
			(island_removal_mode 0)
		)
		(polygon
			(pts
				(arc
					(start 206.9973 -280.03246)
					(mid 206.99358 -280.04144)
					(end 206.9846 -280.04516)
				)
				(arc
					(start 205.5114 -280.04516)
					(mid 205.50242 -280.04144)
					(end 205.4987 -280.03246)
				)
				(arc
					(start 205.4987 -279.537922)
					(mid 205.50242 -279.528942)
					(end 205.5114 -279.525222)
				)
				(arc
					(start 206.9846 -279.525222)
					(mid 206.99358 -279.528942)
					(end 206.9973 -279.537922)
				)
			)
		)
	)
	(zone
		(layer "In1.Cu")
		(hatch none 0.5)
		(connect_pads
			(clearance 0)
		)
		(min_thickness 0.25)
		(keepout
			(tracks not_allowed)
			(vias allowed)
			(pads allowed)
			(copperpour not_allowed)
			(footprints allowed)
		)
		(placement
			(enabled no)
			(sheetname "")
		)
		(fill
			(thermal_gap 0.5)
			(thermal_bridge_width 0.5)
			(island_removal_mode 0)
		)
		(polygon
			(pts
				(arc
					(start 202.897232 -202.682348)
					(mid 202.893512 -202.691328)
					(end 202.884532 -202.695048)
				)
				(arc
					(start 201.411332 -202.695048)
					(mid 201.402352 -202.691328)
					(end 201.398632 -202.682348)
				)
				(arc
					(start 201.398632 -202.18781)
					(mid 201.402352 -202.17883)
					(end 201.411332 -202.17511)
				)
				(arc
					(start 202.884532 -202.17511)
					(mid 202.893512 -202.17883)
					(end 202.897232 -202.18781)
				)
			)
		)
	)
	(zone
		(layer "In1.Cu")
		(hatch none 0.5)
		(connect_pads
			(clearance 0)
		)
		(min_thickness 0.25)
		(keepout
			(tracks not_allowed)
			(vias allowed)
			(pads allowed)
			(copperpour not_allowed)
			(footprints allowed)
		)
		(placement
			(enabled no)
			(sheetname "")
		)
		(fill
			(thermal_gap 0.5)
			(thermal_bridge_width 0.5)
			(island_removal_mode 0)
		)
		(polygon
			(pts
				(arc
					(start 40.98925 -237.532418)
					(mid 40.98553 -237.541398)
					(end 40.97655 -237.545118)
				)
				(arc
					(start 39.50335 -237.545118)
					(mid 39.49437 -237.541398)
					(end 39.49065 -237.532418)
				)
				(arc
					(start 39.49065 -237.03788)
					(mid 39.49437 -237.0289)
					(end 39.50335 -237.02518)
				)
				(arc
					(start 40.97655 -237.02518)
					(mid 40.98553 -237.0289)
					(end 40.98925 -237.03788)
				)
			)
		)
	)
	(zone
		(layer "In1.Cu")
		(hatch none 0.5)
		(connect_pads
			(clearance 0)
		)
		(min_thickness 0.25)
		(keepout
			(tracks not_allowed)
			(vias allowed)
			(pads allowed)
			(copperpour not_allowed)
			(footprints allowed)
		)
		(placement
			(enabled no)
			(sheetname "")
		)
		(fill
			(thermal_gap 0.5)
			(thermal_bridge_width 0.5)
			(island_removal_mode 0)
		)
		(polygon
			(pts
				(arc
					(start 413.117284 -295.33215)
					(mid 413.113564 -295.34113)
					(end 413.104584 -295.34485)
				)
				(arc
					(start 411.631384 -295.34485)
					(mid 411.622404 -295.34113)
					(end 411.618684 -295.33215)
				)
				(arc
					(start 411.618684 -294.837612)
					(mid 411.622404 -294.828632)
					(end 411.631384 -294.824912)
				)
				(arc
					(start 413.104584 -294.824912)
					(mid 413.113564 -294.828632)
					(end 413.117284 -294.837612)
				)
			)
		)
	)
	(zone
		(layer "In1.Cu")
		(hatch none 0.5)
		(connect_pads
			(clearance 0)
		)
		(min_thickness 0.25)
		(keepout
			(tracks not_allowed)
			(vias allowed)
			(pads allowed)
			(copperpour not_allowed)
			(footprints allowed)
		)
		(placement
			(enabled no)
			(sheetname "")
		)
		(fill
			(thermal_gap 0.5)
			(thermal_bridge_width 0.5)
			(island_removal_mode 0)
		)
		(polygon
			(pts
				(arc
					(start 273.841464 -232.432098)
					(mid 273.837744 -232.441078)
					(end 273.828764 -232.444798)
				)
				(arc
					(start 272.355564 -232.444798)
					(mid 272.346584 -232.441078)
					(end 272.342864 -232.432098)
				)
				(arc
					(start 272.342864 -231.93756)
					(mid 272.346584 -231.92858)
					(end 272.355564 -231.92486)
				)
				(arc
					(start 273.828764 -231.92486)
					(mid 273.837744 -231.92858)
					(end 273.841464 -231.93756)
				)
			)
		)
	)
	(zone
		(layer "In1.Cu")
		(hatch none 0.5)
		(connect_pads
			(clearance 0)
		)
		(min_thickness 0.25)
		(keepout
			(tracks not_allowed)
			(vias allowed)
			(pads allowed)
			(copperpour not_allowed)
			(footprints allowed)
		)
		(placement
			(enabled no)
			(sheetname "")
		)
		(fill
			(thermal_gap 0.5)
			(thermal_bridge_width 0.5)
			(island_removal_mode 0)
		)
		(polygon
			(pts
				(arc
					(start 376.961146 -394.385292)
					(mid 376.580146 -394.385292)
					(end 376.961146 -394.385292)
				)
			)
		)
	)
	(zone
		(layer "In1.Cu")
		(hatch none 0.5)
		(connect_pads
			(clearance 0)
		)
		(min_thickness 0.25)
		(keepout
			(tracks not_allowed)
			(vias allowed)
			(pads allowed)
			(copperpour not_allowed)
			(footprints allowed)
		)
		(placement
			(enabled no)
			(sheetname "")
		)
		(fill
			(thermal_gap 0.5)
			(thermal_bridge_width 0.5)
			(island_removal_mode 0)
		)
		(polygon
			(pts
				(arc
					(start 187.809378 -299.582586)
					(mid 187.805658 -299.591566)
					(end 187.796678 -299.595286)
				)
				(arc
					(start 186.323478 -299.595286)
					(mid 186.314498 -299.591566)
					(end 186.310778 -299.582586)
				)
				(arc
					(start 186.310778 -299.088048)
					(mid 186.314498 -299.079068)
					(end 186.323478 -299.075348)
				)
				(arc
					(start 187.796678 -299.075348)
					(mid 187.805658 -299.079068)
					(end 187.809378 -299.088048)
				)
			)
		)
	)
	(zone
		(layer "In1.Cu")
		(hatch none 0.5)
		(connect_pads
			(clearance 0)
		)
		(min_thickness 0.25)
		(keepout
			(tracks not_allowed)
			(vias allowed)
			(pads allowed)
			(copperpour not_allowed)
			(footprints allowed)
		)
		(placement
			(enabled no)
			(sheetname "")
		)
		(fill
			(thermal_gap 0.5)
			(thermal_bridge_width 0.5)
			(island_removal_mode 0)
		)
		(polygon
			(pts
				(arc
					(start 94.49816 -383.92227)
					(mid 94.19336 -383.92227)
					(end 94.49816 -383.92227)
				)
			)
		)
	)
	(zone
		(layer "In1.Cu")
		(hatch none 0.5)
		(connect_pads
			(clearance 0)
		)
		(min_thickness 0.25)
		(keepout
			(tracks not_allowed)
			(vias allowed)
			(pads allowed)
			(copperpour not_allowed)
			(footprints allowed)
		)
		(placement
			(enabled no)
			(sheetname "")
		)
		(fill
			(thermal_gap 0.5)
			(thermal_bridge_width 0.5)
			(island_removal_mode 0)
		)
		(polygon
			(pts
				(arc
					(start 308.370224 -392.30427)
					(mid 308.065424 -392.30427)
					(end 308.370224 -392.30427)
				)
			)
		)
	)
	(zone
		(layer "In1.Cu")
		(hatch none 0.5)
		(connect_pads
			(clearance 0)
		)
		(min_thickness 0.25)
		(keepout
			(tracks not_allowed)
			(vias allowed)
			(pads allowed)
			(copperpour not_allowed)
			(footprints allowed)
		)
		(placement
			(enabled no)
			(sheetname "")
		)
		(fill
			(thermal_gap 0.5)
			(thermal_bridge_width 0.5)
			(island_removal_mode 0)
		)
		(polygon
			(pts
				(arc
					(start 311.060846 -394.385292)
					(mid 310.679846 -394.385292)
					(end 311.060846 -394.385292)
				)
			)
		)
	)
	(zone
		(layer "In1.Cu")
		(hatch none 0.5)
		(connect_pads
			(clearance 0)
		)
		(min_thickness 0.25)
		(keepout
			(tracks not_allowed)
			(vias allowed)
			(pads allowed)
			(copperpour not_allowed)
			(footprints allowed)
		)
		(placement
			(enabled no)
			(sheetname "")
		)
		(fill
			(thermal_gap 0.5)
			(thermal_bridge_width 0.5)
			(island_removal_mode 0)
		)
		(polygon
			(pts
				(arc
					(start 30.001464 -280.03246)
					(mid 29.997744 -280.04144)
					(end 29.988764 -280.04516)
				)
				(arc
					(start 28.515564 -280.04516)
					(mid 28.506584 -280.04144)
					(end 28.502864 -280.03246)
				)
				(arc
					(start 28.502864 -279.537922)
					(mid 28.506584 -279.528942)
					(end 28.515564 -279.525222)
				)
				(arc
					(start 29.988764 -279.525222)
					(mid 29.997744 -279.528942)
					(end 30.001464 -279.537922)
				)
			)
		)
	)
	(zone
		(layer "In1.Cu")
		(hatch none 0.5)
		(connect_pads
			(clearance 0)
		)
		(min_thickness 0.25)
		(keepout
			(tracks not_allowed)
			(vias allowed)
			(pads allowed)
			(copperpour not_allowed)
			(footprints allowed)
		)
		(placement
			(enabled no)
			(sheetname "")
		)
		(fill
			(thermal_gap 0.5)
			(thermal_bridge_width 0.5)
			(island_removal_mode 0)
		)
		(polygon
			(pts
				(arc
					(start 417.217352 -244.332252)
					(mid 417.213632 -244.341232)
					(end 417.204652 -244.344952)
				)
				(arc
					(start 415.731452 -244.344952)
					(mid 415.722472 -244.341232)
					(end 415.718752 -244.332252)
				)
				(arc
					(start 415.718752 -243.837714)
					(mid 415.722472 -243.828734)
					(end 415.731452 -243.825014)
				)
				(arc
					(start 417.204652 -243.825014)
					(mid 417.213632 -243.828734)
					(end 417.217352 -243.837714)
				)
			)
		)
	)
	(zone
		(layer "In1.Cu")
		(hatch none 0.5)
		(connect_pads
			(clearance 0)
		)
		(min_thickness 0.25)
		(keepout
			(tracks not_allowed)
			(vias allowed)
			(pads allowed)
			(copperpour not_allowed)
			(footprints allowed)
		)
		(placement
			(enabled no)
			(sheetname "")
		)
		(fill
			(thermal_gap 0.5)
			(thermal_bridge_width 0.5)
			(island_removal_mode 0)
		)
		(polygon
			(pts
				(arc
					(start 424.761406 -211.182204)
					(mid 424.757686 -211.191184)
					(end 424.748706 -211.194904)
				)
				(arc
					(start 423.275506 -211.194904)
					(mid 423.266526 -211.191184)
					(end 423.262806 -211.182204)
				)
				(arc
					(start 423.262806 -210.687666)
					(mid 423.266526 -210.678686)
					(end 423.275506 -210.674966)
				)
				(arc
					(start 424.748706 -210.674966)
					(mid 424.757686 -210.678686)
					(end 424.761406 -210.687666)
				)
			)
		)
	)
	(zone
		(layer "In1.Cu")
		(hatch none 0.5)
		(connect_pads
			(clearance 0)
		)
		(min_thickness 0.25)
		(keepout
			(tracks not_allowed)
			(vias allowed)
			(pads allowed)
			(copperpour not_allowed)
			(footprints allowed)
		)
		(placement
			(enabled no)
			(sheetname "")
		)
		(fill
			(thermal_gap 0.5)
			(thermal_bridge_width 0.5)
			(island_removal_mode 0)
		)
		(polygon
			(pts
				(arc
					(start 413.117284 -201.83221)
					(mid 413.113564 -201.84119)
					(end 413.104584 -201.84491)
				)
				(arc
					(start 411.631384 -201.84491)
					(mid 411.622404 -201.84119)
					(end 411.618684 -201.83221)
				)
				(arc
					(start 411.618684 -201.337672)
					(mid 411.622404 -201.328692)
					(end 411.631384 -201.324972)
				)
				(arc
					(start 413.104584 -201.324972)
					(mid 413.113564 -201.328692)
					(end 413.117284 -201.337672)
				)
			)
		)
	)
	(zone
		(layer "In1.Cu")
		(hatch none 0.5)
		(connect_pads
			(clearance 0)
		)
		(min_thickness 0.25)
		(keepout
			(tracks not_allowed)
			(vias allowed)
			(pads allowed)
			(copperpour not_allowed)
			(footprints allowed)
		)
		(placement
			(enabled no)
			(sheetname "")
		)
		(fill
			(thermal_gap 0.5)
			(thermal_bridge_width 0.5)
			(island_removal_mode 0)
		)
		(polygon
			(pts
				(arc
					(start 343.298018 -399.143474)
					(mid 342.993218 -399.143474)
					(end 343.298018 -399.143474)
				)
			)
		)
	)
	(zone
		(layer "In1.Cu")
		(hatch none 0.5)
		(connect_pads
			(clearance 0)
		)
		(min_thickness 0.25)
		(keepout
			(tracks not_allowed)
			(vias allowed)
			(pads allowed)
			(copperpour not_allowed)
			(footprints allowed)
		)
		(placement
			(enabled no)
			(sheetname "")
		)
		(fill
			(thermal_gap 0.5)
			(thermal_bridge_width 0.5)
			(island_removal_mode 0)
		)
		(polygon
			(pts
				(arc
					(start 308.117494 -285.982156)
					(mid 308.113774 -285.991136)
					(end 308.104794 -285.994856)
				)
				(arc
					(start 306.631594 -285.994856)
					(mid 306.622614 -285.991136)
					(end 306.618894 -285.982156)
				)
				(arc
					(start 306.618894 -285.487618)
					(mid 306.622614 -285.478638)
					(end 306.631594 -285.474918)
				)
				(arc
					(start 308.104794 -285.474918)
					(mid 308.113774 -285.478638)
					(end 308.117494 -285.487618)
				)
			)
		)
	)
	(zone
		(layer "In1.Cu")
		(hatch none 0.5)
		(connect_pads
			(clearance 0)
		)
		(min_thickness 0.25)
		(keepout
			(tracks not_allowed)
			(vias allowed)
			(pads allowed)
			(copperpour not_allowed)
			(footprints allowed)
		)
		(placement
			(enabled no)
			(sheetname "")
		)
		(fill
			(thermal_gap 0.5)
			(thermal_bridge_width 0.5)
			(island_removal_mode 0)
		)
		(polygon
			(pts
				(arc
					(start 353.988878 -397.156432)
					(mid 353.607878 -397.156432)
					(end 353.988878 -397.156432)
				)
			)
		)
	)
	(zone
		(layer "In1.Cu")
		(hatch none 0.5)
		(connect_pads
			(clearance 0)
		)
		(min_thickness 0.25)
		(keepout
			(tracks not_allowed)
			(vias allowed)
			(pads allowed)
			(copperpour not_allowed)
			(footprints allowed)
		)
		(placement
			(enabled no)
			(sheetname "")
		)
		(fill
			(thermal_gap 0.5)
			(thermal_bridge_width 0.5)
			(island_removal_mode 0)
		)
		(polygon
			(pts
				(arc
					(start 285.485332 -236.68228)
					(mid 285.481612 -236.69126)
					(end 285.472632 -236.69498)
				)
				(arc
					(start 283.999432 -236.69498)
					(mid 283.990452 -236.69126)
					(end 283.986732 -236.68228)
				)
				(arc
					(start 283.986732 -236.187742)
					(mid 283.990452 -236.178762)
					(end 283.999432 -236.175042)
				)
				(arc
					(start 285.472632 -236.175042)
					(mid 285.481612 -236.178762)
					(end 285.485332 -236.187742)
				)
			)
		)
	)
	(zone
		(layer "In1.Cu")
		(hatch none 0.5)
		(connect_pads
			(clearance 0)
		)
		(min_thickness 0.25)
		(keepout
			(tracks not_allowed)
			(vias allowed)
			(pads allowed)
			(copperpour not_allowed)
			(footprints allowed)
		)
		(placement
			(enabled no)
			(sheetname "")
		)
		(fill
			(thermal_gap 0.5)
			(thermal_bridge_width 0.5)
			(island_removal_mode 0)
		)
		(polygon
			(pts
				(arc
					(start 184.365392 -263.032494)
					(mid 184.361672 -263.041474)
					(end 184.352692 -263.045194)
				)
				(arc
					(start 182.879492 -263.045194)
					(mid 182.870512 -263.041474)
					(end 182.866792 -263.032494)
				)
				(arc
					(start 182.866792 -262.537956)
					(mid 182.870512 -262.528976)
					(end 182.879492 -262.525256)
				)
				(arc
					(start 184.352692 -262.525256)
					(mid 184.361672 -262.528976)
					(end 184.365392 -262.537956)
				)
			)
		)
	)
	(zone
		(layer "In1.Cu")
		(hatch none 0.5)
		(connect_pads
			(clearance 0)
		)
		(min_thickness 0.25)
		(keepout
			(tracks not_allowed)
			(vias allowed)
			(pads allowed)
			(copperpour not_allowed)
			(footprints allowed)
		)
		(placement
			(enabled no)
			(sheetname "")
		)
		(fill
			(thermal_gap 0.5)
			(thermal_bridge_width 0.5)
			(island_removal_mode 0)
		)
		(polygon
			(pts
				(arc
					(start 30.001464 -212.88248)
					(mid 29.997744 -212.89146)
					(end 29.988764 -212.89518)
				)
				(arc
					(start 28.515564 -212.89518)
					(mid 28.506584 -212.89146)
					(end 28.502864 -212.88248)
				)
				(arc
					(start 28.502864 -212.387942)
					(mid 28.506584 -212.378962)
					(end 28.515564 -212.375242)
				)
				(arc
					(start 29.988764 -212.375242)
					(mid 29.997744 -212.378962)
					(end 30.001464 -212.387942)
				)
			)
		)
	)
	(zone
		(layer "In1.Cu")
		(hatch none 0.5)
		(connect_pads
			(clearance 0)
		)
		(min_thickness 0.25)
		(keepout
			(tracks not_allowed)
			(vias allowed)
			(pads allowed)
			(copperpour not_allowed)
			(footprints allowed)
		)
		(placement
			(enabled no)
			(sheetname "")
		)
		(fill
			(thermal_gap 0.5)
			(thermal_bridge_width 0.5)
			(island_removal_mode 0)
		)
		(polygon
			(pts
				(arc
					(start 195.353432 -237.532418)
					(mid 195.349712 -237.541398)
					(end 195.340732 -237.545118)
				)
				(arc
					(start 193.867532 -237.545118)
					(mid 193.858552 -237.541398)
					(end 193.854832 -237.532418)
				)
				(arc
					(start 193.854832 -237.03788)
					(mid 193.858552 -237.0289)
					(end 193.867532 -237.02518)
				)
				(arc
					(start 195.340732 -237.02518)
					(mid 195.349712 -237.0289)
					(end 195.353432 -237.03788)
				)
			)
		)
	)
	(zone
		(layer "In1.Cu")
		(hatch none 0.5)
		(connect_pads
			(clearance 0)
		)
		(min_thickness 0.25)
		(keepout
			(tracks not_allowed)
			(vias allowed)
			(pads allowed)
			(copperpour not_allowed)
			(footprints allowed)
		)
		(placement
			(enabled no)
			(sheetname "")
		)
		(fill
			(thermal_gap 0.5)
			(thermal_bridge_width 0.5)
			(island_removal_mode 0)
		)
		(polygon
			(pts
				(arc
					(start 335.988914 -397.156432)
					(mid 335.607914 -397.156432)
					(end 335.988914 -397.156432)
				)
			)
		)
	)
	(zone
		(layer "In1.Cu")
		(hatch none 0.5)
		(connect_pads
			(clearance 0)
		)
		(min_thickness 0.25)
		(keepout
			(tracks not_allowed)
			(vias allowed)
			(pads allowed)
			(copperpour not_allowed)
			(footprints allowed)
		)
		(placement
			(enabled no)
			(sheetname "")
		)
		(fill
			(thermal_gap 0.5)
			(thermal_bridge_width 0.5)
			(island_removal_mode 0)
		)
		(polygon
			(pts
				(arc
					(start 85.188806 -386.003292)
					(mid 84.807806 -386.003292)
					(end 85.188806 -386.003292)
				)
			)
		)
	)
	(zone
		(layer "In1.Cu")
		(hatch none 0.5)
		(connect_pads
			(clearance 0)
		)
		(min_thickness 0.25)
		(keepout
			(tracks not_allowed)
			(vias allowed)
			(pads allowed)
			(copperpour not_allowed)
			(footprints allowed)
		)
		(placement
			(enabled no)
			(sheetname "")
		)
		(fill
			(thermal_gap 0.5)
			(thermal_bridge_width 0.5)
			(island_removal_mode 0)
		)
		(polygon
			(pts
				(arc
					(start 296.473372 -245.182136)
					(mid 296.469652 -245.191116)
					(end 296.460672 -245.194836)
				)
				(arc
					(start 294.987472 -245.194836)
					(mid 294.978492 -245.191116)
					(end 294.974772 -245.182136)
				)
				(arc
					(start 294.974772 -244.687598)
					(mid 294.978492 -244.678618)
					(end 294.987472 -244.674898)
				)
				(arc
					(start 296.460672 -244.674898)
					(mid 296.469652 -244.678618)
					(end 296.473372 -244.687598)
				)
			)
		)
	)
	(zone
		(layer "In1.Cu")
		(hatch none 0.5)
		(connect_pads
			(clearance 0)
		)
		(min_thickness 0.25)
		(keepout
			(tracks not_allowed)
			(vias allowed)
			(pads allowed)
			(copperpour not_allowed)
			(footprints allowed)
		)
		(placement
			(enabled no)
			(sheetname "")
		)
		(fill
			(thermal_gap 0.5)
			(thermal_bridge_width 0.5)
			(island_removal_mode 0)
		)
		(polygon
			(pts
				(arc
					(start 321.570096 -399.143474)
					(mid 321.265296 -399.143474)
					(end 321.570096 -399.143474)
				)
			)
		)
	)
	(zone
		(layer "In1.Cu")
		(hatch none 0.5)
		(connect_pads
			(clearance 0)
		)
		(min_thickness 0.25)
		(keepout
			(tracks not_allowed)
			(vias allowed)
			(pads allowed)
			(copperpour not_allowed)
			(footprints allowed)
		)
		(placement
			(enabled no)
			(sheetname "")
		)
		(fill
			(thermal_gap 0.5)
			(thermal_bridge_width 0.5)
			(island_removal_mode 0)
		)
		(polygon
			(pts
				(arc
					(start 61.061092 -386.003292)
					(mid 60.680092 -386.003292)
					(end 61.061092 -386.003292)
				)
			)
		)
	)
	(zone
		(layer "In1.Cu")
		(hatch none 0.5)
		(connect_pads
			(clearance 0)
		)
		(min_thickness 0.25)
		(keepout
			(tracks not_allowed)
			(vias allowed)
			(pads allowed)
			(copperpour not_allowed)
			(footprints allowed)
		)
		(placement
			(enabled no)
			(sheetname "")
		)
		(fill
			(thermal_gap 0.5)
			(thermal_bridge_width 0.5)
			(island_removal_mode 0)
		)
		(polygon
			(pts
				(arc
					(start 293.029386 -238.382302)
					(mid 293.025666 -238.391282)
					(end 293.016686 -238.395002)
				)
				(arc
					(start 291.543486 -238.395002)
					(mid 291.534506 -238.391282)
					(end 291.530786 -238.382302)
				)
				(arc
					(start 291.530786 -237.887764)
					(mid 291.534506 -237.878784)
					(end 291.543486 -237.875064)
				)
				(arc
					(start 293.016686 -237.875064)
					(mid 293.025666 -237.878784)
					(end 293.029386 -237.887764)
				)
			)
		)
	)
	(zone
		(layer "In1.Cu")
		(hatch none 0.5)
		(connect_pads
			(clearance 0)
		)
		(min_thickness 0.25)
		(keepout
			(tracks not_allowed)
			(vias allowed)
			(pads allowed)
			(copperpour not_allowed)
			(footprints allowed)
		)
		(placement
			(enabled no)
			(sheetname "")
		)
		(fill
			(thermal_gap 0.5)
			(thermal_bridge_width 0.5)
			(island_removal_mode 0)
		)
		(polygon
			(pts
				(arc
					(start 187.809378 -301.282354)
					(mid 187.805658 -301.291334)
					(end 187.796678 -301.295054)
				)
				(arc
					(start 186.323478 -301.295054)
					(mid 186.314498 -301.291334)
					(end 186.310778 -301.282354)
				)
				(arc
					(start 186.310778 -300.787816)
					(mid 186.314498 -300.778836)
					(end 186.323478 -300.775116)
				)
				(arc
					(start 187.796678 -300.775116)
					(mid 187.805658 -300.778836)
					(end 187.809378 -300.787816)
				)
			)
		)
	)
	(zone
		(layer "In1.Cu")
		(hatch none 0.5)
		(connect_pads
			(clearance 0)
		)
		(min_thickness 0.25)
		(keepout
			(tracks not_allowed)
			(vias allowed)
			(pads allowed)
			(copperpour not_allowed)
			(footprints allowed)
		)
		(placement
			(enabled no)
			(sheetname "")
		)
		(fill
			(thermal_gap 0.5)
			(thermal_bridge_width 0.5)
			(island_removal_mode 0)
		)
		(polygon
			(pts
				(arc
					(start 354.434648 -379.360684)
					(mid 354.454572 -379.36992)
					(end 354.476304 -379.37313)
				)
				(arc
					(start 354.670868 -379.37313)
					(mid 354.72475 -379.350812)
					(end 354.747068 -379.29693)
				)
				(arc
					(start 354.747068 -378.61113)
					(mid 354.72475 -378.557248)
					(end 354.670868 -378.53493)
				)
				(arc
					(start 354.476304 -378.53493)
					(mid 354.45456 -378.538098)
					(end 354.434648 -378.547376)
				)
				(arc
					(start 354.138484 -378.740162)
					(mid 354.0968 -378.752384)
					(end 354.055172 -378.739908)
				)
				(arc
					(start 353.761548 -378.547376)
					(mid 353.741624 -378.53814)
					(end 353.719892 -378.53493)
				)
				(arc
					(start 353.525328 -378.53493)
					(mid 353.471446 -378.557248)
					(end 353.449128 -378.61113)
				)
				(arc
					(start 353.449128 -379.29693)
					(mid 353.471446 -379.350812)
					(end 353.525328 -379.37313)
				)
				(arc
					(start 353.721162 -379.37313)
					(mid 353.742906 -379.369962)
					(end 353.762818 -379.360684)
				)
				(arc
					(start 354.056442 -379.168152)
					(mid 354.098098 -379.15575)
					(end 354.139754 -379.168152)
				)
			)
		)
	)
	(zone
		(layer "In1.Cu")
		(hatch none 0.5)
		(connect_pads
			(clearance 0)
		)
		(min_thickness 0.25)
		(keepout
			(tracks not_allowed)
			(vias allowed)
			(pads allowed)
			(copperpour not_allowed)
			(footprints allowed)
		)
		(placement
			(enabled no)
			(sheetname "")
		)
		(fill
			(thermal_gap 0.5)
			(thermal_bridge_width 0.5)
			(island_removal_mode 0)
		)
		(polygon
			(pts
				(arc
					(start 428.205392 -254.53213)
					(mid 428.201672 -254.54111)
					(end 428.192692 -254.54483)
				)
				(arc
					(start 426.719492 -254.54483)
					(mid 426.710512 -254.54111)
					(end 426.706792 -254.53213)
				)
				(arc
					(start 426.706792 -254.037592)
					(mid 426.710512 -254.028612)
					(end 426.719492 -254.024892)
				)
				(arc
					(start 428.192692 -254.024892)
					(mid 428.201672 -254.028612)
					(end 428.205392 -254.037592)
				)
			)
		)
	)
	(zone
		(layer "In1.Cu")
		(hatch none 0.5)
		(connect_pads
			(clearance 0)
		)
		(min_thickness 0.25)
		(keepout
			(tracks not_allowed)
			(vias allowed)
			(pads allowed)
			(copperpour not_allowed)
			(footprints allowed)
		)
		(placement
			(enabled no)
			(sheetname "")
		)
		(fill
			(thermal_gap 0.5)
			(thermal_bridge_width 0.5)
			(island_removal_mode 0)
		)
		(polygon
			(pts
				(arc
					(start 270.397478 -264.732262)
					(mid 270.393758 -264.741242)
					(end 270.384778 -264.744962)
				)
				(arc
					(start 268.911578 -264.744962)
					(mid 268.902598 -264.741242)
					(end 268.898878 -264.732262)
				)
				(arc
					(start 268.898878 -264.237724)
					(mid 268.902598 -264.228744)
					(end 268.911578 -264.225024)
				)
				(arc
					(start 270.384778 -264.225024)
					(mid 270.393758 -264.228744)
					(end 270.397478 -264.237724)
				)
			)
		)
	)
	(zone
		(layer "In1.Cu")
		(hatch none 0.5)
		(connect_pads
			(clearance 0)
		)
		(min_thickness 0.25)
		(keepout
			(tracks not_allowed)
			(vias allowed)
			(pads allowed)
			(copperpour not_allowed)
			(footprints allowed)
		)
		(placement
			(enabled no)
			(sheetname "")
		)
		(fill
			(thermal_gap 0.5)
			(thermal_bridge_width 0.5)
			(island_removal_mode 0)
		)
		(polygon
			(pts
				(arc
					(start 202.897232 -221.382336)
					(mid 202.893512 -221.391316)
					(end 202.884532 -221.395036)
				)
				(arc
					(start 201.411332 -221.395036)
					(mid 201.402352 -221.391316)
					(end 201.398632 -221.382336)
				)
				(arc
					(start 201.398632 -220.887798)
					(mid 201.402352 -220.878818)
					(end 201.411332 -220.875098)
				)
				(arc
					(start 202.884532 -220.875098)
					(mid 202.893512 -220.878818)
					(end 202.897232 -220.887798)
				)
			)
		)
	)
	(zone
		(layer "In1.Cu")
		(hatch none 0.5)
		(connect_pads
			(clearance 0)
		)
		(min_thickness 0.25)
		(keepout
			(tracks not_allowed)
			(vias allowed)
			(pads allowed)
			(copperpour not_allowed)
			(footprints allowed)
		)
		(placement
			(enabled no)
			(sheetname "")
		)
		(fill
			(thermal_gap 0.5)
			(thermal_bridge_width 0.5)
			(island_removal_mode 0)
		)
		(polygon
			(pts
				(arc
					(start 115.761262 -385.31038)
					(mid 115.380262 -385.31038)
					(end 115.761262 -385.31038)
				)
			)
		)
	)
	(zone
		(layer "In1.Cu")
		(hatch none 0.5)
		(connect_pads
			(clearance 0)
		)
		(min_thickness 0.25)
		(keepout
			(tracks not_allowed)
			(vias allowed)
			(pads allowed)
			(copperpour not_allowed)
			(footprints allowed)
		)
		(placement
			(enabled no)
			(sheetname "")
		)
		(fill
			(thermal_gap 0.5)
			(thermal_bridge_width 0.5)
			(island_removal_mode 0)
		)
		(polygon
			(pts
				(arc
					(start 199.4535 -297.032426)
					(mid 199.44978 -297.041406)
					(end 199.4408 -297.045126)
				)
				(arc
					(start 197.9676 -297.045126)
					(mid 197.95862 -297.041406)
					(end 197.9549 -297.032426)
				)
				(arc
					(start 197.9549 -296.537888)
					(mid 197.95862 -296.528908)
					(end 197.9676 -296.525188)
				)
				(arc
					(start 199.4408 -296.525188)
					(mid 199.44978 -296.528908)
					(end 199.4535 -296.537888)
				)
			)
		)
	)
	(zone
		(layer "In1.Cu")
		(hatch none 0.5)
		(connect_pads
			(clearance 0)
		)
		(min_thickness 0.25)
		(keepout
			(tracks not_allowed)
			(vias allowed)
			(pads allowed)
			(copperpour not_allowed)
			(footprints allowed)
		)
		(placement
			(enabled no)
			(sheetname "")
		)
		(fill
			(thermal_gap 0.5)
			(thermal_bridge_width 0.5)
			(island_removal_mode 0)
		)
		(polygon
			(pts
				(arc
					(start 18.357342 -305.532536)
					(mid 18.353622 -305.541516)
					(end 18.344642 -305.545236)
				)
				(arc
					(start 16.871442 -305.545236)
					(mid 16.862462 -305.541516)
					(end 16.858742 -305.532536)
				)
				(arc
					(start 16.858742 -305.037998)
					(mid 16.862462 -305.029018)
					(end 16.871442 -305.025298)
				)
				(arc
					(start 18.344642 -305.025298)
					(mid 18.353622 -305.029018)
					(end 18.357342 -305.037998)
				)
			)
		)
	)
	(zone
		(layer "In1.Cu")
		(hatch none 0.5)
		(connect_pads
			(clearance 0)
		)
		(min_thickness 0.25)
		(keepout
			(tracks not_allowed)
			(vias allowed)
			(pads allowed)
			(copperpour not_allowed)
			(footprints allowed)
		)
		(placement
			(enabled no)
			(sheetname "")
		)
		(fill
			(thermal_gap 0.5)
			(thermal_bridge_width 0.5)
			(island_removal_mode 0)
		)
		(polygon
			(pts
				(arc
					(start 37.545264 -268.13256)
					(mid 37.541544 -268.14154)
					(end 37.532564 -268.14526)
				)
				(arc
					(start 36.059364 -268.14526)
					(mid 36.050384 -268.14154)
					(end 36.046664 -268.13256)
				)
				(arc
					(start 36.046664 -267.638022)
					(mid 36.050384 -267.629042)
					(end 36.059364 -267.625322)
				)
				(arc
					(start 37.532564 -267.625322)
					(mid 37.541544 -267.629042)
					(end 37.545264 -267.638022)
				)
			)
		)
	)
	(zone
		(layer "In1.Cu")
		(hatch none 0.5)
		(connect_pads
			(clearance 0)
		)
		(min_thickness 0.25)
		(keepout
			(tracks not_allowed)
			(vias allowed)
			(pads allowed)
			(copperpour not_allowed)
			(footprints allowed)
		)
		(placement
			(enabled no)
			(sheetname "")
		)
		(fill
			(thermal_gap 0.5)
			(thermal_bridge_width 0.5)
			(island_removal_mode 0)
		)
		(polygon
			(pts
				(arc
					(start 413.117284 -263.882124)
					(mid 413.113564 -263.891104)
					(end 413.104584 -263.894824)
				)
				(arc
					(start 411.631384 -263.894824)
					(mid 411.622404 -263.891104)
					(end 411.618684 -263.882124)
				)
				(arc
					(start 411.618684 -263.387586)
					(mid 411.622404 -263.378606)
					(end 411.631384 -263.374886)
				)
				(arc
					(start 413.104584 -263.374886)
					(mid 413.113564 -263.378606)
					(end 413.117284 -263.387586)
				)
			)
		)
	)
	(zone
		(layer "In1.Cu")
		(hatch none 0.5)
		(connect_pads
			(clearance 0)
		)
		(min_thickness 0.25)
		(keepout
			(tracks not_allowed)
			(vias allowed)
			(pads allowed)
			(copperpour not_allowed)
			(footprints allowed)
		)
		(placement
			(enabled no)
			(sheetname "")
		)
		(fill
			(thermal_gap 0.5)
			(thermal_bridge_width 0.5)
			(island_removal_mode 0)
		)
		(polygon
			(pts
				(arc
					(start 176.821338 -295.332404)
					(mid 176.817618 -295.341384)
					(end 176.808638 -295.345104)
				)
				(arc
					(start 175.335438 -295.345104)
					(mid 175.326458 -295.341384)
					(end 175.322738 -295.332404)
				)
				(arc
					(start 175.322738 -294.837866)
					(mid 175.326458 -294.828886)
					(end 175.335438 -294.825166)
				)
				(arc
					(start 176.808638 -294.825166)
					(mid 176.817618 -294.828886)
					(end 176.821338 -294.837866)
				)
			)
		)
	)
	(zone
		(layer "In1.Cu")
		(hatch none 0.5)
		(connect_pads
			(clearance 0)
		)
		(min_thickness 0.25)
		(keepout
			(tracks not_allowed)
			(vias allowed)
			(pads allowed)
			(copperpour not_allowed)
			(footprints allowed)
		)
		(placement
			(enabled no)
			(sheetname "")
		)
		(fill
			(thermal_gap 0.5)
			(thermal_bridge_width 0.5)
			(island_removal_mode 0)
		)
		(polygon
			(pts
				(arc
					(start 154.688794 -386.003292)
					(mid 154.307794 -386.003292)
					(end 154.688794 -386.003292)
				)
			)
		)
	)
	(zone
		(layer "In1.Cu")
		(hatch none 0.5)
		(connect_pads
			(clearance 0)
		)
		(min_thickness 0.25)
		(keepout
			(tracks not_allowed)
			(vias allowed)
			(pads allowed)
			(copperpour not_allowed)
			(footprints allowed)
		)
		(placement
			(enabled no)
			(sheetname "")
		)
		(fill
			(thermal_gap 0.5)
			(thermal_bridge_width 0.5)
			(island_removal_mode 0)
		)
		(polygon
			(pts
				(arc
					(start 45.089318 -306.38242)
					(mid 45.085598 -306.3914)
					(end 45.076618 -306.39512)
				)
				(arc
					(start 43.603418 -306.39512)
					(mid 43.594438 -306.3914)
					(end 43.590718 -306.38242)
				)
				(arc
					(start 43.590718 -305.887882)
					(mid 43.594438 -305.878902)
					(end 43.603418 -305.875182)
				)
				(arc
					(start 45.076618 -305.875182)
					(mid 45.085598 -305.878902)
					(end 45.089318 -305.887882)
				)
			)
		)
	)
	(zone
		(layer "In1.Cu")
		(hatch none 0.5)
		(connect_pads
			(clearance 0)
		)
		(min_thickness 0.25)
		(keepout
			(tracks not_allowed)
			(vias allowed)
			(pads allowed)
			(copperpour not_allowed)
			(footprints allowed)
		)
		(placement
			(enabled no)
			(sheetname "")
		)
		(fill
			(thermal_gap 0.5)
			(thermal_bridge_width 0.5)
			(island_removal_mode 0)
		)
		(polygon
			(pts
				(arc
					(start 311.060846 -397.849344)
					(mid 310.679846 -397.849344)
					(end 311.060846 -397.849344)
				)
			)
		)
	)
	(zone
		(layer "In1.Cu")
		(hatch none 0.5)
		(connect_pads
			(clearance 0)
		)
		(min_thickness 0.25)
		(keepout
			(tracks not_allowed)
			(vias allowed)
			(pads allowed)
			(copperpour not_allowed)
			(footprints allowed)
		)
		(placement
			(enabled no)
			(sheetname "")
		)
		(fill
			(thermal_gap 0.5)
			(thermal_bridge_width 0.5)
			(island_removal_mode 0)
		)
		(polygon
			(pts
				(arc
					(start 428.205392 -299.582332)
					(mid 428.201672 -299.591312)
					(end 428.192692 -299.595032)
				)
				(arc
					(start 426.719492 -299.595032)
					(mid 426.710512 -299.591312)
					(end 426.706792 -299.582332)
				)
				(arc
					(start 426.706792 -299.087794)
					(mid 426.710512 -299.078814)
					(end 426.719492 -299.075094)
				)
				(arc
					(start 428.192692 -299.075094)
					(mid 428.201672 -299.078814)
					(end 428.205392 -299.087794)
				)
			)
		)
	)
	(zone
		(layer "In1.Cu")
		(hatch none 0.5)
		(connect_pads
			(clearance 0)
		)
		(min_thickness 0.25)
		(keepout
			(tracks not_allowed)
			(vias allowed)
			(pads allowed)
			(copperpour not_allowed)
			(footprints allowed)
		)
		(placement
			(enabled no)
			(sheetname "")
		)
		(fill
			(thermal_gap 0.5)
			(thermal_bridge_width 0.5)
			(island_removal_mode 0)
		)
		(polygon
			(pts
				(arc
					(start 450.8373 -304.682144)
					(mid 450.83358 -304.691124)
					(end 450.8246 -304.694844)
				)
				(arc
					(start 449.3514 -304.694844)
					(mid 449.34242 -304.691124)
					(end 449.3387 -304.682144)
				)
				(arc
					(start 449.3387 -304.187606)
					(mid 449.34242 -304.178626)
					(end 449.3514 -304.174906)
				)
				(arc
					(start 450.8246 -304.174906)
					(mid 450.83358 -304.178626)
					(end 450.8373 -304.187606)
				)
			)
		)
	)
	(zone
		(layer "In1.Cu")
		(hatch none 0.5)
		(connect_pads
			(clearance 0)
		)
		(min_thickness 0.25)
		(keepout
			(tracks not_allowed)
			(vias allowed)
			(pads allowed)
			(copperpour not_allowed)
			(footprints allowed)
		)
		(placement
			(enabled no)
			(sheetname "")
		)
		(fill
			(thermal_gap 0.5)
			(thermal_bridge_width 0.5)
			(island_removal_mode 0)
		)
		(polygon
			(pts
				(arc
					(start 296.473372 -217.132154)
					(mid 296.469652 -217.141134)
					(end 296.460672 -217.144854)
				)
				(arc
					(start 294.987472 -217.144854)
					(mid 294.978492 -217.141134)
					(end 294.974772 -217.132154)
				)
				(arc
					(start 294.974772 -216.637616)
					(mid 294.978492 -216.628636)
					(end 294.987472 -216.624916)
				)
				(arc
					(start 296.460672 -216.624916)
					(mid 296.469652 -216.628636)
					(end 296.473372 -216.637616)
				)
			)
		)
	)
	(zone
		(layer "In1.Cu")
		(hatch none 0.5)
		(connect_pads
			(clearance 0)
		)
		(min_thickness 0.25)
		(keepout
			(tracks not_allowed)
			(vias allowed)
			(pads allowed)
			(copperpour not_allowed)
			(footprints allowed)
		)
		(placement
			(enabled no)
			(sheetname "")
		)
		(fill
			(thermal_gap 0.5)
			(thermal_bridge_width 0.5)
			(island_removal_mode 0)
		)
		(polygon
			(pts
				(arc
					(start 424.761406 -200.982326)
					(mid 424.757686 -200.991306)
					(end 424.748706 -200.995026)
				)
				(arc
					(start 423.275506 -200.995026)
					(mid 423.266526 -200.991306)
					(end 423.262806 -200.982326)
				)
				(arc
					(start 423.262806 -200.487788)
					(mid 423.266526 -200.478808)
					(end 423.275506 -200.475088)
				)
				(arc
					(start 424.748706 -200.475088)
					(mid 424.757686 -200.478808)
					(end 424.761406 -200.487788)
				)
			)
		)
	)
	(zone
		(layer "In1.Cu")
		(hatch none 0.5)
		(connect_pads
			(clearance 0)
		)
		(min_thickness 0.25)
		(keepout
			(tracks not_allowed)
			(vias allowed)
			(pads allowed)
			(copperpour not_allowed)
			(footprints allowed)
		)
		(placement
			(enabled no)
			(sheetname "")
		)
		(fill
			(thermal_gap 0.5)
			(thermal_bridge_width 0.5)
			(island_removal_mode 0)
		)
		(polygon
			(pts
				(arc
					(start 281.385264 -279.182322)
					(mid 281.381544 -279.191302)
					(end 281.372564 -279.195022)
				)
				(arc
					(start 279.899364 -279.195022)
					(mid 279.890384 -279.191302)
					(end 279.886664 -279.182322)
				)
				(arc
					(start 279.886664 -278.687784)
					(mid 279.890384 -278.678804)
					(end 279.899364 -278.675084)
				)
				(arc
					(start 281.372564 -278.675084)
					(mid 281.381544 -278.678804)
					(end 281.385264 -278.687784)
				)
			)
		)
	)
	(zone
		(layer "In1.Cu")
		(hatch none 0.5)
		(connect_pads
			(clearance 0)
		)
		(min_thickness 0.25)
		(keepout
			(tracks not_allowed)
			(vias allowed)
			(pads allowed)
			(copperpour not_allowed)
			(footprints allowed)
		)
		(placement
			(enabled no)
			(sheetname "")
		)
		(fill
			(thermal_gap 0.5)
			(thermal_bridge_width 0.5)
			(island_removal_mode 0)
		)
		(polygon
			(pts
				(arc
					(start 176.821338 -268.13256)
					(mid 176.817618 -268.14154)
					(end 176.808638 -268.14526)
				)
				(arc
					(start 175.335438 -268.14526)
					(mid 175.326458 -268.14154)
					(end 175.322738 -268.13256)
				)
				(arc
					(start 175.322738 -267.638022)
					(mid 175.326458 -267.629042)
					(end 175.335438 -267.625322)
				)
				(arc
					(start 176.808638 -267.625322)
					(mid 176.817618 -267.629042)
					(end 176.821338 -267.638022)
				)
			)
		)
	)
	(zone
		(layer "In1.Cu")
		(hatch none 0.5)
		(connect_pads
			(clearance 0)
		)
		(min_thickness 0.25)
		(keepout
			(tracks not_allowed)
			(vias allowed)
			(pads allowed)
			(copperpour not_allowed)
			(footprints allowed)
		)
		(placement
			(enabled no)
			(sheetname "")
		)
		(fill
			(thermal_gap 0.5)
			(thermal_bridge_width 0.5)
			(island_removal_mode 0)
		)
		(polygon
			(pts
				(arc
					(start 84.78901 -385.31038)
					(mid 84.40801 -385.31038)
					(end 84.78901 -385.31038)
				)
			)
		)
	)
	(zone
		(layer "In1.Cu")
		(hatch none 0.5)
		(connect_pads
			(clearance 0)
		)
		(min_thickness 0.25)
		(keepout
			(tracks not_allowed)
			(vias allowed)
			(pads allowed)
			(copperpour not_allowed)
			(footprints allowed)
		)
		(placement
			(enabled no)
			(sheetname "")
		)
		(fill
			(thermal_gap 0.5)
			(thermal_bridge_width 0.5)
			(island_removal_mode 0)
		)
		(polygon
			(pts
				(arc
					(start 285.485332 -197.582282)
					(mid 285.481612 -197.591262)
					(end 285.472632 -197.594982)
				)
				(arc
					(start 283.999432 -197.594982)
					(mid 283.990452 -197.591262)
					(end 283.986732 -197.582282)
				)
				(arc
					(start 283.986732 -197.087744)
					(mid 283.990452 -197.078764)
					(end 283.999432 -197.075044)
				)
				(arc
					(start 285.472632 -197.075044)
					(mid 285.481612 -197.078764)
					(end 285.485332 -197.087744)
				)
			)
		)
	)
	(zone
		(layer "In1.Cu")
		(hatch none 0.5)
		(connect_pads
			(clearance 0)
		)
		(min_thickness 0.25)
		(keepout
			(tracks not_allowed)
			(vias allowed)
			(pads allowed)
			(copperpour not_allowed)
			(footprints allowed)
		)
		(placement
			(enabled no)
			(sheetname "")
		)
		(fill
			(thermal_gap 0.5)
			(thermal_bridge_width 0.5)
			(island_removal_mode 0)
		)
		(polygon
			(pts
				(arc
					(start 63.061342 -385.31038)
					(mid 62.680342 -385.31038)
					(end 63.061342 -385.31038)
				)
			)
		)
	)
	(zone
		(layer "In1.Cu")
		(hatch none 0.5)
		(connect_pads
			(clearance 0)
		)
		(min_thickness 0.25)
		(keepout
			(tracks not_allowed)
			(vias allowed)
			(pads allowed)
			(copperpour not_allowed)
			(footprints allowed)
		)
		(placement
			(enabled no)
			(sheetname "")
		)
		(fill
			(thermal_gap 0.5)
			(thermal_bridge_width 0.5)
			(island_removal_mode 0)
		)
		(polygon
			(pts
				(arc
					(start 420.661338 -301.2821)
					(mid 420.657618 -301.29108)
					(end 420.648638 -301.2948)
				)
				(arc
					(start 419.175438 -301.2948)
					(mid 419.166458 -301.29108)
					(end 419.162738 -301.2821)
				)
				(arc
					(start 419.162738 -300.787562)
					(mid 419.166458 -300.778582)
					(end 419.175438 -300.774862)
				)
				(arc
					(start 420.648638 -300.774862)
					(mid 420.657618 -300.778582)
					(end 420.661338 -300.787562)
				)
			)
		)
	)
	(zone
		(layer "In1.Cu")
		(hatch none 0.5)
		(connect_pads
			(clearance 0)
		)
		(min_thickness 0.25)
		(keepout
			(tracks not_allowed)
			(vias allowed)
			(pads allowed)
			(copperpour not_allowed)
			(footprints allowed)
		)
		(placement
			(enabled no)
			(sheetname "")
		)
		(fill
			(thermal_gap 0.5)
			(thermal_bridge_width 0.5)
			(island_removal_mode 0)
		)
		(polygon
			(pts
				(arc
					(start 447.393568 -298.732194)
					(mid 447.389848 -298.741174)
					(end 447.380868 -298.744894)
				)
				(arc
					(start 445.907668 -298.744894)
					(mid 445.898688 -298.741174)
					(end 445.894968 -298.732194)
				)
				(arc
					(start 445.894968 -298.237656)
					(mid 445.898688 -298.228676)
					(end 445.907668 -298.224956)
				)
				(arc
					(start 447.380868 -298.224956)
					(mid 447.389848 -298.228676)
					(end 447.393568 -298.237656)
				)
			)
		)
	)
	(zone
		(layer "In1.Cu")
		(hatch none 0.5)
		(connect_pads
			(clearance 0)
		)
		(min_thickness 0.25)
		(keepout
			(tracks not_allowed)
			(vias allowed)
			(pads allowed)
			(copperpour not_allowed)
			(footprints allowed)
		)
		(placement
			(enabled no)
			(sheetname "")
		)
		(fill
			(thermal_gap 0.5)
			(thermal_bridge_width 0.5)
			(island_removal_mode 0)
		)
		(polygon
			(pts
				(arc
					(start 195.353432 -284.282388)
					(mid 195.349712 -284.291368)
					(end 195.340732 -284.295088)
				)
				(arc
					(start 193.867532 -284.295088)
					(mid 193.858552 -284.291368)
					(end 193.854832 -284.282388)
				)
				(arc
					(start 193.854832 -283.78785)
					(mid 193.858552 -283.77887)
					(end 193.867532 -283.77515)
				)
				(arc
					(start 195.340732 -283.77515)
					(mid 195.349712 -283.77887)
					(end 195.353432 -283.78785)
				)
			)
		)
	)
	(zone
		(layer "In1.Cu")
		(hatch none 0.5)
		(connect_pads
			(clearance 0)
		)
		(min_thickness 0.25)
		(keepout
			(tracks not_allowed)
			(vias allowed)
			(pads allowed)
			(copperpour not_allowed)
			(footprints allowed)
		)
		(placement
			(enabled no)
			(sheetname "")
		)
		(fill
			(thermal_gap 0.5)
			(thermal_bridge_width 0.5)
			(island_removal_mode 0)
		)
		(polygon
			(pts
				(arc
					(start 450.8373 -207.78216)
					(mid 450.83358 -207.79114)
					(end 450.8246 -207.79486)
				)
				(arc
					(start 449.3514 -207.79486)
					(mid 449.34242 -207.79114)
					(end 449.3387 -207.78216)
				)
				(arc
					(start 449.3387 -207.287622)
					(mid 449.34242 -207.278642)
					(end 449.3514 -207.274922)
				)
				(arc
					(start 450.8246 -207.274922)
					(mid 450.83358 -207.278642)
					(end 450.8373 -207.287622)
				)
			)
		)
	)
	(zone
		(layer "In1.Cu")
		(hatch none 0.5)
		(connect_pads
			(clearance 0)
		)
		(min_thickness 0.25)
		(keepout
			(tracks not_allowed)
			(vias allowed)
			(pads allowed)
			(copperpour not_allowed)
			(footprints allowed)
		)
		(placement
			(enabled no)
			(sheetname "")
		)
		(fill
			(thermal_gap 0.5)
			(thermal_bridge_width 0.5)
			(island_removal_mode 0)
		)
		(polygon
			(pts
				(arc
					(start 293.029386 -281.732228)
					(mid 293.025666 -281.741208)
					(end 293.016686 -281.744928)
				)
				(arc
					(start 291.543486 -281.744928)
					(mid 291.534506 -281.741208)
					(end 291.530786 -281.732228)
				)
				(arc
					(start 291.530786 -281.23769)
					(mid 291.534506 -281.22871)
					(end 291.543486 -281.22499)
				)
				(arc
					(start 293.016686 -281.22499)
					(mid 293.025666 -281.22871)
					(end 293.029386 -281.23769)
				)
			)
		)
	)
	(zone
		(layer "In1.Cu")
		(hatch none 0.5)
		(connect_pads
			(clearance 0)
		)
		(min_thickness 0.25)
		(keepout
			(tracks not_allowed)
			(vias allowed)
			(pads allowed)
			(copperpour not_allowed)
			(footprints allowed)
		)
		(placement
			(enabled no)
			(sheetname "")
		)
		(fill
			(thermal_gap 0.5)
			(thermal_bridge_width 0.5)
			(island_removal_mode 0)
		)
		(polygon
			(pts
				(arc
					(start 277.941532 -302.132238)
					(mid 277.937812 -302.141218)
					(end 277.928832 -302.144938)
				)
				(arc
					(start 276.455632 -302.144938)
					(mid 276.446652 -302.141218)
					(end 276.442932 -302.132238)
				)
				(arc
					(start 276.442932 -301.6377)
					(mid 276.446652 -301.62872)
					(end 276.455632 -301.625)
				)
				(arc
					(start 277.928832 -301.625)
					(mid 277.937812 -301.62872)
					(end 277.941532 -301.6377)
				)
			)
		)
	)
	(zone
		(layer "In1.Cu")
		(hatch none 0.5)
		(connect_pads
			(clearance 0)
		)
		(min_thickness 0.25)
		(keepout
			(tracks not_allowed)
			(vias allowed)
			(pads allowed)
			(copperpour not_allowed)
			(footprints allowed)
		)
		(placement
			(enabled no)
			(sheetname "")
		)
		(fill
			(thermal_gap 0.5)
			(thermal_bridge_width 0.5)
			(island_removal_mode 0)
		)
		(polygon
			(pts
				(arc
					(start 447.393568 -311.482232)
					(mid 447.389848 -311.491212)
					(end 447.380868 -311.494932)
				)
				(arc
					(start 445.907668 -311.494932)
					(mid 445.898688 -311.491212)
					(end 445.894968 -311.482232)
				)
				(arc
					(start 445.894968 -310.987694)
					(mid 445.898688 -310.978714)
					(end 445.907668 -310.974994)
				)
				(arc
					(start 447.380868 -310.974994)
					(mid 447.389848 -310.978714)
					(end 447.393568 -310.987694)
				)
			)
		)
	)
	(zone
		(layer "In1.Cu")
		(hatch none 0.5)
		(connect_pads
			(clearance 0)
		)
		(min_thickness 0.25)
		(keepout
			(tracks not_allowed)
			(vias allowed)
			(pads allowed)
			(copperpour not_allowed)
			(footprints allowed)
		)
		(placement
			(enabled no)
			(sheetname "")
		)
		(fill
			(thermal_gap 0.5)
			(thermal_bridge_width 0.5)
			(island_removal_mode 0)
		)
		(polygon
			(pts
				(arc
					(start 206.9973 -234.982512)
					(mid 206.99358 -234.991492)
					(end 206.9846 -234.995212)
				)
				(arc
					(start 205.5114 -234.995212)
					(mid 205.50242 -234.991492)
					(end 205.4987 -234.982512)
				)
				(arc
					(start 205.4987 -234.487974)
					(mid 205.50242 -234.478994)
					(end 205.5114 -234.475274)
				)
				(arc
					(start 206.9846 -234.475274)
					(mid 206.99358 -234.478994)
					(end 206.9973 -234.487974)
				)
			)
		)
	)
	(zone
		(layer "In1.Cu")
		(hatch none 0.5)
		(connect_pads
			(clearance 0)
		)
		(min_thickness 0.25)
		(keepout
			(tracks not_allowed)
			(vias allowed)
			(pads allowed)
			(copperpour not_allowed)
			(footprints allowed)
		)
		(placement
			(enabled no)
			(sheetname "")
		)
		(fill
			(thermal_gap 0.5)
			(thermal_bridge_width 0.5)
			(island_removal_mode 0)
		)
		(polygon
			(pts
				(arc
					(start 450.8373 -290.232338)
					(mid 450.83358 -290.241318)
					(end 450.8246 -290.245038)
				)
				(arc
					(start 449.3514 -290.245038)
					(mid 449.34242 -290.241318)
					(end 449.3387 -290.232338)
				)
				(arc
					(start 449.3387 -289.7378)
					(mid 449.34242 -289.72882)
					(end 449.3514 -289.7251)
				)
				(arc
					(start 450.8246 -289.7251)
					(mid 450.83358 -289.72882)
					(end 450.8373 -289.7378)
				)
			)
		)
	)
	(zone
		(layer "In1.Cu")
		(hatch none 0.5)
		(connect_pads
			(clearance 0)
		)
		(min_thickness 0.25)
		(keepout
			(tracks not_allowed)
			(vias allowed)
			(pads allowed)
			(copperpour not_allowed)
			(footprints allowed)
		)
		(placement
			(enabled no)
			(sheetname "")
		)
		(fill
			(thermal_gap 0.5)
			(thermal_bridge_width 0.5)
			(island_removal_mode 0)
		)
		(polygon
			(pts
				(arc
					(start 56.077358 -239.23244)
					(mid 56.073638 -239.24142)
					(end 56.064658 -239.24514)
				)
				(arc
					(start 54.591458 -239.24514)
					(mid 54.582478 -239.24142)
					(end 54.578758 -239.23244)
				)
				(arc
					(start 54.578758 -238.737902)
					(mid 54.582478 -238.728922)
					(end 54.591458 -238.725202)
				)
				(arc
					(start 56.064658 -238.725202)
					(mid 56.073638 -238.728922)
					(end 56.077358 -238.737902)
				)
			)
		)
	)
	(zone
		(layer "In1.Cu")
		(hatch none 0.5)
		(connect_pads
			(clearance 0)
		)
		(min_thickness 0.25)
		(keepout
			(tracks not_allowed)
			(vias allowed)
			(pads allowed)
			(copperpour not_allowed)
			(footprints allowed)
		)
		(placement
			(enabled no)
			(sheetname "")
		)
		(fill
			(thermal_gap 0.5)
			(thermal_bridge_width 0.5)
			(island_removal_mode 0)
		)
		(polygon
			(pts
				(arc
					(start 277.941532 -304.682144)
					(mid 277.937812 -304.691124)
					(end 277.928832 -304.694844)
				)
				(arc
					(start 276.455632 -304.694844)
					(mid 276.446652 -304.691124)
					(end 276.442932 -304.682144)
				)
				(arc
					(start 276.442932 -304.187606)
					(mid 276.446652 -304.178626)
					(end 276.455632 -304.174906)
				)
				(arc
					(start 277.928832 -304.174906)
					(mid 277.937812 -304.178626)
					(end 277.941532 -304.187606)
				)
			)
		)
	)
	(zone
		(layer "In1.Cu")
		(hatch none 0.5)
		(connect_pads
			(clearance 0)
		)
		(min_thickness 0.25)
		(keepout
			(tracks not_allowed)
			(vias allowed)
			(pads allowed)
			(copperpour not_allowed)
			(footprints allowed)
		)
		(placement
			(enabled no)
			(sheetname "")
		)
		(fill
			(thermal_gap 0.5)
			(thermal_bridge_width 0.5)
			(island_removal_mode 0)
		)
		(polygon
			(pts
				(arc
					(start 40.98925 -200.132442)
					(mid 40.98553 -200.141422)
					(end 40.97655 -200.145142)
				)
				(arc
					(start 39.50335 -200.145142)
					(mid 39.49437 -200.141422)
					(end 39.49065 -200.132442)
				)
				(arc
					(start 39.49065 -199.637904)
					(mid 39.49437 -199.628924)
					(end 39.50335 -199.625204)
				)
				(arc
					(start 40.97655 -199.625204)
					(mid 40.98553 -199.628924)
					(end 40.98925 -199.637904)
				)
			)
		)
	)
	(zone
		(layer "In1.Cu")
		(hatch none 0.5)
		(connect_pads
			(clearance 0)
		)
		(min_thickness 0.25)
		(keepout
			(tracks not_allowed)
			(vias allowed)
			(pads allowed)
			(copperpour not_allowed)
			(footprints allowed)
		)
		(placement
			(enabled no)
			(sheetname "")
		)
		(fill
			(thermal_gap 0.5)
			(thermal_bridge_width 0.5)
			(island_removal_mode 0)
		)
		(polygon
			(pts
				(arc
					(start 308.117494 -201.83221)
					(mid 308.113774 -201.84119)
					(end 308.104794 -201.84491)
				)
				(arc
					(start 306.631594 -201.84491)
					(mid 306.622614 -201.84119)
					(end 306.618894 -201.83221)
				)
				(arc
					(start 306.618894 -201.337672)
					(mid 306.622614 -201.328692)
					(end 306.631594 -201.324972)
				)
				(arc
					(start 308.104794 -201.324972)
					(mid 308.113774 -201.328692)
					(end 308.117494 -201.337672)
				)
			)
		)
	)
	(zone
		(layer "In1.Cu")
		(hatch none 0.5)
		(connect_pads
			(clearance 0)
		)
		(min_thickness 0.25)
		(keepout
			(tracks not_allowed)
			(vias allowed)
			(pads allowed)
			(copperpour not_allowed)
			(footprints allowed)
		)
		(placement
			(enabled no)
			(sheetname "")
		)
		(fill
			(thermal_gap 0.5)
			(thermal_bridge_width 0.5)
			(island_removal_mode 0)
		)
		(polygon
			(pts
				(arc
					(start 40.98925 -268.982444)
					(mid 40.98553 -268.991424)
					(end 40.97655 -268.995144)
				)
				(arc
					(start 39.50335 -268.995144)
					(mid 39.49437 -268.991424)
					(end 39.49065 -268.982444)
				)
				(arc
					(start 39.49065 -268.487906)
					(mid 39.49437 -268.478926)
					(end 39.50335 -268.475206)
				)
				(arc
					(start 40.97655 -268.475206)
					(mid 40.98553 -268.478926)
					(end 40.98925 -268.487906)
				)
			)
		)
	)
	(zone
		(layer "In1.Cu")
		(hatch none 0.5)
		(connect_pads
			(clearance 0)
		)
		(min_thickness 0.25)
		(keepout
			(tracks not_allowed)
			(vias allowed)
			(pads allowed)
			(copperpour not_allowed)
			(footprints allowed)
		)
		(placement
			(enabled no)
			(sheetname "")
		)
		(fill
			(thermal_gap 0.5)
			(thermal_bridge_width 0.5)
			(island_removal_mode 0)
		)
		(polygon
			(pts
				(arc
					(start 187.809378 -316.582552)
					(mid 187.805658 -316.591532)
					(end 187.796678 -316.595252)
				)
				(arc
					(start 186.323478 -316.595252)
					(mid 186.314498 -316.591532)
					(end 186.310778 -316.582552)
				)
				(arc
					(start 186.310778 -316.088014)
					(mid 186.314498 -316.079034)
					(end 186.323478 -316.075314)
				)
				(arc
					(start 187.796678 -316.075314)
					(mid 187.805658 -316.079034)
					(end 187.809378 -316.088014)
				)
			)
		)
	)
	(zone
		(layer "In1.Cu")
		(hatch none 0.5)
		(connect_pads
			(clearance 0)
		)
		(min_thickness 0.25)
		(keepout
			(tracks not_allowed)
			(vias allowed)
			(pads allowed)
			(copperpour not_allowed)
			(footprints allowed)
		)
		(placement
			(enabled no)
			(sheetname "")
		)
		(fill
			(thermal_gap 0.5)
			(thermal_bridge_width 0.5)
			(island_removal_mode 0)
		)
		(polygon
			(pts
				(arc
					(start 413.117284 -241.782092)
					(mid 413.113564 -241.791072)
					(end 413.104584 -241.794792)
				)
				(arc
					(start 411.631384 -241.794792)
					(mid 411.622404 -241.791072)
					(end 411.618684 -241.782092)
				)
				(arc
					(start 411.618684 -241.287554)
					(mid 411.622404 -241.278574)
					(end 411.631384 -241.274854)
				)
				(arc
					(start 413.104584 -241.274854)
					(mid 413.113564 -241.278574)
					(end 413.117284 -241.287554)
				)
			)
		)
	)
	(zone
		(layer "In1.Cu")
		(hatch none 0.5)
		(connect_pads
			(clearance 0)
		)
		(min_thickness 0.25)
		(keepout
			(tracks not_allowed)
			(vias allowed)
			(pads allowed)
			(copperpour not_allowed)
			(footprints allowed)
		)
		(placement
			(enabled no)
			(sheetname "")
		)
		(fill
			(thermal_gap 0.5)
			(thermal_bridge_width 0.5)
			(island_removal_mode 0)
		)
		(polygon
			(pts
				(arc
					(start 40.767508 -17.967198)
					(mid 40.789826 -18.02108)
					(end 40.843708 -18.043398)
				)
				(arc
					(start 41.039288 -18.043398)
					(mid 41.061164 -18.040266)
					(end 41.081198 -18.030952)
				)
				(arc
					(start 41.374822 -17.83842)
					(mid 41.416478 -17.826018)
					(end 41.458134 -17.83842)
				)
				(arc
					(start 41.753028 -18.030952)
					(mid 41.772952 -18.040188)
					(end 41.794684 -18.043398)
				)
				(arc
					(start 41.989248 -18.043398)
					(mid 42.04313 -18.02108)
					(end 42.065448 -17.967198)
				)
				(arc
					(start 42.065448 -17.281398)
					(mid 42.04313 -17.227516)
					(end 41.989248 -17.205198)
				)
				(arc
					(start 41.794684 -17.205198)
					(mid 41.77294 -17.208366)
					(end 41.753028 -17.217644)
				)
				(arc
					(start 41.456864 -17.41043)
					(mid 41.41518 -17.422652)
					(end 41.373552 -17.410176)
				)
				(arc
					(start 41.079928 -17.217644)
					(mid 41.060004 -17.208408)
					(end 41.038272 -17.205198)
				)
				(arc
					(start 40.843708 -17.205198)
					(mid 40.789826 -17.227516)
					(end 40.767508 -17.281398)
				)
			)
		)
	)
	(zone
		(layer "In1.Cu")
		(hatch none 0.5)
		(connect_pads
			(clearance 0)
		)
		(min_thickness 0.25)
		(keepout
			(tracks not_allowed)
			(vias allowed)
			(pads allowed)
			(copperpour not_allowed)
			(footprints allowed)
		)
		(placement
			(enabled no)
			(sheetname "")
		)
		(fill
			(thermal_gap 0.5)
			(thermal_bridge_width 0.5)
			(island_removal_mode 0)
		)
		(polygon
			(pts
				(arc
					(start 52.633372 -264.732516)
					(mid 52.629652 -264.741496)
					(end 52.620672 -264.745216)
				)
				(arc
					(start 51.147472 -264.745216)
					(mid 51.138492 -264.741496)
					(end 51.134772 -264.732516)
				)
				(arc
					(start 51.134772 -264.237978)
					(mid 51.138492 -264.228998)
					(end 51.147472 -264.225278)
				)
				(arc
					(start 52.620672 -264.225278)
					(mid 52.629652 -264.228998)
					(end 52.633372 -264.237978)
				)
			)
		)
	)
	(zone
		(layer "In1.Cu")
		(hatch none 0.5)
		(connect_pads
			(clearance 0)
		)
		(min_thickness 0.25)
		(keepout
			(tracks not_allowed)
			(vias allowed)
			(pads allowed)
			(copperpour not_allowed)
			(footprints allowed)
		)
		(placement
			(enabled no)
			(sheetname "")
		)
		(fill
			(thermal_gap 0.5)
			(thermal_bridge_width 0.5)
			(island_removal_mode 0)
		)
		(polygon
			(pts
				(arc
					(start 150.218648 -391.319258)
					(mid 150.345648 -391.446258)
					(end 150.472648 -391.319258)
				)
				(arc
					(start 150.472648 -391.243058)
					(mid 150.345648 -391.116058)
					(end 150.218648 -391.243058)
				)
			)
		)
	)
	(zone
		(layer "In1.Cu")
		(hatch none 0.5)
		(connect_pads
			(clearance 0)
		)
		(min_thickness 0.25)
		(keepout
			(tracks not_allowed)
			(vias allowed)
			(pads allowed)
			(copperpour not_allowed)
			(footprints allowed)
		)
		(placement
			(enabled no)
			(sheetname "")
		)
		(fill
			(thermal_gap 0.5)
			(thermal_bridge_width 0.5)
			(island_removal_mode 0)
		)
		(polygon
			(pts
				(arc
					(start 281.385264 -215.432132)
					(mid 281.381544 -215.441112)
					(end 281.372564 -215.444832)
				)
				(arc
					(start 279.899364 -215.444832)
					(mid 279.890384 -215.441112)
					(end 279.886664 -215.432132)
				)
				(arc
					(start 279.886664 -214.937594)
					(mid 279.890384 -214.928614)
					(end 279.899364 -214.924894)
				)
				(arc
					(start 281.372564 -214.924894)
					(mid 281.381544 -214.928614)
					(end 281.385264 -214.937594)
				)
			)
		)
	)
	(zone
		(layer "In1.Cu")
		(hatch none 0.5)
		(connect_pads
			(clearance 0)
		)
		(min_thickness 0.25)
		(keepout
			(tracks not_allowed)
			(vias allowed)
			(pads allowed)
			(copperpour not_allowed)
			(footprints allowed)
		)
		(placement
			(enabled no)
			(sheetname "")
		)
		(fill
			(thermal_gap 0.5)
			(thermal_bridge_width 0.5)
			(island_removal_mode 0)
		)
		(polygon
			(pts
				(arc
					(start 383.761234 -393.69238)
					(mid 383.380234 -393.69238)
					(end 383.761234 -393.69238)
				)
			)
		)
	)
	(zone
		(layer "In1.Cu")
		(hatch none 0.5)
		(connect_pads
			(clearance 0)
		)
		(min_thickness 0.25)
		(keepout
			(tracks not_allowed)
			(vias allowed)
			(pads allowed)
			(copperpour not_allowed)
			(footprints allowed)
		)
		(placement
			(enabled no)
			(sheetname "")
		)
		(fill
			(thermal_gap 0.5)
			(thermal_bridge_width 0.5)
			(island_removal_mode 0)
		)
		(polygon
			(pts
				(arc
					(start 454.937368 -246.032274)
					(mid 454.933648 -246.041254)
					(end 454.924668 -246.044974)
				)
				(arc
					(start 453.451468 -246.044974)
					(mid 453.442488 -246.041254)
					(end 453.438768 -246.032274)
				)
				(arc
					(start 453.438768 -245.537736)
					(mid 453.442488 -245.528756)
					(end 453.451468 -245.525036)
				)
				(arc
					(start 454.924668 -245.525036)
					(mid 454.933648 -245.528756)
					(end 454.937368 -245.537736)
				)
			)
		)
	)
	(zone
		(layer "In1.Cu")
		(hatch none 0.5)
		(connect_pads
			(clearance 0)
		)
		(min_thickness 0.25)
		(keepout
			(tracks not_allowed)
			(vias allowed)
			(pads allowed)
			(copperpour not_allowed)
			(footprints allowed)
		)
		(placement
			(enabled no)
			(sheetname "")
		)
		(fill
			(thermal_gap 0.5)
			(thermal_bridge_width 0.5)
			(island_removal_mode 0)
		)
		(polygon
			(pts
				(arc
					(start 151.088852 -386.003292)
					(mid 150.707852 -386.003292)
					(end 151.088852 -386.003292)
				)
			)
		)
	)
	(zone
		(layer "In1.Cu")
		(hatch none 0.5)
		(connect_pads
			(clearance 0)
		)
		(min_thickness 0.25)
		(keepout
			(tracks not_allowed)
			(vias allowed)
			(pads allowed)
			(copperpour not_allowed)
			(footprints allowed)
		)
		(placement
			(enabled no)
			(sheetname "")
		)
		(fill
			(thermal_gap 0.5)
			(thermal_bridge_width 0.5)
			(island_removal_mode 0)
		)
		(polygon
			(pts
				(arc
					(start 206.5782 -225.385376)
					(mid 205.9178 -225.385376)
					(end 206.5782 -225.385376)
				)
			)
		)
	)
	(zone
		(layer "In1.Cu")
		(hatch none 0.5)
		(connect_pads
			(clearance 0)
		)
		(min_thickness 0.25)
		(keepout
			(tracks not_allowed)
			(vias allowed)
			(pads allowed)
			(copperpour not_allowed)
			(footprints allowed)
		)
		(placement
			(enabled no)
			(sheetname "")
		)
		(fill
			(thermal_gap 0.5)
			(thermal_bridge_width 0.5)
			(island_removal_mode 0)
		)
		(polygon
			(pts
				(arc
					(start 22.45741 -201.832464)
					(mid 22.45369 -201.841444)
					(end 22.44471 -201.845164)
				)
				(arc
					(start 20.97151 -201.845164)
					(mid 20.96253 -201.841444)
					(end 20.95881 -201.832464)
				)
				(arc
					(start 20.95881 -201.337926)
					(mid 20.96253 -201.328946)
					(end 20.97151 -201.325226)
				)
				(arc
					(start 22.44471 -201.325226)
					(mid 22.45369 -201.328946)
					(end 22.45741 -201.337926)
				)
			)
		)
	)
	(zone
		(layer "In1.Cu")
		(hatch none 0.5)
		(connect_pads
			(clearance 0)
		)
		(min_thickness 0.25)
		(keepout
			(tracks not_allowed)
			(vias allowed)
			(pads allowed)
			(copperpour not_allowed)
			(footprints allowed)
		)
		(placement
			(enabled no)
			(sheetname "")
		)
		(fill
			(thermal_gap 0.5)
			(thermal_bridge_width 0.5)
			(island_removal_mode 0)
		)
		(polygon
			(pts
				(arc
					(start 410.68879 -397.849344)
					(mid 410.30779 -397.849344)
					(end 410.68879 -397.849344)
				)
			)
		)
	)
	(zone
		(layer "In1.Cu")
		(hatch none 0.5)
		(connect_pads
			(clearance 0)
		)
		(min_thickness 0.25)
		(keepout
			(tracks not_allowed)
			(vias allowed)
			(pads allowed)
			(copperpour not_allowed)
			(footprints allowed)
		)
		(placement
			(enabled no)
			(sheetname "")
		)
		(fill
			(thermal_gap 0.5)
			(thermal_bridge_width 0.5)
			(island_removal_mode 0)
		)
		(polygon
			(pts
				(arc
					(start 296.473372 -246.882158)
					(mid 296.469652 -246.891138)
					(end 296.460672 -246.894858)
				)
				(arc
					(start 294.987472 -246.894858)
					(mid 294.978492 -246.891138)
					(end 294.974772 -246.882158)
				)
				(arc
					(start 294.974772 -246.38762)
					(mid 294.978492 -246.37864)
					(end 294.987472 -246.37492)
				)
				(arc
					(start 296.460672 -246.37492)
					(mid 296.469652 -246.37864)
					(end 296.473372 -246.38762)
				)
			)
		)
	)
	(zone
		(layer "In1.Cu")
		(hatch none 0.5)
		(connect_pads
			(clearance 0)
		)
		(min_thickness 0.25)
		(keepout
			(tracks not_allowed)
			(vias allowed)
			(pads allowed)
			(copperpour not_allowed)
			(footprints allowed)
		)
		(placement
			(enabled no)
			(sheetname "")
		)
		(fill
			(thermal_gap 0.5)
			(thermal_bridge_width 0.5)
			(island_removal_mode 0)
		)
		(polygon
			(pts
				(arc
					(start 33.445196 -251.982478)
					(mid 33.441476 -251.991458)
					(end 33.432496 -251.995178)
				)
				(arc
					(start 31.959296 -251.995178)
					(mid 31.950316 -251.991458)
					(end 31.946596 -251.982478)
				)
				(arc
					(start 31.946596 -251.48794)
					(mid 31.950316 -251.47896)
					(end 31.959296 -251.47524)
				)
				(arc
					(start 33.432496 -251.47524)
					(mid 33.441476 -251.47896)
					(end 33.445196 -251.48794)
				)
			)
		)
	)
	(zone
		(layer "In1.Cu")
		(hatch none 0.5)
		(connect_pads
			(clearance 0)
		)
		(min_thickness 0.25)
		(keepout
			(tracks not_allowed)
			(vias allowed)
			(pads allowed)
			(copperpour not_allowed)
			(footprints allowed)
		)
		(placement
			(enabled no)
			(sheetname "")
		)
		(fill
			(thermal_gap 0.5)
			(thermal_bridge_width 0.5)
			(island_removal_mode 0)
		)
		(polygon
			(pts
				(arc
					(start 117.070378 -383.92227)
					(mid 116.765578 -383.92227)
					(end 117.070378 -383.92227)
				)
			)
		)
	)
	(zone
		(layer "In1.Cu")
		(hatch none 0.5)
		(connect_pads
			(clearance 0)
		)
		(min_thickness 0.25)
		(keepout
			(tracks not_allowed)
			(vias allowed)
			(pads allowed)
			(copperpour not_allowed)
			(footprints allowed)
		)
		(placement
			(enabled no)
			(sheetname "")
		)
		(fill
			(thermal_gap 0.5)
			(thermal_bridge_width 0.5)
			(island_removal_mode 0)
		)
		(polygon
			(pts
				(arc
					(start 47.86122 -386.003292)
					(mid 47.48022 -386.003292)
					(end 47.86122 -386.003292)
				)
			)
		)
	)
	(zone
		(layer "In1.Cu")
		(hatch none 0.5)
		(connect_pads
			(clearance 0)
		)
		(min_thickness 0.25)
		(keepout
			(tracks not_allowed)
			(vias allowed)
			(pads allowed)
			(copperpour not_allowed)
			(footprints allowed)
		)
		(placement
			(enabled no)
			(sheetname "")
		)
		(fill
			(thermal_gap 0.5)
			(thermal_bridge_width 0.5)
			(island_removal_mode 0)
		)
		(polygon
			(pts
				(arc
					(start 316.190884 -399.701258)
					(mid 316.317884 -399.828258)
					(end 316.444884 -399.701258)
				)
				(arc
					(start 316.444884 -399.625058)
					(mid 316.317884 -399.498058)
					(end 316.190884 -399.625058)
				)
			)
		)
	)
	(zone
		(layer "In1.Cu")
		(hatch none 0.5)
		(connect_pads
			(clearance 0)
		)
		(min_thickness 0.25)
		(keepout
			(tracks not_allowed)
			(vias allowed)
			(pads allowed)
			(copperpour not_allowed)
			(footprints allowed)
		)
		(placement
			(enabled no)
			(sheetname "")
		)
		(fill
			(thermal_gap 0.5)
			(thermal_bridge_width 0.5)
			(island_removal_mode 0)
		)
		(polygon
			(pts
				(arc
					(start 277.941532 -225.632264)
					(mid 277.937812 -225.641244)
					(end 277.928832 -225.644964)
				)
				(arc
					(start 276.455632 -225.644964)
					(mid 276.446652 -225.641244)
					(end 276.442932 -225.632264)
				)
				(arc
					(start 276.442932 -225.137726)
					(mid 276.446652 -225.128746)
					(end 276.455632 -225.125026)
				)
				(arc
					(start 277.928832 -225.125026)
					(mid 277.937812 -225.128746)
					(end 277.941532 -225.137726)
				)
			)
		)
	)
	(zone
		(layer "In1.Cu")
		(hatch none 0.5)
		(connect_pads
			(clearance 0)
		)
		(min_thickness 0.25)
		(keepout
			(tracks not_allowed)
			(vias allowed)
			(pads allowed)
			(copperpour not_allowed)
			(footprints allowed)
		)
		(placement
			(enabled no)
			(sheetname "")
		)
		(fill
			(thermal_gap 0.5)
			(thermal_bridge_width 0.5)
			(island_removal_mode 0)
		)
		(polygon
			(pts
				(arc
					(start 450.8373 -279.182322)
					(mid 450.83358 -279.191302)
					(end 450.8246 -279.195022)
				)
				(arc
					(start 449.3514 -279.195022)
					(mid 449.34242 -279.191302)
					(end 449.3387 -279.182322)
				)
				(arc
					(start 449.3387 -278.687784)
					(mid 449.34242 -278.678804)
					(end 449.3514 -278.675084)
				)
				(arc
					(start 450.8246 -278.675084)
					(mid 450.83358 -278.678804)
					(end 450.8373 -278.687784)
				)
			)
		)
	)
	(zone
		(layer "In1.Cu")
		(hatch none 0.5)
		(connect_pads
			(clearance 0)
		)
		(min_thickness 0.25)
		(keepout
			(tracks not_allowed)
			(vias allowed)
			(pads allowed)
			(copperpour not_allowed)
			(footprints allowed)
		)
		(placement
			(enabled no)
			(sheetname "")
		)
		(fill
			(thermal_gap 0.5)
			(thermal_bridge_width 0.5)
			(island_removal_mode 0)
		)
		(polygon
			(pts
				(arc
					(start 48.533304 -312.33237)
					(mid 48.529584 -312.34135)
					(end 48.520604 -312.34507)
				)
				(arc
					(start 47.047404 -312.34507)
					(mid 47.038424 -312.34135)
					(end 47.034704 -312.33237)
				)
				(arc
					(start 47.034704 -311.837832)
					(mid 47.038424 -311.828852)
					(end 47.047404 -311.825132)
				)
				(arc
					(start 48.520604 -311.825132)
					(mid 48.529584 -311.828852)
					(end 48.533304 -311.837832)
				)
			)
		)
	)
	(zone
		(layer "In1.Cu")
		(hatch none 0.5)
		(connect_pads
			(clearance 0)
		)
		(min_thickness 0.25)
		(keepout
			(tracks not_allowed)
			(vias allowed)
			(pads allowed)
			(copperpour not_allowed)
			(footprints allowed)
		)
		(placement
			(enabled no)
			(sheetname "")
		)
		(fill
			(thermal_gap 0.5)
			(thermal_bridge_width 0.5)
			(island_removal_mode 0)
		)
		(polygon
			(pts
				(arc
					(start 454.937368 -270.682212)
					(mid 454.933648 -270.691192)
					(end 454.924668 -270.694912)
				)
				(arc
					(start 453.451468 -270.694912)
					(mid 453.442488 -270.691192)
					(end 453.438768 -270.682212)
				)
				(arc
					(start 453.438768 -270.187674)
					(mid 453.442488 -270.178694)
					(end 453.451468 -270.174974)
				)
				(arc
					(start 454.924668 -270.174974)
					(mid 454.933648 -270.178694)
					(end 454.937368 -270.187674)
				)
			)
		)
	)
	(zone
		(layer "In1.Cu")
		(hatch none 0.5)
		(connect_pads
			(clearance 0)
		)
		(min_thickness 0.25)
		(keepout
			(tracks not_allowed)
			(vias allowed)
			(pads allowed)
			(copperpour not_allowed)
			(footprints allowed)
		)
		(placement
			(enabled no)
			(sheetname "")
		)
		(fill
			(thermal_gap 0.5)
			(thermal_bridge_width 0.5)
			(island_removal_mode 0)
		)
		(polygon
			(pts
				(arc
					(start 266.29741 -284.282134)
					(mid 266.29369 -284.291114)
					(end 266.28471 -284.294834)
				)
				(arc
					(start 264.81151 -284.294834)
					(mid 264.80253 -284.291114)
					(end 264.79881 -284.282134)
				)
				(arc
					(start 264.79881 -283.787596)
					(mid 264.80253 -283.778616)
					(end 264.81151 -283.774896)
				)
				(arc
					(start 266.28471 -283.774896)
					(mid 266.29369 -283.778616)
					(end 266.29741 -283.787596)
				)
			)
		)
	)
	(zone
		(layer "In1.Cu")
		(hatch none 0.5)
		(connect_pads
			(clearance 0)
		)
		(min_thickness 0.25)
		(keepout
			(tracks not_allowed)
			(vias allowed)
			(pads allowed)
			(copperpour not_allowed)
			(footprints allowed)
		)
		(placement
			(enabled no)
			(sheetname "")
		)
		(fill
			(thermal_gap 0.5)
			(thermal_bridge_width 0.5)
			(island_removal_mode 0)
		)
		(polygon
			(pts
				(arc
					(start 120.96115 -389.467344)
					(mid 120.58015 -389.467344)
					(end 120.96115 -389.467344)
				)
			)
		)
	)
	(zone
		(layer "In1.Cu")
		(hatch none 0.5)
		(connect_pads
			(clearance 0)
		)
		(min_thickness 0.25)
		(keepout
			(tracks not_allowed)
			(vias allowed)
			(pads allowed)
			(copperpour not_allowed)
			(footprints allowed)
		)
		(placement
			(enabled no)
			(sheetname "")
		)
		(fill
			(thermal_gap 0.5)
			(thermal_bridge_width 0.5)
			(island_removal_mode 0)
		)
		(polygon
			(pts
				(arc
					(start 172.72127 -301.282354)
					(mid 172.71755 -301.291334)
					(end 172.70857 -301.295054)
				)
				(arc
					(start 171.23537 -301.295054)
					(mid 171.22639 -301.291334)
					(end 171.22267 -301.282354)
				)
				(arc
					(start 171.22267 -300.787816)
					(mid 171.22639 -300.778836)
					(end 171.23537 -300.775116)
				)
				(arc
					(start 172.70857 -300.775116)
					(mid 172.71755 -300.778836)
					(end 172.72127 -300.787816)
				)
			)
		)
	)
	(zone
		(layer "In1.Cu")
		(hatch none 0.5)
		(connect_pads
			(clearance 0)
		)
		(min_thickness 0.25)
		(keepout
			(tracks not_allowed)
			(vias allowed)
			(pads allowed)
			(copperpour not_allowed)
			(footprints allowed)
		)
		(placement
			(enabled no)
			(sheetname "")
		)
		(fill
			(thermal_gap 0.5)
			(thermal_bridge_width 0.5)
			(island_removal_mode 0)
		)
		(polygon
			(pts
				(arc
					(start 48.533304 -304.682398)
					(mid 48.529584 -304.691378)
					(end 48.520604 -304.695098)
				)
				(arc
					(start 47.047404 -304.695098)
					(mid 47.038424 -304.691378)
					(end 47.034704 -304.682398)
				)
				(arc
					(start 47.034704 -304.18786)
					(mid 47.038424 -304.17888)
					(end 47.047404 -304.17516)
				)
				(arc
					(start 48.520604 -304.17516)
					(mid 48.529584 -304.17888)
					(end 48.533304 -304.18786)
				)
			)
		)
	)
	(zone
		(layer "In1.Cu")
		(hatch none 0.5)
		(connect_pads
			(clearance 0)
		)
		(min_thickness 0.25)
		(keepout
			(tracks not_allowed)
			(vias allowed)
			(pads allowed)
			(copperpour not_allowed)
			(footprints allowed)
		)
		(placement
			(enabled no)
			(sheetname "")
		)
		(fill
			(thermal_gap 0.5)
			(thermal_bridge_width 0.5)
			(island_removal_mode 0)
		)
		(polygon
			(pts
				(arc
					(start 374.27027 -392.30427)
					(mid 373.96547 -392.30427)
					(end 374.27027 -392.30427)
				)
			)
		)
	)
	(zone
		(layer "In1.Cu")
		(hatch none 0.5)
		(connect_pads
			(clearance 0)
		)
		(min_thickness 0.25)
		(keepout
			(tracks not_allowed)
			(vias allowed)
			(pads allowed)
			(copperpour not_allowed)
			(footprints allowed)
		)
		(placement
			(enabled no)
			(sheetname "")
		)
		(fill
			(thermal_gap 0.5)
			(thermal_bridge_width 0.5)
			(island_removal_mode 0)
		)
		(polygon
			(pts
				(arc
					(start 206.9973 -276.632416)
					(mid 206.99358 -276.641396)
					(end 206.9846 -276.645116)
				)
				(arc
					(start 205.5114 -276.645116)
					(mid 205.50242 -276.641396)
					(end 205.4987 -276.632416)
				)
				(arc
					(start 205.4987 -276.137878)
					(mid 205.50242 -276.128898)
					(end 205.5114 -276.125178)
				)
				(arc
					(start 206.9846 -276.125178)
					(mid 206.99358 -276.128898)
					(end 206.9973 -276.137878)
				)
			)
		)
	)
	(zone
		(layer "In1.Cu")
		(hatch none 0.5)
		(connect_pads
			(clearance 0)
		)
		(min_thickness 0.25)
		(keepout
			(tracks not_allowed)
			(vias allowed)
			(pads allowed)
			(copperpour not_allowed)
			(footprints allowed)
		)
		(placement
			(enabled no)
			(sheetname "")
		)
		(fill
			(thermal_gap 0.5)
			(thermal_bridge_width 0.5)
			(island_removal_mode 0)
		)
		(polygon
			(pts
				(arc
					(start 52.633372 -208.632552)
					(mid 52.629652 -208.641532)
					(end 52.620672 -208.645252)
				)
				(arc
					(start 51.147472 -208.645252)
					(mid 51.138492 -208.641532)
					(end 51.134772 -208.632552)
				)
				(arc
					(start 51.134772 -208.138014)
					(mid 51.138492 -208.129034)
					(end 51.147472 -208.125314)
				)
				(arc
					(start 52.620672 -208.125314)
					(mid 52.629652 -208.129034)
					(end 52.633372 -208.138014)
				)
			)
		)
	)
	(zone
		(layer "In1.Cu")
		(hatch none 0.5)
		(connect_pads
			(clearance 0)
		)
		(min_thickness 0.25)
		(keepout
			(tracks not_allowed)
			(vias allowed)
			(pads allowed)
			(copperpour not_allowed)
			(footprints allowed)
		)
		(placement
			(enabled no)
			(sheetname "")
		)
		(fill
			(thermal_gap 0.5)
			(thermal_bridge_width 0.5)
			(island_removal_mode 0)
		)
		(polygon
			(pts
				(arc
					(start 37.545264 -309.782464)
					(mid 37.541544 -309.791444)
					(end 37.532564 -309.795164)
				)
				(arc
					(start 36.059364 -309.795164)
					(mid 36.050384 -309.791444)
					(end 36.046664 -309.782464)
				)
				(arc
					(start 36.046664 -309.287926)
					(mid 36.050384 -309.278946)
					(end 36.059364 -309.275226)
				)
				(arc
					(start 37.532564 -309.275226)
					(mid 37.541544 -309.278946)
					(end 37.545264 -309.287926)
				)
			)
		)
	)
	(zone
		(layer "In1.Cu")
		(hatch none 0.5)
		(connect_pads
			(clearance 0)
		)
		(min_thickness 0.25)
		(keepout
			(tracks not_allowed)
			(vias allowed)
			(pads allowed)
			(copperpour not_allowed)
			(footprints allowed)
		)
		(placement
			(enabled no)
			(sheetname "")
		)
		(fill
			(thermal_gap 0.5)
			(thermal_bridge_width 0.5)
			(island_removal_mode 0)
		)
		(polygon
			(pts
				(arc
					(start 45.089318 -272.382488)
					(mid 45.085598 -272.391468)
					(end 45.076618 -272.395188)
				)
				(arc
					(start 43.603418 -272.395188)
					(mid 43.594438 -272.391468)
					(end 43.590718 -272.382488)
				)
				(arc
					(start 43.590718 -271.88795)
					(mid 43.594438 -271.87897)
					(end 43.603418 -271.87525)
				)
				(arc
					(start 45.076618 -271.87525)
					(mid 45.085598 -271.87897)
					(end 45.089318 -271.88795)
				)
			)
		)
	)
	(zone
		(layer "In1.Cu")
		(hatch none 0.5)
		(connect_pads
			(clearance 0)
		)
		(min_thickness 0.25)
		(keepout
			(tracks not_allowed)
			(vias allowed)
			(pads allowed)
			(copperpour not_allowed)
			(footprints allowed)
		)
		(placement
			(enabled no)
			(sheetname "")
		)
		(fill
			(thermal_gap 0.5)
			(thermal_bridge_width 0.5)
			(island_removal_mode 0)
		)
		(polygon
			(pts
				(arc
					(start 413.117284 -239.232186)
					(mid 413.113564 -239.241166)
					(end 413.104584 -239.244886)
				)
				(arc
					(start 411.631384 -239.244886)
					(mid 411.622404 -239.241166)
					(end 411.618684 -239.232186)
				)
				(arc
					(start 411.618684 -238.737648)
					(mid 411.622404 -238.728668)
					(end 411.631384 -238.724948)
				)
				(arc
					(start 413.104584 -238.724948)
					(mid 413.113564 -238.728668)
					(end 413.117284 -238.737648)
				)
			)
		)
	)
	(zone
		(layer "In1.Cu")
		(hatch none 0.5)
		(connect_pads
			(clearance 0)
		)
		(min_thickness 0.25)
		(keepout
			(tracks not_allowed)
			(vias allowed)
			(pads allowed)
			(copperpour not_allowed)
			(footprints allowed)
		)
		(placement
			(enabled no)
			(sheetname "")
		)
		(fill
			(thermal_gap 0.5)
			(thermal_bridge_width 0.5)
			(island_removal_mode 0)
		)
		(polygon
			(pts
				(arc
					(start 285.485332 -223.932242)
					(mid 285.481612 -223.941222)
					(end 285.472632 -223.944942)
				)
				(arc
					(start 283.999432 -223.944942)
					(mid 283.990452 -223.941222)
					(end 283.986732 -223.932242)
				)
				(arc
					(start 283.986732 -223.437704)
					(mid 283.990452 -223.428724)
					(end 283.999432 -223.425004)
				)
				(arc
					(start 285.472632 -223.425004)
					(mid 285.481612 -223.428724)
					(end 285.485332 -223.437704)
				)
			)
		)
	)
	(zone
		(layer "In1.Cu")
		(hatch none 0.5)
		(connect_pads
			(clearance 0)
		)
		(min_thickness 0.25)
		(keepout
			(tracks not_allowed)
			(vias allowed)
			(pads allowed)
			(copperpour not_allowed)
			(footprints allowed)
		)
		(placement
			(enabled no)
			(sheetname "")
		)
		(fill
			(thermal_gap 0.5)
			(thermal_bridge_width 0.5)
			(island_removal_mode 0)
		)
		(polygon
			(pts
				(arc
					(start 265.87831 -204.134974)
					(mid 265.21791 -204.134974)
					(end 265.87831 -204.134974)
				)
			)
		)
	)
	(zone
		(layer "In1.Cu")
		(hatch none 0.5)
		(connect_pads
			(clearance 0)
		)
		(min_thickness 0.25)
		(keepout
			(tracks not_allowed)
			(vias allowed)
			(pads allowed)
			(copperpour not_allowed)
			(footprints allowed)
		)
		(placement
			(enabled no)
			(sheetname "")
		)
		(fill
			(thermal_gap 0.5)
			(thermal_bridge_width 0.5)
			(island_removal_mode 0)
		)
		(polygon
			(pts
				(arc
					(start 199.4535 -300.43247)
					(mid 199.44978 -300.44145)
					(end 199.4408 -300.44517)
				)
				(arc
					(start 197.9676 -300.44517)
					(mid 197.95862 -300.44145)
					(end 197.9549 -300.43247)
				)
				(arc
					(start 197.9549 -299.937932)
					(mid 197.95862 -299.928952)
					(end 197.9676 -299.925232)
				)
				(arc
					(start 199.4408 -299.925232)
					(mid 199.44978 -299.928952)
					(end 199.4535 -299.937932)
				)
			)
		)
	)
	(zone
		(layer "In1.Cu")
		(hatch none 0.5)
		(connect_pads
			(clearance 0)
		)
		(min_thickness 0.25)
		(keepout
			(tracks not_allowed)
			(vias allowed)
			(pads allowed)
			(copperpour not_allowed)
			(footprints allowed)
		)
		(placement
			(enabled no)
			(sheetname "")
		)
		(fill
			(thermal_gap 0.5)
			(thermal_bridge_width 0.5)
			(island_removal_mode 0)
		)
		(polygon
			(pts
				(arc
					(start 439.849514 -249.432318)
					(mid 439.845794 -249.441298)
					(end 439.836814 -249.445018)
				)
				(arc
					(start 438.363614 -249.445018)
					(mid 438.354634 -249.441298)
					(end 438.350914 -249.432318)
				)
				(arc
					(start 438.350914 -248.93778)
					(mid 438.354634 -248.9288)
					(end 438.363614 -248.92508)
				)
				(arc
					(start 439.836814 -248.92508)
					(mid 439.845794 -248.9288)
					(end 439.849514 -248.93778)
				)
			)
		)
	)
	(zone
		(layer "In1.Cu")
		(hatch none 0.5)
		(connect_pads
			(clearance 0)
		)
		(min_thickness 0.25)
		(keepout
			(tracks not_allowed)
			(vias allowed)
			(pads allowed)
			(copperpour not_allowed)
			(footprints allowed)
		)
		(placement
			(enabled no)
			(sheetname "")
		)
		(fill
			(thermal_gap 0.5)
			(thermal_bridge_width 0.5)
			(island_removal_mode 0)
		)
		(polygon
			(pts
				(arc
					(start 266.29741 -246.882158)
					(mid 266.29369 -246.891138)
					(end 266.28471 -246.894858)
				)
				(arc
					(start 264.81151 -246.894858)
					(mid 264.80253 -246.891138)
					(end 264.79881 -246.882158)
				)
				(arc
					(start 264.79881 -246.38762)
					(mid 264.80253 -246.37864)
					(end 264.81151 -246.37492)
				)
				(arc
					(start 266.28471 -246.37492)
					(mid 266.29369 -246.37864)
					(end 266.29741 -246.38762)
				)
			)
		)
	)
	(zone
		(layer "In1.Cu")
		(hatch none 0.5)
		(connect_pads
			(clearance 0)
		)
		(min_thickness 0.25)
		(keepout
			(tracks not_allowed)
			(vias allowed)
			(pads allowed)
			(copperpour not_allowed)
			(footprints allowed)
		)
		(placement
			(enabled no)
			(sheetname "")
		)
		(fill
			(thermal_gap 0.5)
			(thermal_bridge_width 0.5)
			(island_removal_mode 0)
		)
		(polygon
			(pts
				(arc
					(start 33.445196 -268.982444)
					(mid 33.441476 -268.991424)
					(end 33.432496 -268.995144)
				)
				(arc
					(start 31.959296 -268.995144)
					(mid 31.950316 -268.991424)
					(end 31.946596 -268.982444)
				)
				(arc
					(start 31.946596 -268.487906)
					(mid 31.950316 -268.478926)
					(end 31.959296 -268.475206)
				)
				(arc
					(start 33.432496 -268.475206)
					(mid 33.441476 -268.478926)
					(end 33.445196 -268.487906)
				)
			)
		)
	)
	(zone
		(layer "In1.Cu")
		(hatch none 0.5)
		(connect_pads
			(clearance 0)
		)
		(min_thickness 0.25)
		(keepout
			(tracks not_allowed)
			(vias allowed)
			(pads allowed)
			(copperpour not_allowed)
			(footprints allowed)
		)
		(placement
			(enabled no)
			(sheetname "")
		)
		(fill
			(thermal_gap 0.5)
			(thermal_bridge_width 0.5)
			(island_removal_mode 0)
		)
		(polygon
			(pts
				(arc
					(start 420.661338 -234.13212)
					(mid 420.657618 -234.1411)
					(end 420.648638 -234.14482)
				)
				(arc
					(start 419.175438 -234.14482)
					(mid 419.166458 -234.1411)
					(end 419.162738 -234.13212)
				)
				(arc
					(start 419.162738 -233.637582)
					(mid 419.166458 -233.628602)
					(end 419.175438 -233.624882)
				)
				(arc
					(start 420.648638 -233.624882)
					(mid 420.657618 -233.628602)
					(end 420.661338 -233.637582)
				)
			)
		)
	)
	(zone
		(layer "In1.Cu")
		(hatch none 0.5)
		(connect_pads
			(clearance 0)
		)
		(min_thickness 0.25)
		(keepout
			(tracks not_allowed)
			(vias allowed)
			(pads allowed)
			(copperpour not_allowed)
			(footprints allowed)
		)
		(placement
			(enabled no)
			(sheetname "")
		)
		(fill
			(thermal_gap 0.5)
			(thermal_bridge_width 0.5)
			(island_removal_mode 0)
		)
		(polygon
			(pts
				(arc
					(start 454.937368 -234.982258)
					(mid 454.933648 -234.991238)
					(end 454.924668 -234.994958)
				)
				(arc
					(start 453.451468 -234.994958)
					(mid 453.442488 -234.991238)
					(end 453.438768 -234.982258)
				)
				(arc
					(start 453.438768 -234.48772)
					(mid 453.442488 -234.47874)
					(end 453.451468 -234.47502)
				)
				(arc
					(start 454.924668 -234.47502)
					(mid 454.933648 -234.47874)
					(end 454.937368 -234.48772)
				)
			)
		)
	)
	(zone
		(layer "In1.Cu")
		(hatch none 0.5)
		(connect_pads
			(clearance 0)
		)
		(min_thickness 0.25)
		(keepout
			(tracks not_allowed)
			(vias allowed)
			(pads allowed)
			(copperpour not_allowed)
			(footprints allowed)
		)
		(placement
			(enabled no)
			(sheetname "")
		)
		(fill
			(thermal_gap 0.5)
			(thermal_bridge_width 0.5)
			(island_removal_mode 0)
		)
		(polygon
			(pts
				(arc
					(start 403.818598 -399.701258)
					(mid 403.945598 -399.828258)
					(end 404.072598 -399.701258)
				)
				(arc
					(start 404.072598 -399.625058)
					(mid 403.945598 -399.498058)
					(end 403.818598 -399.625058)
				)
			)
		)
	)
	(zone
		(layer "In1.Cu")
		(hatch none 0.5)
		(connect_pads
			(clearance 0)
		)
		(min_thickness 0.25)
		(keepout
			(tracks not_allowed)
			(vias allowed)
			(pads allowed)
			(copperpour not_allowed)
			(footprints allowed)
		)
		(placement
			(enabled no)
			(sheetname "")
		)
		(fill
			(thermal_gap 0.5)
			(thermal_bridge_width 0.5)
			(island_removal_mode 0)
		)
		(polygon
			(pts
				(arc
					(start 191.909446 -211.182458)
					(mid 191.905726 -211.191438)
					(end 191.896746 -211.195158)
				)
				(arc
					(start 190.423546 -211.195158)
					(mid 190.414566 -211.191438)
					(end 190.410846 -211.182458)
				)
				(arc
					(start 190.410846 -210.68792)
					(mid 190.414566 -210.67894)
					(end 190.423546 -210.67522)
				)
				(arc
					(start 191.896746 -210.67522)
					(mid 191.905726 -210.67894)
					(end 191.909446 -210.68792)
				)
			)
		)
	)
	(zone
		(layer "In1.Cu")
		(hatch none 0.5)
		(connect_pads
			(clearance 0)
		)
		(min_thickness 0.25)
		(keepout
			(tracks not_allowed)
			(vias allowed)
			(pads allowed)
			(copperpour not_allowed)
			(footprints allowed)
		)
		(placement
			(enabled no)
			(sheetname "")
		)
		(fill
			(thermal_gap 0.5)
			(thermal_bridge_width 0.5)
			(island_removal_mode 0)
		)
		(polygon
			(pts
				(arc
					(start 60.177426 -231.582468)
					(mid 60.173706 -231.591448)
					(end 60.164726 -231.595168)
				)
				(arc
					(start 58.691526 -231.595168)
					(mid 58.682546 -231.591448)
					(end 58.678826 -231.582468)
				)
				(arc
					(start 58.678826 -231.08793)
					(mid 58.682546 -231.07895)
					(end 58.691526 -231.07523)
				)
				(arc
					(start 60.164726 -231.07523)
					(mid 60.173706 -231.07895)
					(end 60.177426 -231.08793)
				)
			)
		)
	)
	(zone
		(layer "In1.Cu")
		(hatch none 0.5)
		(connect_pads
			(clearance 0)
		)
		(min_thickness 0.25)
		(keepout
			(tracks not_allowed)
			(vias allowed)
			(pads allowed)
			(copperpour not_allowed)
			(footprints allowed)
		)
		(placement
			(enabled no)
			(sheetname "")
		)
		(fill
			(thermal_gap 0.5)
			(thermal_bridge_width 0.5)
			(island_removal_mode 0)
		)
		(polygon
			(pts
				(arc
					(start 304.017426 -277.4823)
					(mid 304.013706 -277.49128)
					(end 304.004726 -277.495)
				)
				(arc
					(start 302.531526 -277.495)
					(mid 302.522546 -277.49128)
					(end 302.518826 -277.4823)
				)
				(arc
					(start 302.518826 -276.987762)
					(mid 302.522546 -276.978782)
					(end 302.531526 -276.975062)
				)
				(arc
					(start 304.004726 -276.975062)
					(mid 304.013706 -276.978782)
					(end 304.017426 -276.987762)
				)
			)
		)
	)
	(zone
		(layer "In1.Cu")
		(hatch none 0.5)
		(connect_pads
			(clearance 0)
		)
		(min_thickness 0.25)
		(keepout
			(tracks not_allowed)
			(vias allowed)
			(pads allowed)
			(copperpour not_allowed)
			(footprints allowed)
		)
		(placement
			(enabled no)
			(sheetname "")
		)
		(fill
			(thermal_gap 0.5)
			(thermal_bridge_width 0.5)
			(island_removal_mode 0)
		)
		(polygon
			(pts
				(arc
					(start 413.117284 -284.282134)
					(mid 413.113564 -284.291114)
					(end 413.104584 -284.294834)
				)
				(arc
					(start 411.631384 -284.294834)
					(mid 411.622404 -284.291114)
					(end 411.618684 -284.282134)
				)
				(arc
					(start 411.618684 -283.787596)
					(mid 411.622404 -283.778616)
					(end 411.631384 -283.774896)
				)
				(arc
					(start 413.104584 -283.774896)
					(mid 413.113564 -283.778616)
					(end 413.117284 -283.787596)
				)
			)
		)
	)
	(zone
		(layer "In1.Cu")
		(hatch none 0.5)
		(connect_pads
			(clearance 0)
		)
		(min_thickness 0.25)
		(keepout
			(tracks not_allowed)
			(vias allowed)
			(pads allowed)
			(copperpour not_allowed)
			(footprints allowed)
		)
		(placement
			(enabled no)
			(sheetname "")
		)
		(fill
			(thermal_gap 0.5)
			(thermal_bridge_width 0.5)
			(island_removal_mode 0)
		)
		(polygon
			(pts
				(arc
					(start 176.821338 -244.332506)
					(mid 176.817618 -244.341486)
					(end 176.808638 -244.345206)
				)
				(arc
					(start 175.335438 -244.345206)
					(mid 175.326458 -244.341486)
					(end 175.322738 -244.332506)
				)
				(arc
					(start 175.322738 -243.837968)
					(mid 175.326458 -243.828988)
					(end 175.335438 -243.825268)
				)
				(arc
					(start 176.808638 -243.825268)
					(mid 176.817618 -243.828988)
					(end 176.821338 -243.837968)
				)
			)
		)
	)
	(zone
		(layer "In1.Cu")
		(hatch none 0.5)
		(connect_pads
			(clearance 0)
		)
		(min_thickness 0.25)
		(keepout
			(tracks not_allowed)
			(vias allowed)
			(pads allowed)
			(copperpour not_allowed)
			(footprints allowed)
		)
		(placement
			(enabled no)
			(sheetname "")
		)
		(fill
			(thermal_gap 0.5)
			(thermal_bridge_width 0.5)
			(island_removal_mode 0)
		)
		(polygon
			(pts
				(arc
					(start 169.277284 -264.732516)
					(mid 169.273564 -264.741496)
					(end 169.264584 -264.745216)
				)
				(arc
					(start 167.791384 -264.745216)
					(mid 167.782404 -264.741496)
					(end 167.778684 -264.732516)
				)
				(arc
					(start 167.778684 -264.237978)
					(mid 167.782404 -264.228998)
					(end 167.791384 -264.225278)
				)
				(arc
					(start 169.264584 -264.225278)
					(mid 169.273564 -264.228998)
					(end 169.277284 -264.237978)
				)
			)
		)
	)
	(zone
		(layer "In1.Cu")
		(hatch none 0.5)
		(connect_pads
			(clearance 0)
		)
		(min_thickness 0.25)
		(keepout
			(tracks not_allowed)
			(vias allowed)
			(pads allowed)
			(copperpour not_allowed)
			(footprints allowed)
		)
		(placement
			(enabled no)
			(sheetname "")
		)
		(fill
			(thermal_gap 0.5)
			(thermal_bridge_width 0.5)
			(island_removal_mode 0)
		)
		(polygon
			(pts
				(arc
					(start 180.265324 -229.882446)
					(mid 180.261604 -229.891426)
					(end 180.252624 -229.895146)
				)
				(arc
					(start 178.779424 -229.895146)
					(mid 178.770444 -229.891426)
					(end 178.766724 -229.882446)
				)
				(arc
					(start 178.766724 -229.387908)
					(mid 178.770444 -229.378928)
					(end 178.779424 -229.375208)
				)
				(arc
					(start 180.252624 -229.375208)
					(mid 180.261604 -229.378928)
					(end 180.265324 -229.387908)
				)
			)
		)
	)
	(zone
		(layer "In1.Cu")
		(hatch none 0.5)
		(connect_pads
			(clearance 0)
		)
		(min_thickness 0.25)
		(keepout
			(tracks not_allowed)
			(vias allowed)
			(pads allowed)
			(copperpour not_allowed)
			(footprints allowed)
		)
		(placement
			(enabled no)
			(sheetname "")
		)
		(fill
			(thermal_gap 0.5)
			(thermal_bridge_width 0.5)
			(island_removal_mode 0)
		)
		(polygon
			(pts
				(arc
					(start 52.633372 -217.982546)
					(mid 52.629652 -217.991526)
					(end 52.620672 -217.995246)
				)
				(arc
					(start 51.147472 -217.995246)
					(mid 51.138492 -217.991526)
					(end 51.134772 -217.982546)
				)
				(arc
					(start 51.134772 -217.488008)
					(mid 51.138492 -217.479028)
					(end 51.147472 -217.475308)
				)
				(arc
					(start 52.620672 -217.475308)
					(mid 52.629652 -217.479028)
					(end 52.633372 -217.488008)
				)
			)
		)
	)
	(zone
		(layer "In1.Cu")
		(hatch none 0.5)
		(connect_pads
			(clearance 0)
		)
		(min_thickness 0.25)
		(keepout
			(tracks not_allowed)
			(vias allowed)
			(pads allowed)
			(copperpour not_allowed)
			(footprints allowed)
		)
		(placement
			(enabled no)
			(sheetname "")
		)
		(fill
			(thermal_gap 0.5)
			(thermal_bridge_width 0.5)
			(island_removal_mode 0)
		)
		(polygon
			(pts
				(arc
					(start 285.485332 -254.53213)
					(mid 285.481612 -254.54111)
					(end 285.472632 -254.54483)
				)
				(arc
					(start 283.999432 -254.54483)
					(mid 283.990452 -254.54111)
					(end 283.986732 -254.53213)
				)
				(arc
					(start 283.986732 -254.037592)
					(mid 283.990452 -254.028612)
					(end 283.999432 -254.024892)
				)
				(arc
					(start 285.472632 -254.024892)
					(mid 285.481612 -254.028612)
					(end 285.485332 -254.037592)
				)
			)
		)
	)
	(zone
		(layer "In1.Cu")
		(hatch none 0.5)
		(connect_pads
			(clearance 0)
		)
		(min_thickness 0.25)
		(keepout
			(tracks not_allowed)
			(vias allowed)
			(pads allowed)
			(copperpour not_allowed)
			(footprints allowed)
		)
		(placement
			(enabled no)
			(sheetname "")
		)
		(fill
			(thermal_gap 0.5)
			(thermal_bridge_width 0.5)
			(island_removal_mode 0)
		)
		(polygon
			(pts
				(arc
					(start 132.561076 -385.31038)
					(mid 132.180076 -385.31038)
					(end 132.561076 -385.31038)
				)
			)
		)
	)
	(zone
		(layer "In1.Cu")
		(hatch none 0.5)
		(connect_pads
			(clearance 0)
		)
		(min_thickness 0.25)
		(keepout
			(tracks not_allowed)
			(vias allowed)
			(pads allowed)
			(copperpour not_allowed)
			(footprints allowed)
		)
		(placement
			(enabled no)
			(sheetname "")
		)
		(fill
			(thermal_gap 0.5)
			(thermal_bridge_width 0.5)
			(island_removal_mode 0)
		)
		(polygon
			(pts
				(arc
					(start 439.849514 -238.382302)
					(mid 439.845794 -238.391282)
					(end 439.836814 -238.395002)
				)
				(arc
					(start 438.363614 -238.395002)
					(mid 438.354634 -238.391282)
					(end 438.350914 -238.382302)
				)
				(arc
					(start 438.350914 -237.887764)
					(mid 438.354634 -237.878784)
					(end 438.363614 -237.875064)
				)
				(arc
					(start 439.836814 -237.875064)
					(mid 439.845794 -237.878784)
					(end 439.849514 -237.887764)
				)
			)
		)
	)
	(zone
		(layer "In1.Cu")
		(hatch none 0.5)
		(connect_pads
			(clearance 0)
		)
		(min_thickness 0.25)
		(keepout
			(tracks not_allowed)
			(vias allowed)
			(pads allowed)
			(copperpour not_allowed)
			(footprints allowed)
		)
		(placement
			(enabled no)
			(sheetname "")
		)
		(fill
			(thermal_gap 0.5)
			(thermal_bridge_width 0.5)
			(island_removal_mode 0)
		)
		(polygon
			(pts
				(arc
					(start 285.485332 -268.132306)
					(mid 285.481612 -268.141286)
					(end 285.472632 -268.145006)
				)
				(arc
					(start 283.999432 -268.145006)
					(mid 283.990452 -268.141286)
					(end 283.986732 -268.132306)
				)
				(arc
					(start 283.986732 -267.637768)
					(mid 283.990452 -267.628788)
					(end 283.999432 -267.625068)
				)
				(arc
					(start 285.472632 -267.625068)
					(mid 285.481612 -267.628788)
					(end 285.485332 -267.637768)
				)
			)
		)
	)
	(zone
		(layer "In1.Cu")
		(hatch none 0.5)
		(connect_pads
			(clearance 0)
		)
		(min_thickness 0.25)
		(keepout
			(tracks not_allowed)
			(vias allowed)
			(pads allowed)
			(copperpour not_allowed)
			(footprints allowed)
		)
		(placement
			(enabled no)
			(sheetname "")
		)
		(fill
			(thermal_gap 0.5)
			(thermal_bridge_width 0.5)
			(island_removal_mode 0)
		)
		(polygon
			(pts
				(arc
					(start 30.001464 -283.432504)
					(mid 29.997744 -283.441484)
					(end 29.988764 -283.445204)
				)
				(arc
					(start 28.515564 -283.445204)
					(mid 28.506584 -283.441484)
					(end 28.502864 -283.432504)
				)
				(arc
					(start 28.502864 -282.937966)
					(mid 28.506584 -282.928986)
					(end 28.515564 -282.925266)
				)
				(arc
					(start 29.988764 -282.925266)
					(mid 29.997744 -282.928986)
					(end 30.001464 -282.937966)
				)
			)
		)
	)
	(zone
		(layer "In1.Cu")
		(hatch none 0.5)
		(connect_pads
			(clearance 0)
		)
		(min_thickness 0.25)
		(keepout
			(tracks not_allowed)
			(vias allowed)
			(pads allowed)
			(copperpour not_allowed)
			(footprints allowed)
		)
		(placement
			(enabled no)
			(sheetname "")
		)
		(fill
			(thermal_gap 0.5)
			(thermal_bridge_width 0.5)
			(island_removal_mode 0)
		)
		(polygon
			(pts
				(arc
					(start 184.365392 -216.282524)
					(mid 184.361672 -216.291504)
					(end 184.352692 -216.295224)
				)
				(arc
					(start 182.879492 -216.295224)
					(mid 182.870512 -216.291504)
					(end 182.866792 -216.282524)
				)
				(arc
					(start 182.866792 -215.787986)
					(mid 182.870512 -215.779006)
					(end 182.879492 -215.775286)
				)
				(arc
					(start 184.352692 -215.775286)
					(mid 184.361672 -215.779006)
					(end 184.365392 -215.787986)
				)
			)
		)
	)
	(zone
		(layer "In1.Cu")
		(hatch none 0.5)
		(connect_pads
			(clearance 0)
		)
		(min_thickness 0.25)
		(keepout
			(tracks not_allowed)
			(vias allowed)
			(pads allowed)
			(copperpour not_allowed)
			(footprints allowed)
		)
		(placement
			(enabled no)
			(sheetname "")
		)
		(fill
			(thermal_gap 0.5)
			(thermal_bridge_width 0.5)
			(island_removal_mode 0)
		)
		(polygon
			(pts
				(arc
					(start 159.488886 -386.003292)
					(mid 159.107886 -386.003292)
					(end 159.488886 -386.003292)
				)
			)
		)
	)
	(zone
		(layer "In1.Cu")
		(hatch none 0.5)
		(connect_pads
			(clearance 0)
		)
		(min_thickness 0.25)
		(keepout
			(tracks not_allowed)
			(vias allowed)
			(pads allowed)
			(copperpour not_allowed)
			(footprints allowed)
		)
		(placement
			(enabled no)
			(sheetname "")
		)
		(fill
			(thermal_gap 0.5)
			(thermal_bridge_width 0.5)
			(island_removal_mode 0)
		)
		(polygon
			(pts
				(arc
					(start 424.761406 -304.682144)
					(mid 424.757686 -304.691124)
					(end 424.748706 -304.694844)
				)
				(arc
					(start 423.275506 -304.694844)
					(mid 423.266526 -304.691124)
					(end 423.262806 -304.682144)
				)
				(arc
					(start 423.262806 -304.187606)
					(mid 423.266526 -304.178626)
					(end 423.275506 -304.174906)
				)
				(arc
					(start 424.748706 -304.174906)
					(mid 424.757686 -304.178626)
					(end 424.761406 -304.187606)
				)
			)
		)
	)
	(zone
		(layer "In1.Cu")
		(hatch none 0.5)
		(connect_pads
			(clearance 0)
		)
		(min_thickness 0.25)
		(keepout
			(tracks not_allowed)
			(vias allowed)
			(pads allowed)
			(copperpour not_allowed)
			(footprints allowed)
		)
		(placement
			(enabled no)
			(sheetname "")
		)
		(fill
			(thermal_gap 0.5)
			(thermal_bridge_width 0.5)
			(island_removal_mode 0)
		)
		(polygon
			(pts
				(arc
					(start 447.393568 -270.682212)
					(mid 447.389848 -270.691192)
					(end 447.380868 -270.694912)
				)
				(arc
					(start 445.907668 -270.694912)
					(mid 445.898688 -270.691192)
					(end 445.894968 -270.682212)
				)
				(arc
					(start 445.894968 -270.187674)
					(mid 445.898688 -270.178694)
					(end 445.907668 -270.174974)
				)
				(arc
					(start 447.380868 -270.174974)
					(mid 447.389848 -270.178694)
					(end 447.393568 -270.187674)
				)
			)
		)
	)
	(zone
		(layer "In1.Cu")
		(hatch none 0.5)
		(connect_pads
			(clearance 0)
		)
		(min_thickness 0.25)
		(keepout
			(tracks not_allowed)
			(vias allowed)
			(pads allowed)
			(copperpour not_allowed)
			(footprints allowed)
		)
		(placement
			(enabled no)
			(sheetname "")
		)
		(fill
			(thermal_gap 0.5)
			(thermal_bridge_width 0.5)
			(island_removal_mode 0)
		)
		(polygon
			(pts
				(arc
					(start 281.385264 -318.28232)
					(mid 281.381544 -318.2913)
					(end 281.372564 -318.29502)
				)
				(arc
					(start 279.899364 -318.29502)
					(mid 279.890384 -318.2913)
					(end 279.886664 -318.28232)
				)
				(arc
					(start 279.886664 -317.787782)
					(mid 279.890384 -317.778802)
					(end 279.899364 -317.775082)
				)
				(arc
					(start 281.372564 -317.775082)
					(mid 281.381544 -317.778802)
					(end 281.385264 -317.787782)
				)
			)
		)
	)
	(zone
		(layer "In1.Cu")
		(hatch none 0.5)
		(connect_pads
			(clearance 0)
		)
		(min_thickness 0.25)
		(keepout
			(tracks not_allowed)
			(vias allowed)
			(pads allowed)
			(copperpour not_allowed)
			(footprints allowed)
		)
		(placement
			(enabled no)
			(sheetname "")
		)
		(fill
			(thermal_gap 0.5)
			(thermal_bridge_width 0.5)
			(island_removal_mode 0)
		)
		(polygon
			(pts
				(arc
					(start 41.751504 -11.91768)
					(mid 41.729186 -11.971562)
					(end 41.675304 -11.99388)
				)
				(arc
					(start 40.63873 -11.99388)
					(mid 40.584848 -11.971562)
					(end 40.56253 -11.91768)
				)
				(arc
					(start 40.56253 -10.51814)
					(mid 40.584848 -10.464258)
					(end 40.63873 -10.44194)
				)
				(arc
					(start 41.675304 -10.44194)
					(mid 41.729186 -10.464258)
					(end 41.751504 -10.51814)
				)
			)
		)
	)
	(zone
		(layer "In1.Cu")
		(hatch none 0.5)
		(connect_pads
			(clearance 0)
		)
		(min_thickness 0.25)
		(keepout
			(tracks not_allowed)
			(vias allowed)
			(pads allowed)
			(copperpour not_allowed)
			(footprints allowed)
		)
		(placement
			(enabled no)
			(sheetname "")
		)
		(fill
			(thermal_gap 0.5)
			(thermal_bridge_width 0.5)
			(island_removal_mode 0)
		)
		(polygon
			(pts
				(arc
					(start 22.45741 -247.73255)
					(mid 22.45369 -247.74153)
					(end 22.44471 -247.74525)
				)
				(arc
					(start 20.97151 -247.74525)
					(mid 20.96253 -247.74153)
					(end 20.95881 -247.73255)
				)
				(arc
					(start 20.95881 -247.238012)
					(mid 20.96253 -247.229032)
					(end 20.97151 -247.225312)
				)
				(arc
					(start 22.44471 -247.225312)
					(mid 22.45369 -247.229032)
					(end 22.45741 -247.238012)
				)
			)
		)
	)
	(zone
		(layer "In1.Cu")
		(hatch none 0.5)
		(connect_pads
			(clearance 0)
		)
		(min_thickness 0.25)
		(keepout
			(tracks not_allowed)
			(vias allowed)
			(pads allowed)
			(copperpour not_allowed)
			(footprints allowed)
		)
		(placement
			(enabled no)
			(sheetname "")
		)
		(fill
			(thermal_gap 0.5)
			(thermal_bridge_width 0.5)
			(island_removal_mode 0)
		)
		(polygon
			(pts
				(arc
					(start 435.749446 -276.632162)
					(mid 435.745726 -276.641142)
					(end 435.736746 -276.644862)
				)
				(arc
					(start 434.263546 -276.644862)
					(mid 434.254566 -276.641142)
					(end 434.250846 -276.632162)
				)
				(arc
					(start 434.250846 -276.137624)
					(mid 434.254566 -276.128644)
					(end 434.263546 -276.124924)
				)
				(arc
					(start 435.736746 -276.124924)
					(mid 435.745726 -276.128644)
					(end 435.749446 -276.137624)
				)
			)
		)
	)
	(zone
		(layer "In1.Cu")
		(hatch none 0.5)
		(connect_pads
			(clearance 0)
		)
		(min_thickness 0.25)
		(keepout
			(tracks not_allowed)
			(vias allowed)
			(pads allowed)
			(copperpour not_allowed)
			(footprints allowed)
		)
		(placement
			(enabled no)
			(sheetname "")
		)
		(fill
			(thermal_gap 0.5)
			(thermal_bridge_width 0.5)
			(island_removal_mode 0)
		)
		(polygon
			(pts
				(arc
					(start 304.017426 -307.232304)
					(mid 304.013706 -307.241284)
					(end 304.004726 -307.245004)
				)
				(arc
					(start 302.531526 -307.245004)
					(mid 302.522546 -307.241284)
					(end 302.518826 -307.232304)
				)
				(arc
					(start 302.518826 -306.737766)
					(mid 302.522546 -306.728786)
					(end 302.531526 -306.725066)
				)
				(arc
					(start 304.004726 -306.725066)
					(mid 304.013706 -306.728786)
					(end 304.017426 -306.737766)
				)
			)
		)
	)
	(zone
		(layer "In1.Cu")
		(hatch none 0.5)
		(connect_pads
			(clearance 0)
		)
		(min_thickness 0.25)
		(keepout
			(tracks not_allowed)
			(vias allowed)
			(pads allowed)
			(copperpour not_allowed)
			(footprints allowed)
		)
		(placement
			(enabled no)
			(sheetname "")
		)
		(fill
			(thermal_gap 0.5)
			(thermal_bridge_width 0.5)
			(island_removal_mode 0)
		)
		(polygon
			(pts
				(arc
					(start 413.117284 -299.582332)
					(mid 413.113564 -299.591312)
					(end 413.104584 -299.595032)
				)
				(arc
					(start 411.631384 -299.595032)
					(mid 411.622404 -299.591312)
					(end 411.618684 -299.582332)
				)
				(arc
					(start 411.618684 -299.087794)
					(mid 411.622404 -299.078814)
					(end 411.631384 -299.075094)
				)
				(arc
					(start 413.104584 -299.075094)
					(mid 413.113564 -299.078814)
					(end 413.117284 -299.087794)
				)
			)
		)
	)
	(zone
		(layer "In1.Cu")
		(hatch none 0.5)
		(connect_pads
			(clearance 0)
		)
		(min_thickness 0.25)
		(keepout
			(tracks not_allowed)
			(vias allowed)
			(pads allowed)
			(copperpour not_allowed)
			(footprints allowed)
		)
		(placement
			(enabled no)
			(sheetname "")
		)
		(fill
			(thermal_gap 0.5)
			(thermal_bridge_width 0.5)
			(island_removal_mode 0)
		)
		(polygon
			(pts
				(arc
					(start 321.570096 -392.30427)
					(mid 321.265296 -392.30427)
					(end 321.570096 -392.30427)
				)
			)
		)
	)
	(zone
		(layer "In1.Cu")
		(hatch none 0.5)
		(connect_pads
			(clearance 0)
		)
		(min_thickness 0.25)
		(keepout
			(tracks not_allowed)
			(vias allowed)
			(pads allowed)
			(copperpour not_allowed)
			(footprints allowed)
		)
		(placement
			(enabled no)
			(sheetname "")
		)
		(fill
			(thermal_gap 0.5)
			(thermal_bridge_width 0.5)
			(island_removal_mode 0)
		)
		(polygon
			(pts
				(arc
					(start 432.30546 -313.182254)
					(mid 432.30174 -313.191234)
					(end 432.29276 -313.194954)
				)
				(arc
					(start 430.81956 -313.194954)
					(mid 430.81058 -313.191234)
					(end 430.80686 -313.182254)
				)
				(arc
					(start 430.80686 -312.687716)
					(mid 430.81058 -312.678736)
					(end 430.81956 -312.675016)
				)
				(arc
					(start 432.29276 -312.675016)
					(mid 432.30174 -312.678736)
					(end 432.30546 -312.687716)
				)
			)
		)
	)
	(zone
		(layer "In1.Cu")
		(hatch none 0.5)
		(connect_pads
			(clearance 0)
		)
		(min_thickness 0.25)
		(keepout
			(tracks not_allowed)
			(vias allowed)
			(pads allowed)
			(copperpour not_allowed)
			(footprints allowed)
		)
		(placement
			(enabled no)
			(sheetname "")
		)
		(fill
			(thermal_gap 0.5)
			(thermal_bridge_width 0.5)
			(island_removal_mode 0)
		)
		(polygon
			(pts
				(arc
					(start 202.897232 -243.482368)
					(mid 202.893512 -243.491348)
					(end 202.884532 -243.495068)
				)
				(arc
					(start 201.411332 -243.495068)
					(mid 201.402352 -243.491348)
					(end 201.398632 -243.482368)
				)
				(arc
					(start 201.398632 -242.98783)
					(mid 201.402352 -242.97885)
					(end 201.411332 -242.97513)
				)
				(arc
					(start 202.884532 -242.97513)
					(mid 202.893512 -242.97885)
					(end 202.897232 -242.98783)
				)
			)
		)
	)
	(zone
		(layer "In1.Cu")
		(hatch none 0.5)
		(connect_pads
			(clearance 0)
		)
		(min_thickness 0.25)
		(keepout
			(tracks not_allowed)
			(vias allowed)
			(pads allowed)
			(copperpour not_allowed)
			(footprints allowed)
		)
		(placement
			(enabled no)
			(sheetname "")
		)
		(fill
			(thermal_gap 0.5)
			(thermal_bridge_width 0.5)
			(island_removal_mode 0)
		)
		(polygon
			(pts
				(arc
					(start 88.388952 -385.31038)
					(mid 88.007952 -385.31038)
					(end 88.388952 -385.31038)
				)
			)
		)
	)
	(zone
		(layer "In1.Cu")
		(hatch none 0.5)
		(connect_pads
			(clearance 0)
		)
		(min_thickness 0.25)
		(keepout
			(tracks not_allowed)
			(vias allowed)
			(pads allowed)
			(copperpour not_allowed)
			(footprints allowed)
		)
		(placement
			(enabled no)
			(sheetname "")
		)
		(fill
			(thermal_gap 0.5)
			(thermal_bridge_width 0.5)
			(island_removal_mode 0)
		)
		(polygon
			(pts
				(arc
					(start 270.397478 -313.182254)
					(mid 270.393758 -313.191234)
					(end 270.384778 -313.194954)
				)
				(arc
					(start 268.911578 -313.194954)
					(mid 268.902598 -313.191234)
					(end 268.898878 -313.182254)
				)
				(arc
					(start 268.898878 -312.687716)
					(mid 268.902598 -312.678736)
					(end 268.911578 -312.675016)
				)
				(arc
					(start 270.384778 -312.675016)
					(mid 270.393758 -312.678736)
					(end 270.397478 -312.687716)
				)
			)
		)
	)
	(zone
		(layer "In1.Cu")
		(hatch none 0.5)
		(connect_pads
			(clearance 0)
		)
		(min_thickness 0.25)
		(keepout
			(tracks not_allowed)
			(vias allowed)
			(pads allowed)
			(copperpour not_allowed)
			(footprints allowed)
		)
		(placement
			(enabled no)
			(sheetname "")
		)
		(fill
			(thermal_gap 0.5)
			(thermal_bridge_width 0.5)
			(island_removal_mode 0)
		)
		(polygon
			(pts
				(arc
					(start 307.061108 -397.156432)
					(mid 306.680108 -397.156432)
					(end 307.061108 -397.156432)
				)
			)
		)
	)
	(zone
		(layer "In1.Cu")
		(hatch none 0.5)
		(connect_pads
			(clearance 0)
		)
		(min_thickness 0.25)
		(keepout
			(tracks not_allowed)
			(vias allowed)
			(pads allowed)
			(copperpour not_allowed)
			(footprints allowed)
		)
		(placement
			(enabled no)
			(sheetname "")
		)
		(fill
			(thermal_gap 0.5)
			(thermal_bridge_width 0.5)
			(island_removal_mode 0)
		)
		(polygon
			(pts
				(arc
					(start 296.473372 -274.93214)
					(mid 296.469652 -274.94112)
					(end 296.460672 -274.94484)
				)
				(arc
					(start 294.987472 -274.94484)
					(mid 294.978492 -274.94112)
					(end 294.974772 -274.93214)
				)
				(arc
					(start 294.974772 -274.437602)
					(mid 294.978492 -274.428622)
					(end 294.987472 -274.424902)
				)
				(arc
					(start 296.460672 -274.424902)
					(mid 296.469652 -274.428622)
					(end 296.473372 -274.437602)
				)
			)
		)
	)
	(zone
		(layer "In1.Cu")
		(hatch none 0.5)
		(connect_pads
			(clearance 0)
		)
		(min_thickness 0.25)
		(keepout
			(tracks not_allowed)
			(vias allowed)
			(pads allowed)
			(copperpour not_allowed)
			(footprints allowed)
		)
		(placement
			(enabled no)
			(sheetname "")
		)
		(fill
			(thermal_gap 0.5)
			(thermal_bridge_width 0.5)
			(island_removal_mode 0)
		)
		(polygon
			(pts
				(arc
					(start 277.941532 -242.63223)
					(mid 277.937812 -242.64121)
					(end 277.928832 -242.64493)
				)
				(arc
					(start 276.455632 -242.64493)
					(mid 276.446652 -242.64121)
					(end 276.442932 -242.63223)
				)
				(arc
					(start 276.442932 -242.137692)
					(mid 276.446652 -242.128712)
					(end 276.455632 -242.124992)
				)
				(arc
					(start 277.928832 -242.124992)
					(mid 277.937812 -242.128712)
					(end 277.941532 -242.137692)
				)
			)
		)
	)
	(zone
		(layer "In1.Cu")
		(hatch none 0.5)
		(connect_pads
			(clearance 0)
		)
		(min_thickness 0.25)
		(keepout
			(tracks not_allowed)
			(vias allowed)
			(pads allowed)
			(copperpour not_allowed)
			(footprints allowed)
		)
		(placement
			(enabled no)
			(sheetname "")
		)
		(fill
			(thermal_gap 0.5)
			(thermal_bridge_width 0.5)
			(island_removal_mode 0)
		)
		(polygon
			(pts
				(arc
					(start 296.473372 -267.282168)
					(mid 296.469652 -267.291148)
					(end 296.460672 -267.294868)
				)
				(arc
					(start 294.987472 -267.294868)
					(mid 294.978492 -267.291148)
					(end 294.974772 -267.282168)
				)
				(arc
					(start 294.974772 -266.78763)
					(mid 294.978492 -266.77865)
					(end 294.987472 -266.77493)
				)
				(arc
					(start 296.460672 -266.77493)
					(mid 296.469652 -266.77865)
					(end 296.473372 -266.78763)
				)
			)
		)
	)
	(zone
		(layer "In1.Cu")
		(hatch none 0.5)
		(connect_pads
			(clearance 0)
		)
		(min_thickness 0.25)
		(keepout
			(tracks not_allowed)
			(vias allowed)
			(pads allowed)
			(copperpour not_allowed)
			(footprints allowed)
		)
		(placement
			(enabled no)
			(sheetname "")
		)
		(fill
			(thermal_gap 0.5)
			(thermal_bridge_width 0.5)
			(island_removal_mode 0)
		)
		(polygon
			(pts
				(arc
					(start 212.820504 5.633974)
					(mid 212.842822 5.687856)
					(end 212.896704 5.710174)
				)
				(arc
					(start 213.508844 5.710174)
					(mid 213.562726 5.687856)
					(end 213.585044 5.633974)
				)
				(arc
					(start 213.585044 4.536694)
					(mid 213.562726 4.482812)
					(end 213.508844 4.460494)
				)
				(arc
					(start 212.896704 4.460494)
					(mid 212.842822 4.482812)
					(end 212.820504 4.536694)
				)
			)
		)
	)
	(zone
		(layer "In1.Cu")
		(hatch none 0.5)
		(connect_pads
			(clearance 0)
		)
		(min_thickness 0.25)
		(keepout
			(tracks not_allowed)
			(vias allowed)
			(pads allowed)
			(copperpour not_allowed)
			(footprints allowed)
		)
		(placement
			(enabled no)
			(sheetname "")
		)
		(fill
			(thermal_gap 0.5)
			(thermal_bridge_width 0.5)
			(island_removal_mode 0)
		)
		(polygon
			(pts
				(arc
					(start 317.860934 -397.156432)
					(mid 317.479934 -397.156432)
					(end 317.860934 -397.156432)
				)
			)
		)
	)
	(zone
		(layer "In1.Cu")
		(hatch none 0.5)
		(connect_pads
			(clearance 0)
		)
		(min_thickness 0.25)
		(keepout
			(tracks not_allowed)
			(vias allowed)
			(pads allowed)
			(copperpour not_allowed)
			(footprints allowed)
		)
		(placement
			(enabled no)
			(sheetname "")
		)
		(fill
			(thermal_gap 0.5)
			(thermal_bridge_width 0.5)
			(island_removal_mode 0)
		)
		(polygon
			(pts
				(arc
					(start 450.8373 -237.532164)
					(mid 450.83358 -237.541144)
					(end 450.8246 -237.544864)
				)
				(arc
					(start 449.3514 -237.544864)
					(mid 449.34242 -237.541144)
					(end 449.3387 -237.532164)
				)
				(arc
					(start 449.3387 -237.037626)
					(mid 449.34242 -237.028646)
					(end 449.3514 -237.024926)
				)
				(arc
					(start 450.8246 -237.024926)
					(mid 450.83358 -237.028646)
					(end 450.8373 -237.037626)
				)
			)
		)
	)
	(zone
		(layer "In1.Cu")
		(hatch none 0.5)
		(connect_pads
			(clearance 0)
		)
		(min_thickness 0.25)
		(keepout
			(tracks not_allowed)
			(vias allowed)
			(pads allowed)
			(copperpour not_allowed)
			(footprints allowed)
		)
		(placement
			(enabled no)
			(sheetname "")
		)
		(fill
			(thermal_gap 0.5)
			(thermal_bridge_width 0.5)
			(island_removal_mode 0)
		)
		(polygon
			(pts
				(arc
					(start 52.633372 -254.532384)
					(mid 52.629652 -254.541364)
					(end 52.620672 -254.545084)
				)
				(arc
					(start 51.147472 -254.545084)
					(mid 51.138492 -254.541364)
					(end 51.134772 -254.532384)
				)
				(arc
					(start 51.134772 -254.037846)
					(mid 51.138492 -254.028866)
					(end 51.147472 -254.025146)
				)
				(arc
					(start 52.620672 -254.025146)
					(mid 52.629652 -254.028866)
					(end 52.633372 -254.037846)
				)
			)
		)
	)
	(zone
		(layer "In1.Cu")
		(hatch none 0.5)
		(connect_pads
			(clearance 0)
		)
		(min_thickness 0.25)
		(keepout
			(tracks not_allowed)
			(vias allowed)
			(pads allowed)
			(copperpour not_allowed)
			(footprints allowed)
		)
		(placement
			(enabled no)
			(sheetname "")
		)
		(fill
			(thermal_gap 0.5)
			(thermal_bridge_width 0.5)
			(island_removal_mode 0)
		)
		(polygon
			(pts
				(arc
					(start 303.570132 -399.143474)
					(mid 303.265332 -399.143474)
					(end 303.570132 -399.143474)
				)
			)
		)
	)
	(zone
		(layer "In1.Cu")
		(hatch none 0.5)
		(connect_pads
			(clearance 0)
		)
		(min_thickness 0.25)
		(keepout
			(tracks not_allowed)
			(vias allowed)
			(pads allowed)
			(copperpour not_allowed)
			(footprints allowed)
		)
		(placement
			(enabled no)
			(sheetname "")
		)
		(fill
			(thermal_gap 0.5)
			(thermal_bridge_width 0.5)
			(island_removal_mode 0)
		)
		(polygon
			(pts
				(arc
					(start 25.901396 -228.182424)
					(mid 25.897676 -228.191404)
					(end 25.888696 -228.195124)
				)
				(arc
					(start 24.415496 -228.195124)
					(mid 24.406516 -228.191404)
					(end 24.402796 -228.182424)
				)
				(arc
					(start 24.402796 -227.687886)
					(mid 24.406516 -227.678906)
					(end 24.415496 -227.675186)
				)
				(arc
					(start 25.888696 -227.675186)
					(mid 25.897676 -227.678906)
					(end 25.901396 -227.687886)
				)
			)
		)
	)
	(zone
		(layer "In1.Cu")
		(hatch none 0.5)
		(connect_pads
			(clearance 0)
		)
		(min_thickness 0.25)
		(keepout
			(tracks not_allowed)
			(vias allowed)
			(pads allowed)
			(copperpour not_allowed)
			(footprints allowed)
		)
		(placement
			(enabled no)
			(sheetname "")
		)
		(fill
			(thermal_gap 0.5)
			(thermal_bridge_width 0.5)
			(island_removal_mode 0)
		)
		(polygon
			(pts
				(arc
					(start 273.841464 -290.232338)
					(mid 273.837744 -290.241318)
					(end 273.828764 -290.245038)
				)
				(arc
					(start 272.355564 -290.245038)
					(mid 272.346584 -290.241318)
					(end 272.342864 -290.232338)
				)
				(arc
					(start 272.342864 -289.7378)
					(mid 272.346584 -289.72882)
					(end 272.355564 -289.7251)
				)
				(arc
					(start 273.828764 -289.7251)
					(mid 273.837744 -289.72882)
					(end 273.841464 -289.7378)
				)
			)
		)
	)
	(zone
		(layer "In1.Cu")
		(hatch none 0.5)
		(connect_pads
			(clearance 0)
		)
		(min_thickness 0.25)
		(keepout
			(tracks not_allowed)
			(vias allowed)
			(pads allowed)
			(copperpour not_allowed)
			(footprints allowed)
		)
		(placement
			(enabled no)
			(sheetname "")
		)
		(fill
			(thermal_gap 0.5)
			(thermal_bridge_width 0.5)
			(island_removal_mode 0)
		)
		(polygon
			(pts
				(arc
					(start 165.177216 -265.5824)
					(mid 165.173496 -265.59138)
					(end 165.164516 -265.5951)
				)
				(arc
					(start 163.691316 -265.5951)
					(mid 163.682336 -265.59138)
					(end 163.678616 -265.5824)
				)
				(arc
					(start 163.678616 -265.087862)
					(mid 163.682336 -265.078882)
					(end 163.691316 -265.075162)
				)
				(arc
					(start 165.164516 -265.075162)
					(mid 165.173496 -265.078882)
					(end 165.177216 -265.087862)
				)
			)
		)
	)
	(zone
		(layer "In1.Cu")
		(hatch none 0.5)
		(connect_pads
			(clearance 0)
		)
		(min_thickness 0.25)
		(keepout
			(tracks not_allowed)
			(vias allowed)
			(pads allowed)
			(copperpour not_allowed)
			(footprints allowed)
		)
		(placement
			(enabled no)
			(sheetname "")
		)
		(fill
			(thermal_gap 0.5)
			(thermal_bridge_width 0.5)
			(island_removal_mode 0)
		)
		(polygon
			(pts
				(arc
					(start 424.761406 -217.982292)
					(mid 424.757686 -217.991272)
					(end 424.748706 -217.994992)
				)
				(arc
					(start 423.275506 -217.994992)
					(mid 423.266526 -217.991272)
					(end 423.262806 -217.982292)
				)
				(arc
					(start 423.262806 -217.487754)
					(mid 423.266526 -217.478774)
					(end 423.275506 -217.475054)
				)
				(arc
					(start 424.748706 -217.475054)
					(mid 424.757686 -217.478774)
					(end 424.761406 -217.487754)
				)
			)
		)
	)
	(zone
		(layer "In1.Cu")
		(hatch none 0.5)
		(connect_pads
			(clearance 0)
		)
		(min_thickness 0.25)
		(keepout
			(tracks not_allowed)
			(vias allowed)
			(pads allowed)
			(copperpour not_allowed)
			(footprints allowed)
		)
		(placement
			(enabled no)
			(sheetname "")
		)
		(fill
			(thermal_gap 0.5)
			(thermal_bridge_width 0.5)
			(island_removal_mode 0)
		)
		(polygon
			(pts
				(arc
					(start 420.661338 -211.182204)
					(mid 420.657618 -211.191184)
					(end 420.648638 -211.194904)
				)
				(arc
					(start 419.175438 -211.194904)
					(mid 419.166458 -211.191184)
					(end 419.162738 -211.182204)
				)
				(arc
					(start 419.162738 -210.687666)
					(mid 419.166458 -210.678686)
					(end 419.175438 -210.674966)
				)
				(arc
					(start 420.648638 -210.674966)
					(mid 420.657618 -210.678686)
					(end 420.661338 -210.687666)
				)
			)
		)
	)
	(zone
		(layer "In1.Cu")
		(hatch none 0.5)
		(connect_pads
			(clearance 0)
		)
		(min_thickness 0.25)
		(keepout
			(tracks not_allowed)
			(vias allowed)
			(pads allowed)
			(copperpour not_allowed)
			(footprints allowed)
		)
		(placement
			(enabled no)
			(sheetname "")
		)
		(fill
			(thermal_gap 0.5)
			(thermal_bridge_width 0.5)
			(island_removal_mode 0)
		)
		(polygon
			(pts
				(arc
					(start 417.598098 -399.143474)
					(mid 417.293298 -399.143474)
					(end 417.598098 -399.143474)
				)
			)
		)
	)
	(zone
		(layer "In1.Cu")
		(hatch none 0.5)
		(connect_pads
			(clearance 0)
		)
		(min_thickness 0.25)
		(keepout
			(tracks not_allowed)
			(vias allowed)
			(pads allowed)
			(copperpour not_allowed)
			(footprints allowed)
		)
		(placement
			(enabled no)
			(sheetname "")
		)
		(fill
			(thermal_gap 0.5)
			(thermal_bridge_width 0.5)
			(island_removal_mode 0)
		)
		(polygon
			(pts
				(arc
					(start 157.418786 -383.440686)
					(mid 157.545786 -383.567686)
					(end 157.672786 -383.440686)
				)
				(arc
					(start 157.672786 -383.364486)
					(mid 157.545786 -383.237486)
					(end 157.418786 -383.364486)
				)
			)
		)
	)
	(zone
		(layer "In1.Cu")
		(hatch none 0.5)
		(connect_pads
			(clearance 0)
		)
		(min_thickness 0.25)
		(keepout
			(tracks not_allowed)
			(vias allowed)
			(pads allowed)
			(copperpour not_allowed)
			(footprints allowed)
		)
		(placement
			(enabled no)
			(sheetname "")
		)
		(fill
			(thermal_gap 0.5)
			(thermal_bridge_width 0.5)
			(island_removal_mode 0)
		)
		(polygon
			(pts
				(arc
					(start 150.218648 -383.440686)
					(mid 150.345648 -383.567686)
					(end 150.472648 -383.440686)
				)
				(arc
					(start 150.472648 -383.364486)
					(mid 150.345648 -383.237486)
					(end 150.218648 -383.364486)
				)
			)
		)
	)
	(zone
		(layer "In1.Cu")
		(hatch none 0.5)
		(connect_pads
			(clearance 0)
		)
		(min_thickness 0.25)
		(keepout
			(tracks not_allowed)
			(vias allowed)
			(pads allowed)
			(copperpour not_allowed)
			(footprints allowed)
		)
		(placement
			(enabled no)
			(sheetname "")
		)
		(fill
			(thermal_gap 0.5)
			(thermal_bridge_width 0.5)
			(island_removal_mode 0)
		)
		(polygon
			(pts
				(arc
					(start 52.633372 -302.132492)
					(mid 52.629652 -302.141472)
					(end 52.620672 -302.145192)
				)
				(arc
					(start 51.147472 -302.145192)
					(mid 51.138492 -302.141472)
					(end 51.134772 -302.132492)
				)
				(arc
					(start 51.134772 -301.637954)
					(mid 51.138492 -301.628974)
					(end 51.147472 -301.625254)
				)
				(arc
					(start 52.620672 -301.625254)
					(mid 52.629652 -301.628974)
					(end 52.633372 -301.637954)
				)
			)
		)
	)
	(zone
		(layer "In1.Cu")
		(hatch none 0.5)
		(connect_pads
			(clearance 0)
		)
		(min_thickness 0.25)
		(keepout
			(tracks not_allowed)
			(vias allowed)
			(pads allowed)
			(copperpour not_allowed)
			(footprints allowed)
		)
		(placement
			(enabled no)
			(sheetname "")
		)
		(fill
			(thermal_gap 0.5)
			(thermal_bridge_width 0.5)
			(island_removal_mode 0)
		)
		(polygon
			(pts
				(arc
					(start 180.265324 -302.982376)
					(mid 180.261604 -302.991356)
					(end 180.252624 -302.995076)
				)
				(arc
					(start 178.779424 -302.995076)
					(mid 178.770444 -302.991356)
					(end 178.766724 -302.982376)
				)
				(arc
					(start 178.766724 -302.487838)
					(mid 178.770444 -302.478858)
					(end 178.779424 -302.475138)
				)
				(arc
					(start 180.252624 -302.475138)
					(mid 180.261604 -302.478858)
					(end 180.265324 -302.487838)
				)
			)
		)
	)
	(zone
		(layer "In1.Cu")
		(hatch none 0.5)
		(connect_pads
			(clearance 0)
		)
		(min_thickness 0.25)
		(keepout
			(tracks not_allowed)
			(vias allowed)
			(pads allowed)
			(copperpour not_allowed)
			(footprints allowed)
		)
		(placement
			(enabled no)
			(sheetname "")
		)
		(fill
			(thermal_gap 0.5)
			(thermal_bridge_width 0.5)
			(island_removal_mode 0)
		)
		(polygon
			(pts
				(arc
					(start 191.909446 -247.73255)
					(mid 191.905726 -247.74153)
					(end 191.896746 -247.74525)
				)
				(arc
					(start 190.423546 -247.74525)
					(mid 190.414566 -247.74153)
					(end 190.410846 -247.73255)
				)
				(arc
					(start 190.410846 -247.238012)
					(mid 190.414566 -247.229032)
					(end 190.423546 -247.225312)
				)
				(arc
					(start 191.896746 -247.225312)
					(mid 191.905726 -247.229032)
					(end 191.909446 -247.238012)
				)
			)
		)
	)
	(zone
		(layer "In1.Cu")
		(hatch none 0.5)
		(connect_pads
			(clearance 0)
		)
		(min_thickness 0.25)
		(keepout
			(tracks not_allowed)
			(vias allowed)
			(pads allowed)
			(copperpour not_allowed)
			(footprints allowed)
		)
		(placement
			(enabled no)
			(sheetname "")
		)
		(fill
			(thermal_gap 0.5)
			(thermal_bridge_width 0.5)
			(island_removal_mode 0)
		)
		(polygon
			(pts
				(arc
					(start 285.485332 -234.982258)
					(mid 285.481612 -234.991238)
					(end 285.472632 -234.994958)
				)
				(arc
					(start 283.999432 -234.994958)
					(mid 283.990452 -234.991238)
					(end 283.986732 -234.982258)
				)
				(arc
					(start 283.986732 -234.48772)
					(mid 283.990452 -234.47874)
					(end 283.999432 -234.47502)
				)
				(arc
					(start 285.472632 -234.47502)
					(mid 285.481612 -234.47874)
					(end 285.485332 -234.48772)
				)
			)
		)
	)
	(zone
		(layer "In1.Cu")
		(hatch none 0.5)
		(connect_pads
			(clearance 0)
		)
		(min_thickness 0.25)
		(keepout
			(tracks not_allowed)
			(vias allowed)
			(pads allowed)
			(copperpour not_allowed)
			(footprints allowed)
		)
		(placement
			(enabled no)
			(sheetname "")
		)
		(fill
			(thermal_gap 0.5)
			(thermal_bridge_width 0.5)
			(island_removal_mode 0)
		)
		(polygon
			(pts
				(arc
					(start 128.161034 -386.003292)
					(mid 127.780034 -386.003292)
					(end 128.161034 -386.003292)
				)
			)
		)
	)
	(zone
		(layer "In1.Cu")
		(hatch none 0.5)
		(connect_pads
			(clearance 0)
		)
		(min_thickness 0.25)
		(keepout
			(tracks not_allowed)
			(vias allowed)
			(pads allowed)
			(copperpour not_allowed)
			(footprints allowed)
		)
		(placement
			(enabled no)
			(sheetname "")
		)
		(fill
			(thermal_gap 0.5)
			(thermal_bridge_width 0.5)
			(island_removal_mode 0)
		)
		(polygon
			(pts
				(arc
					(start 312.260742 -397.849344)
					(mid 311.879742 -397.849344)
					(end 312.260742 -397.849344)
				)
			)
		)
	)
	(zone
		(layer "In1.Cu")
		(hatch none 0.5)
		(connect_pads
			(clearance 0)
		)
		(min_thickness 0.25)
		(keepout
			(tracks not_allowed)
			(vias allowed)
			(pads allowed)
			(copperpour not_allowed)
			(footprints allowed)
		)
		(placement
			(enabled no)
			(sheetname "")
		)
		(fill
			(thermal_gap 0.5)
			(thermal_bridge_width 0.5)
			(island_removal_mode 0)
		)
		(polygon
			(pts
				(arc
					(start 266.29741 -312.332116)
					(mid 266.29369 -312.341096)
					(end 266.28471 -312.344816)
				)
				(arc
					(start 264.81151 -312.344816)
					(mid 264.80253 -312.341096)
					(end 264.79881 -312.332116)
				)
				(arc
					(start 264.79881 -311.837578)
					(mid 264.80253 -311.828598)
					(end 264.81151 -311.824878)
				)
				(arc
					(start 266.28471 -311.824878)
					(mid 266.29369 -311.828598)
					(end 266.29741 -311.837578)
				)
			)
		)
	)
	(zone
		(layer "In1.Cu")
		(hatch none 0.5)
		(connect_pads
			(clearance 0)
		)
		(min_thickness 0.25)
		(keepout
			(tracks not_allowed)
			(vias allowed)
			(pads allowed)
			(copperpour not_allowed)
			(footprints allowed)
		)
		(placement
			(enabled no)
			(sheetname "")
		)
		(fill
			(thermal_gap 0.5)
			(thermal_bridge_width 0.5)
			(island_removal_mode 0)
		)
		(polygon
			(pts
				(arc
					(start 304.017426 -241.782092)
					(mid 304.013706 -241.791072)
					(end 304.004726 -241.794792)
				)
				(arc
					(start 302.531526 -241.794792)
					(mid 302.522546 -241.791072)
					(end 302.518826 -241.782092)
				)
				(arc
					(start 302.518826 -241.287554)
					(mid 302.522546 -241.278574)
					(end 302.531526 -241.274854)
				)
				(arc
					(start 304.004726 -241.274854)
					(mid 304.013706 -241.278574)
					(end 304.017426 -241.287554)
				)
			)
		)
	)
	(zone
		(layer "In1.Cu")
		(hatch none 0.5)
		(connect_pads
			(clearance 0)
		)
		(min_thickness 0.25)
		(keepout
			(tracks not_allowed)
			(vias allowed)
			(pads allowed)
			(copperpour not_allowed)
			(footprints allowed)
		)
		(placement
			(enabled no)
			(sheetname "")
		)
		(fill
			(thermal_gap 0.5)
			(thermal_bridge_width 0.5)
			(island_removal_mode 0)
		)
		(polygon
			(pts
				(arc
					(start 206.5782 -199.035416)
					(mid 205.9178 -199.035416)
					(end 206.5782 -199.035416)
				)
			)
		)
	)
	(zone
		(layer "In1.Cu")
		(hatch none 0.5)
		(connect_pads
			(clearance 0)
		)
		(min_thickness 0.25)
		(keepout
			(tracks not_allowed)
			(vias allowed)
			(pads allowed)
			(copperpour not_allowed)
			(footprints allowed)
		)
		(placement
			(enabled no)
			(sheetname "")
		)
		(fill
			(thermal_gap 0.5)
			(thermal_bridge_width 0.5)
			(island_removal_mode 0)
		)
		(polygon
			(pts
				(arc
					(start 48.533304 -280.882344)
					(mid 48.529584 -280.891324)
					(end 48.520604 -280.895044)
				)
				(arc
					(start 47.047404 -280.895044)
					(mid 47.038424 -280.891324)
					(end 47.034704 -280.882344)
				)
				(arc
					(start 47.034704 -280.387806)
					(mid 47.038424 -280.378826)
					(end 47.047404 -280.375106)
				)
				(arc
					(start 48.520604 -280.375106)
					(mid 48.529584 -280.378826)
					(end 48.533304 -280.387806)
				)
			)
		)
	)
	(zone
		(layer "In1.Cu")
		(hatch none 0.5)
		(connect_pads
			(clearance 0)
		)
		(min_thickness 0.25)
		(keepout
			(tracks not_allowed)
			(vias allowed)
			(pads allowed)
			(copperpour not_allowed)
			(footprints allowed)
		)
		(placement
			(enabled no)
			(sheetname "")
		)
		(fill
			(thermal_gap 0.5)
			(thermal_bridge_width 0.5)
			(island_removal_mode 0)
		)
		(polygon
			(pts
				(arc
					(start 62.590934 -383.440686)
					(mid 62.717934 -383.567686)
					(end 62.844934 -383.440686)
				)
				(arc
					(start 62.844934 -383.364486)
					(mid 62.717934 -383.237486)
					(end 62.590934 -383.364486)
				)
			)
		)
	)
	(zone
		(layer "In1.Cu")
		(hatch none 0.5)
		(connect_pads
			(clearance 0)
		)
		(min_thickness 0.25)
		(keepout
			(tracks not_allowed)
			(vias allowed)
			(pads allowed)
			(copperpour not_allowed)
			(footprints allowed)
		)
		(placement
			(enabled no)
			(sheetname "")
		)
		(fill
			(thermal_gap 0.5)
			(thermal_bridge_width 0.5)
			(island_removal_mode 0)
		)
		(polygon
			(pts
				(arc
					(start 273.841464 -314.882276)
					(mid 273.837744 -314.891256)
					(end 273.828764 -314.894976)
				)
				(arc
					(start 272.355564 -314.894976)
					(mid 272.346584 -314.891256)
					(end 272.342864 -314.882276)
				)
				(arc
					(start 272.342864 -314.387738)
					(mid 272.346584 -314.378758)
					(end 272.355564 -314.375038)
				)
				(arc
					(start 273.828764 -314.375038)
					(mid 273.837744 -314.378758)
					(end 273.841464 -314.387738)
				)
			)
		)
	)
	(zone
		(layer "In1.Cu")
		(hatch none 0.5)
		(connect_pads
			(clearance 0)
		)
		(min_thickness 0.25)
		(keepout
			(tracks not_allowed)
			(vias allowed)
			(pads allowed)
			(copperpour not_allowed)
			(footprints allowed)
		)
		(placement
			(enabled no)
			(sheetname "")
		)
		(fill
			(thermal_gap 0.5)
			(thermal_bridge_width 0.5)
			(island_removal_mode 0)
		)
		(polygon
			(pts
				(arc
					(start 435.749446 -200.132188)
					(mid 435.745726 -200.141168)
					(end 435.736746 -200.144888)
				)
				(arc
					(start 434.263546 -200.144888)
					(mid 434.254566 -200.141168)
					(end 434.250846 -200.132188)
				)
				(arc
					(start 434.250846 -199.63765)
					(mid 434.254566 -199.62867)
					(end 434.263546 -199.62495)
				)
				(arc
					(start 435.736746 -199.62495)
					(mid 435.745726 -199.62867)
					(end 435.749446 -199.63765)
				)
			)
		)
	)
	(zone
		(layer "In1.Cu")
		(hatch none 0.5)
		(connect_pads
			(clearance 0)
		)
		(min_thickness 0.25)
		(keepout
			(tracks not_allowed)
			(vias allowed)
			(pads allowed)
			(copperpour not_allowed)
			(footprints allowed)
		)
		(placement
			(enabled no)
			(sheetname "")
		)
		(fill
			(thermal_gap 0.5)
			(thermal_bridge_width 0.5)
			(island_removal_mode 0)
		)
		(polygon
			(pts
				(arc
					(start 199.4535 -203.532486)
					(mid 199.44978 -203.541466)
					(end 199.4408 -203.545186)
				)
				(arc
					(start 197.9676 -203.545186)
					(mid 197.95862 -203.541466)
					(end 197.9549 -203.532486)
				)
				(arc
					(start 197.9549 -203.037948)
					(mid 197.95862 -203.028968)
					(end 197.9676 -203.025248)
				)
				(arc
					(start 199.4408 -203.025248)
					(mid 199.44978 -203.028968)
					(end 199.4535 -203.037948)
				)
			)
		)
	)
	(zone
		(layer "In1.Cu")
		(hatch none 0.5)
		(connect_pads
			(clearance 0)
		)
		(min_thickness 0.25)
		(keepout
			(tracks not_allowed)
			(vias allowed)
			(pads allowed)
			(copperpour not_allowed)
			(footprints allowed)
		)
		(placement
			(enabled no)
			(sheetname "")
		)
		(fill
			(thermal_gap 0.5)
			(thermal_bridge_width 0.5)
			(island_removal_mode 0)
		)
		(polygon
			(pts
				(arc
					(start 52.633372 -263.032494)
					(mid 52.629652 -263.041474)
					(end 52.620672 -263.045194)
				)
				(arc
					(start 51.147472 -263.045194)
					(mid 51.138492 -263.041474)
					(end 51.134772 -263.032494)
				)
				(arc
					(start 51.134772 -262.537956)
					(mid 51.138492 -262.528976)
					(end 51.147472 -262.525256)
				)
				(arc
					(start 52.620672 -262.525256)
					(mid 52.629652 -262.528976)
					(end 52.633372 -262.537956)
				)
			)
		)
	)
	(zone
		(layer "In1.Cu")
		(hatch none 0.5)
		(connect_pads
			(clearance 0)
		)
		(min_thickness 0.25)
		(keepout
			(tracks not_allowed)
			(vias allowed)
			(pads allowed)
			(copperpour not_allowed)
			(footprints allowed)
		)
		(placement
			(enabled no)
			(sheetname "")
		)
		(fill
			(thermal_gap 0.5)
			(thermal_bridge_width 0.5)
			(island_removal_mode 0)
		)
		(polygon
			(pts
				(arc
					(start 206.5782 -284.885384)
					(mid 205.9178 -284.885384)
					(end 206.5782 -284.885384)
				)
			)
		)
	)
	(zone
		(layer "In1.Cu")
		(hatch none 0.5)
		(connect_pads
			(clearance 0)
		)
		(min_thickness 0.25)
		(keepout
			(tracks not_allowed)
			(vias allowed)
			(pads allowed)
			(copperpour not_allowed)
			(footprints allowed)
		)
		(placement
			(enabled no)
			(sheetname "")
		)
		(fill
			(thermal_gap 0.5)
			(thermal_bridge_width 0.5)
			(island_removal_mode 0)
		)
		(polygon
			(pts
				(arc
					(start 52.633372 -212.88248)
					(mid 52.629652 -212.89146)
					(end 52.620672 -212.89518)
				)
				(arc
					(start 51.147472 -212.89518)
					(mid 51.138492 -212.89146)
					(end 51.134772 -212.88248)
				)
				(arc
					(start 51.134772 -212.387942)
					(mid 51.138492 -212.378962)
					(end 51.147472 -212.375242)
				)
				(arc
					(start 52.620672 -212.375242)
					(mid 52.629652 -212.378962)
					(end 52.633372 -212.387942)
				)
			)
		)
	)
	(zone
		(layer "In1.Cu")
		(hatch none 0.5)
		(connect_pads
			(clearance 0)
		)
		(min_thickness 0.25)
		(keepout
			(tracks not_allowed)
			(vias allowed)
			(pads allowed)
			(copperpour not_allowed)
			(footprints allowed)
		)
		(placement
			(enabled no)
			(sheetname "")
		)
		(fill
			(thermal_gap 0.5)
			(thermal_bridge_width 0.5)
			(island_removal_mode 0)
		)
		(polygon
			(pts
				(arc
					(start 439.849514 -268.132306)
					(mid 439.845794 -268.141286)
					(end 439.836814 -268.145006)
				)
				(arc
					(start 438.363614 -268.145006)
					(mid 438.354634 -268.141286)
					(end 438.350914 -268.132306)
				)
				(arc
					(start 438.350914 -267.637768)
					(mid 438.354634 -267.628788)
					(end 438.363614 -267.625068)
				)
				(arc
					(start 439.836814 -267.625068)
					(mid 439.845794 -267.628788)
					(end 439.849514 -267.637768)
				)
			)
		)
	)
	(zone
		(layer "In1.Cu")
		(hatch none 0.5)
		(connect_pads
			(clearance 0)
		)
		(min_thickness 0.25)
		(keepout
			(tracks not_allowed)
			(vias allowed)
			(pads allowed)
			(copperpour not_allowed)
			(footprints allowed)
		)
		(placement
			(enabled no)
			(sheetname "")
		)
		(fill
			(thermal_gap 0.5)
			(thermal_bridge_width 0.5)
			(island_removal_mode 0)
		)
		(polygon
			(pts
				(arc
					(start 454.937368 -223.932242)
					(mid 454.933648 -223.941222)
					(end 454.924668 -223.944942)
				)
				(arc
					(start 453.451468 -223.944942)
					(mid 453.442488 -223.941222)
					(end 453.438768 -223.932242)
				)
				(arc
					(start 453.438768 -223.437704)
					(mid 453.442488 -223.428724)
					(end 453.451468 -223.425004)
				)
				(arc
					(start 454.924668 -223.425004)
					(mid 454.933648 -223.428724)
					(end 454.937368 -223.437704)
				)
			)
		)
	)
	(zone
		(layer "In1.Cu")
		(hatch none 0.5)
		(connect_pads
			(clearance 0)
		)
		(min_thickness 0.25)
		(keepout
			(tracks not_allowed)
			(vias allowed)
			(pads allowed)
			(copperpour not_allowed)
			(footprints allowed)
		)
		(placement
			(enabled no)
			(sheetname "")
		)
		(fill
			(thermal_gap 0.5)
			(thermal_bridge_width 0.5)
			(island_removal_mode 0)
		)
		(polygon
			(pts
				(arc
					(start 420.661338 -265.582146)
					(mid 420.657618 -265.591126)
					(end 420.648638 -265.594846)
				)
				(arc
					(start 419.175438 -265.594846)
					(mid 419.166458 -265.591126)
					(end 419.162738 -265.582146)
				)
				(arc
					(start 419.162738 -265.087608)
					(mid 419.166458 -265.078628)
					(end 419.175438 -265.074908)
				)
				(arc
					(start 420.648638 -265.074908)
					(mid 420.657618 -265.078628)
					(end 420.661338 -265.087608)
				)
			)
		)
	)
	(zone
		(layer "In1.Cu")
		(hatch none 0.5)
		(connect_pads
			(clearance 0)
		)
		(min_thickness 0.25)
		(keepout
			(tracks not_allowed)
			(vias allowed)
			(pads allowed)
			(copperpour not_allowed)
			(footprints allowed)
		)
		(placement
			(enabled no)
			(sheetname "")
		)
		(fill
			(thermal_gap 0.5)
			(thermal_bridge_width 0.5)
			(island_removal_mode 0)
		)
		(polygon
			(pts
				(arc
					(start 199.4535 -199.282558)
					(mid 199.44978 -199.291538)
					(end 199.4408 -199.295258)
				)
				(arc
					(start 197.9676 -199.295258)
					(mid 197.95862 -199.291538)
					(end 197.9549 -199.282558)
				)
				(arc
					(start 197.9549 -198.78802)
					(mid 197.95862 -198.77904)
					(end 197.9676 -198.77532)
				)
				(arc
					(start 199.4408 -198.77532)
					(mid 199.44978 -198.77904)
					(end 199.4535 -198.78802)
				)
			)
		)
	)
	(zone
		(layer "In1.Cu")
		(hatch none 0.5)
		(connect_pads
			(clearance 0)
		)
		(min_thickness 0.25)
		(keepout
			(tracks not_allowed)
			(vias allowed)
			(pads allowed)
			(copperpour not_allowed)
			(footprints allowed)
		)
		(placement
			(enabled no)
			(sheetname "")
		)
		(fill
			(thermal_gap 0.5)
			(thermal_bridge_width 0.5)
			(island_removal_mode 0)
		)
		(polygon
			(pts
				(arc
					(start 45.089318 -199.282558)
					(mid 45.085598 -199.291538)
					(end 45.076618 -199.295258)
				)
				(arc
					(start 43.603418 -199.295258)
					(mid 43.594438 -199.291538)
					(end 43.590718 -199.282558)
				)
				(arc
					(start 43.590718 -198.78802)
					(mid 43.594438 -198.77904)
					(end 43.603418 -198.77532)
				)
				(arc
					(start 45.076618 -198.77532)
					(mid 45.085598 -198.77904)
					(end 45.089318 -198.78802)
				)
			)
		)
	)
	(zone
		(layer "In1.Cu")
		(hatch none 0.5)
		(connect_pads
			(clearance 0)
		)
		(min_thickness 0.25)
		(keepout
			(tracks not_allowed)
			(vias allowed)
			(pads allowed)
			(copperpour not_allowed)
			(footprints allowed)
		)
		(placement
			(enabled no)
			(sheetname "")
		)
		(fill
			(thermal_gap 0.5)
			(thermal_bridge_width 0.5)
			(island_removal_mode 0)
		)
		(polygon
			(pts
				(arc
					(start 63.791084 -383.440686)
					(mid 63.918084 -383.567686)
					(end 64.045084 -383.440686)
				)
				(arc
					(start 64.045084 -383.364486)
					(mid 63.918084 -383.237486)
					(end 63.791084 -383.364486)
				)
			)
		)
	)
	(zone
		(layer "In1.Cu")
		(hatch none 0.5)
		(connect_pads
			(clearance 0)
		)
		(min_thickness 0.25)
		(keepout
			(tracks not_allowed)
			(vias allowed)
			(pads allowed)
			(copperpour not_allowed)
			(footprints allowed)
		)
		(placement
			(enabled no)
			(sheetname "")
		)
		(fill
			(thermal_gap 0.5)
			(thermal_bridge_width 0.5)
			(island_removal_mode 0)
		)
		(polygon
			(pts
				(arc
					(start 35.807396 -423.7482)
					(mid 35.792517 -423.784121)
					(end 35.756596 -423.799)
				)
				(arc
					(start 35.248596 -423.799)
					(mid 35.212675 -423.784121)
					(end 35.197796 -423.7482)
				)
				(arc
					(start 35.197796 -423.27195)
					(mid 35.212675 -423.236029)
					(end 35.248596 -423.22115)
				)
				(arc
					(start 35.756596 -423.22115)
					(mid 35.792517 -423.236029)
					(end 35.807396 -423.27195)
				)
			)
		)
	)
	(zone
		(layer "In1.Cu")
		(hatch none 0.5)
		(connect_pads
			(clearance 0)
		)
		(min_thickness 0.25)
		(keepout
			(tracks not_allowed)
			(vias allowed)
			(pads allowed)
			(copperpour not_allowed)
			(footprints allowed)
		)
		(placement
			(enabled no)
			(sheetname "")
		)
		(fill
			(thermal_gap 0.5)
			(thermal_bridge_width 0.5)
			(island_removal_mode 0)
		)
		(polygon
			(pts
				(arc
					(start 277.941532 -291.082222)
					(mid 277.937812 -291.091202)
					(end 277.928832 -291.094922)
				)
				(arc
					(start 276.455632 -291.094922)
					(mid 276.446652 -291.091202)
					(end 276.442932 -291.082222)
				)
				(arc
					(start 276.442932 -290.587684)
					(mid 276.446652 -290.578704)
					(end 276.455632 -290.574984)
				)
				(arc
					(start 277.928832 -290.574984)
					(mid 277.937812 -290.578704)
					(end 277.941532 -290.587684)
				)
			)
		)
	)
	(zone
		(layer "In1.Cu")
		(hatch none 0.5)
		(connect_pads
			(clearance 0)
		)
		(min_thickness 0.25)
		(keepout
			(tracks not_allowed)
			(vias allowed)
			(pads allowed)
			(copperpour not_allowed)
			(footprints allowed)
		)
		(placement
			(enabled no)
			(sheetname "")
		)
		(fill
			(thermal_gap 0.5)
			(thermal_bridge_width 0.5)
			(island_removal_mode 0)
		)
		(polygon
			(pts
				(arc
					(start 281.385264 -276.632162)
					(mid 281.381544 -276.641142)
					(end 281.372564 -276.644862)
				)
				(arc
					(start 279.899364 -276.644862)
					(mid 279.890384 -276.641142)
					(end 279.886664 -276.632162)
				)
				(arc
					(start 279.886664 -276.137624)
					(mid 279.890384 -276.128644)
					(end 279.899364 -276.124924)
				)
				(arc
					(start 281.372564 -276.124924)
					(mid 281.381544 -276.128644)
					(end 281.385264 -276.137624)
				)
			)
		)
	)
	(zone
		(layer "In1.Cu")
		(hatch none 0.5)
		(connect_pads
			(clearance 0)
		)
		(min_thickness 0.25)
		(keepout
			(tracks not_allowed)
			(vias allowed)
			(pads allowed)
			(copperpour not_allowed)
			(footprints allowed)
		)
		(placement
			(enabled no)
			(sheetname "")
		)
		(fill
			(thermal_gap 0.5)
			(thermal_bridge_width 0.5)
			(island_removal_mode 0)
		)
		(polygon
			(pts
				(arc
					(start 308.117494 -217.982292)
					(mid 308.113774 -217.991272)
					(end 308.104794 -217.994992)
				)
				(arc
					(start 306.631594 -217.994992)
					(mid 306.622614 -217.991272)
					(end 306.618894 -217.982292)
				)
				(arc
					(start 306.618894 -217.487754)
					(mid 306.622614 -217.478774)
					(end 306.631594 -217.475054)
				)
				(arc
					(start 308.104794 -217.475054)
					(mid 308.113774 -217.478774)
					(end 308.117494 -217.487754)
				)
			)
		)
	)
	(zone
		(layer "In1.Cu")
		(hatch none 0.5)
		(connect_pads
			(clearance 0)
		)
		(min_thickness 0.25)
		(keepout
			(tracks not_allowed)
			(vias allowed)
			(pads allowed)
			(copperpour not_allowed)
			(footprints allowed)
		)
		(placement
			(enabled no)
			(sheetname "")
		)
		(fill
			(thermal_gap 0.5)
			(thermal_bridge_width 0.5)
			(island_removal_mode 0)
		)
		(polygon
			(pts
				(arc
					(start 314.370212 -392.30427)
					(mid 314.065412 -392.30427)
					(end 314.370212 -392.30427)
				)
			)
		)
	)
	(zone
		(layer "In1.Cu")
		(hatch none 0.5)
		(connect_pads
			(clearance 0)
		)
		(min_thickness 0.25)
		(keepout
			(tracks not_allowed)
			(vias allowed)
			(pads allowed)
			(copperpour not_allowed)
			(footprints allowed)
		)
		(placement
			(enabled no)
			(sheetname "")
		)
		(fill
			(thermal_gap 0.5)
			(thermal_bridge_width 0.5)
			(island_removal_mode 0)
		)
		(polygon
			(pts
				(arc
					(start 303.860962 -397.849344)
					(mid 303.479962 -397.849344)
					(end 303.860962 -397.849344)
				)
			)
		)
	)
	(zone
		(layer "In1.Cu")
		(hatch none 0.5)
		(connect_pads
			(clearance 0)
		)
		(min_thickness 0.25)
		(keepout
			(tracks not_allowed)
			(vias allowed)
			(pads allowed)
			(copperpour not_allowed)
			(footprints allowed)
		)
		(placement
			(enabled no)
			(sheetname "")
		)
		(fill
			(thermal_gap 0.5)
			(thermal_bridge_width 0.5)
			(island_removal_mode 0)
		)
		(polygon
			(pts
				(arc
					(start 270.397478 -234.982258)
					(mid 270.393758 -234.991238)
					(end 270.384778 -234.994958)
				)
				(arc
					(start 268.911578 -234.994958)
					(mid 268.902598 -234.991238)
					(end 268.898878 -234.982258)
				)
				(arc
					(start 268.898878 -234.48772)
					(mid 268.902598 -234.47874)
					(end 268.911578 -234.47502)
				)
				(arc
					(start 270.384778 -234.47502)
					(mid 270.393758 -234.47874)
					(end 270.397478 -234.48772)
				)
			)
		)
	)
	(zone
		(layer "In1.Cu")
		(hatch none 0.5)
		(connect_pads
			(clearance 0)
		)
		(min_thickness 0.25)
		(keepout
			(tracks not_allowed)
			(vias allowed)
			(pads allowed)
			(copperpour not_allowed)
			(footprints allowed)
		)
		(placement
			(enabled no)
			(sheetname "")
		)
		(fill
			(thermal_gap 0.5)
			(thermal_bridge_width 0.5)
			(island_removal_mode 0)
		)
		(polygon
			(pts
				(arc
					(start 285.485332 -306.382166)
					(mid 285.481612 -306.391146)
					(end 285.472632 -306.394866)
				)
				(arc
					(start 283.999432 -306.394866)
					(mid 283.990452 -306.391146)
					(end 283.986732 -306.382166)
				)
				(arc
					(start 283.986732 -305.887628)
					(mid 283.990452 -305.878648)
					(end 283.999432 -305.874928)
				)
				(arc
					(start 285.472632 -305.874928)
					(mid 285.481612 -305.878648)
					(end 285.485332 -305.887628)
				)
			)
		)
	)
	(zone
		(layer "In1.Cu")
		(hatch none 0.5)
		(connect_pads
			(clearance 0)
		)
		(min_thickness 0.25)
		(keepout
			(tracks not_allowed)
			(vias allowed)
			(pads allowed)
			(copperpour not_allowed)
			(footprints allowed)
		)
		(placement
			(enabled no)
			(sheetname "")
		)
		(fill
			(thermal_gap 0.5)
			(thermal_bridge_width 0.5)
			(island_removal_mode 0)
		)
		(polygon
			(pts
				(arc
					(start 266.29741 -213.73211)
					(mid 266.29369 -213.74109)
					(end 266.28471 -213.74481)
				)
				(arc
					(start 264.81151 -213.74481)
					(mid 264.80253 -213.74109)
					(end 264.79881 -213.73211)
				)
				(arc
					(start 264.79881 -213.237572)
					(mid 264.80253 -213.228592)
					(end 264.81151 -213.224872)
				)
				(arc
					(start 266.28471 -213.224872)
					(mid 266.29369 -213.228592)
					(end 266.29741 -213.237572)
				)
			)
		)
	)
	(zone
		(layer "In1.Cu")
		(hatch none 0.5)
		(connect_pads
			(clearance 0)
		)
		(min_thickness 0.25)
		(keepout
			(tracks not_allowed)
			(vias allowed)
			(pads allowed)
			(copperpour not_allowed)
			(footprints allowed)
		)
		(placement
			(enabled no)
			(sheetname "")
		)
		(fill
			(thermal_gap 0.5)
			(thermal_bridge_width 0.5)
			(island_removal_mode 0)
		)
		(polygon
			(pts
				(arc
					(start 450.8373 -299.582332)
					(mid 450.83358 -299.591312)
					(end 450.8246 -299.595032)
				)
				(arc
					(start 449.3514 -299.595032)
					(mid 449.34242 -299.591312)
					(end 449.3387 -299.582332)
				)
				(arc
					(start 449.3387 -299.087794)
					(mid 449.34242 -299.078814)
					(end 449.3514 -299.075094)
				)
				(arc
					(start 450.8246 -299.075094)
					(mid 450.83358 -299.078814)
					(end 450.8373 -299.087794)
				)
			)
		)
	)
	(zone
		(layer "In1.Cu")
		(hatch none 0.5)
		(connect_pads
			(clearance 0)
		)
		(min_thickness 0.25)
		(keepout
			(tracks not_allowed)
			(vias allowed)
			(pads allowed)
			(copperpour not_allowed)
			(footprints allowed)
		)
		(placement
			(enabled no)
			(sheetname "")
		)
		(fill
			(thermal_gap 0.5)
			(thermal_bridge_width 0.5)
			(island_removal_mode 0)
		)
		(polygon
			(pts
				(arc
					(start 187.809378 -235.832396)
					(mid 187.805658 -235.841376)
					(end 187.796678 -235.845096)
				)
				(arc
					(start 186.323478 -235.845096)
					(mid 186.314498 -235.841376)
					(end 186.310778 -235.832396)
				)
				(arc
					(start 186.310778 -235.337858)
					(mid 186.314498 -235.328878)
					(end 186.323478 -235.325158)
				)
				(arc
					(start 187.796678 -235.325158)
					(mid 187.805658 -235.328878)
					(end 187.809378 -235.337858)
				)
			)
		)
	)
	(zone
		(layer "In1.Cu")
		(hatch none 0.5)
		(connect_pads
			(clearance 0)
		)
		(min_thickness 0.25)
		(keepout
			(tracks not_allowed)
			(vias allowed)
			(pads allowed)
			(copperpour not_allowed)
			(footprints allowed)
		)
		(placement
			(enabled no)
			(sheetname "")
		)
		(fill
			(thermal_gap 0.5)
			(thermal_bridge_width 0.5)
			(island_removal_mode 0)
		)
		(polygon
			(pts
				(arc
					(start 87.918798 -383.440686)
					(mid 88.045798 -383.567686)
					(end 88.172798 -383.440686)
				)
				(arc
					(start 88.172798 -383.364486)
					(mid 88.045798 -383.237486)
					(end 87.918798 -383.364486)
				)
			)
		)
	)
	(zone
		(layer "In1.Cu")
		(hatch none 0.5)
		(connect_pads
			(clearance 0)
		)
		(min_thickness 0.25)
		(keepout
			(tracks not_allowed)
			(vias allowed)
			(pads allowed)
			(copperpour not_allowed)
			(footprints allowed)
		)
		(placement
			(enabled no)
			(sheetname "")
		)
		(fill
			(thermal_gap 0.5)
			(thermal_bridge_width 0.5)
			(island_removal_mode 0)
		)
		(polygon
			(pts
				(arc
					(start 383.29108 -391.822686)
					(mid 383.41808 -391.949686)
					(end 383.54508 -391.822686)
				)
				(arc
					(start 383.54508 -391.746486)
					(mid 383.41808 -391.619486)
					(end 383.29108 -391.746486)
				)
			)
		)
	)
	(zone
		(layer "In1.Cu")
		(hatch none 0.5)
		(connect_pads
			(clearance 0)
		)
		(min_thickness 0.25)
		(keepout
			(tracks not_allowed)
			(vias allowed)
			(pads allowed)
			(copperpour not_allowed)
			(footprints allowed)
		)
		(placement
			(enabled no)
			(sheetname "")
		)
		(fill
			(thermal_gap 0.5)
			(thermal_bridge_width 0.5)
			(island_removal_mode 0)
		)
		(polygon
			(pts
				(arc
					(start 22.45741 -236.682534)
					(mid 22.45369 -236.691514)
					(end 22.44471 -236.695234)
				)
				(arc
					(start 20.97151 -236.695234)
					(mid 20.96253 -236.691514)
					(end 20.95881 -236.682534)
				)
				(arc
					(start 20.95881 -236.187996)
					(mid 20.96253 -236.179016)
					(end 20.97151 -236.175296)
				)
				(arc
					(start 22.44471 -236.175296)
					(mid 22.45369 -236.179016)
					(end 22.45741 -236.187996)
				)
			)
		)
	)
	(zone
		(layer "In1.Cu")
		(hatch none 0.5)
		(connect_pads
			(clearance 0)
		)
		(min_thickness 0.25)
		(keepout
			(tracks not_allowed)
			(vias allowed)
			(pads allowed)
			(copperpour not_allowed)
			(footprints allowed)
		)
		(placement
			(enabled no)
			(sheetname "")
		)
		(fill
			(thermal_gap 0.5)
			(thermal_bridge_width 0.5)
			(island_removal_mode 0)
		)
		(polygon
			(pts
				(arc
					(start 288.929318 -273.232118)
					(mid 288.925598 -273.241098)
					(end 288.916618 -273.244818)
				)
				(arc
					(start 287.443418 -273.244818)
					(mid 287.434438 -273.241098)
					(end 287.430718 -273.232118)
				)
				(arc
					(start 287.430718 -272.73758)
					(mid 287.434438 -272.7286)
					(end 287.443418 -272.72488)
				)
				(arc
					(start 288.916618 -272.72488)
					(mid 288.925598 -272.7286)
					(end 288.929318 -272.73758)
				)
			)
		)
	)
	(zone
		(layer "In1.Cu")
		(hatch none 0.5)
		(connect_pads
			(clearance 0)
		)
		(min_thickness 0.25)
		(keepout
			(tracks not_allowed)
			(vias allowed)
			(pads allowed)
			(copperpour not_allowed)
			(footprints allowed)
		)
		(placement
			(enabled no)
			(sheetname "")
		)
		(fill
			(thermal_gap 0.5)
			(thermal_bridge_width 0.5)
			(island_removal_mode 0)
		)
		(polygon
			(pts
				(arc
					(start 122.161046 -389.467344)
					(mid 121.780046 -389.467344)
					(end 122.161046 -389.467344)
				)
			)
		)
	)
	(zone
		(layer "In1.Cu")
		(hatch none 0.5)
		(connect_pads
			(clearance 0)
		)
		(min_thickness 0.25)
		(keepout
			(tracks not_allowed)
			(vias allowed)
			(pads allowed)
			(copperpour not_allowed)
			(footprints allowed)
		)
		(placement
			(enabled no)
			(sheetname "")
		)
		(fill
			(thermal_gap 0.5)
			(thermal_bridge_width 0.5)
			(island_removal_mode 0)
		)
		(polygon
			(pts
				(arc
					(start 424.761406 -231.582214)
					(mid 424.757686 -231.591194)
					(end 424.748706 -231.594914)
				)
				(arc
					(start 423.275506 -231.594914)
					(mid 423.266526 -231.591194)
					(end 423.262806 -231.582214)
				)
				(arc
					(start 423.262806 -231.087676)
					(mid 423.266526 -231.078696)
					(end 423.275506 -231.074976)
				)
				(arc
					(start 424.748706 -231.074976)
					(mid 424.757686 -231.078696)
					(end 424.761406 -231.087676)
				)
			)
		)
	)
	(zone
		(layer "In1.Cu")
		(hatch none 0.5)
		(connect_pads
			(clearance 0)
		)
		(min_thickness 0.25)
		(keepout
			(tracks not_allowed)
			(vias allowed)
			(pads allowed)
			(copperpour not_allowed)
			(footprints allowed)
		)
		(placement
			(enabled no)
			(sheetname "")
		)
		(fill
			(thermal_gap 0.5)
			(thermal_bridge_width 0.5)
			(island_removal_mode 0)
		)
		(polygon
			(pts
				(arc
					(start 206.9973 -289.382454)
					(mid 206.99358 -289.391434)
					(end 206.9846 -289.395154)
				)
				(arc
					(start 205.5114 -289.395154)
					(mid 205.50242 -289.391434)
					(end 205.4987 -289.382454)
				)
				(arc
					(start 205.4987 -288.887916)
					(mid 205.50242 -288.878936)
					(end 205.5114 -288.875216)
				)
				(arc
					(start 206.9846 -288.875216)
					(mid 206.99358 -288.878936)
					(end 206.9973 -288.887916)
				)
			)
		)
	)
	(zone
		(layer "In1.Cu")
		(hatch none 0.5)
		(connect_pads
			(clearance 0)
		)
		(min_thickness 0.25)
		(keepout
			(tracks not_allowed)
			(vias allowed)
			(pads allowed)
			(copperpour not_allowed)
			(footprints allowed)
		)
		(placement
			(enabled no)
			(sheetname "")
		)
		(fill
			(thermal_gap 0.5)
			(thermal_bridge_width 0.5)
			(island_removal_mode 0)
		)
		(polygon
			(pts
				(arc
					(start 413.117284 -243.482114)
					(mid 413.113564 -243.491094)
					(end 413.104584 -243.494814)
				)
				(arc
					(start 411.631384 -243.494814)
					(mid 411.622404 -243.491094)
					(end 411.618684 -243.482114)
				)
				(arc
					(start 411.618684 -242.987576)
					(mid 411.622404 -242.978596)
					(end 411.631384 -242.974876)
				)
				(arc
					(start 413.104584 -242.974876)
					(mid 413.113564 -242.978596)
					(end 413.117284 -242.987576)
				)
			)
		)
	)
	(zone
		(layer "In1.Cu")
		(hatch none 0.5)
		(connect_pads
			(clearance 0)
		)
		(min_thickness 0.25)
		(keepout
			(tracks not_allowed)
			(vias allowed)
			(pads allowed)
			(copperpour not_allowed)
			(footprints allowed)
		)
		(placement
			(enabled no)
			(sheetname "")
		)
		(fill
			(thermal_gap 0.5)
			(thermal_bridge_width 0.5)
			(island_removal_mode 0)
		)
		(polygon
			(pts
				(arc
					(start 435.749446 -286.832294)
					(mid 435.745726 -286.841274)
					(end 435.736746 -286.844994)
				)
				(arc
					(start 434.263546 -286.844994)
					(mid 434.254566 -286.841274)
					(end 434.250846 -286.832294)
				)
				(arc
					(start 434.250846 -286.337756)
					(mid 434.254566 -286.328776)
					(end 434.263546 -286.325056)
				)
				(arc
					(start 435.736746 -286.325056)
					(mid 435.745726 -286.328776)
					(end 435.749446 -286.337756)
				)
			)
		)
	)
	(zone
		(layer "In1.Cu")
		(hatch none 0.5)
		(connect_pads
			(clearance 0)
		)
		(min_thickness 0.25)
		(keepout
			(tracks not_allowed)
			(vias allowed)
			(pads allowed)
			(copperpour not_allowed)
			(footprints allowed)
		)
		(placement
			(enabled no)
			(sheetname "")
		)
		(fill
			(thermal_gap 0.5)
			(thermal_bridge_width 0.5)
			(island_removal_mode 0)
		)
		(polygon
			(pts
				(arc
					(start 206.5782 -304.435256)
					(mid 205.9178 -304.435256)
					(end 206.5782 -304.435256)
				)
			)
		)
	)
	(zone
		(layer "In1.Cu")
		(hatch none 0.5)
		(connect_pads
			(clearance 0)
		)
		(min_thickness 0.25)
		(keepout
			(tracks not_allowed)
			(vias allowed)
			(pads allowed)
			(copperpour not_allowed)
			(footprints allowed)
		)
		(placement
			(enabled no)
			(sheetname "")
		)
		(fill
			(thermal_gap 0.5)
			(thermal_bridge_width 0.5)
			(island_removal_mode 0)
		)
		(polygon
			(pts
				(arc
					(start 30.001464 -272.382488)
					(mid 29.997744 -272.391468)
					(end 29.988764 -272.395188)
				)
				(arc
					(start 28.515564 -272.395188)
					(mid 28.506584 -272.391468)
					(end 28.502864 -272.382488)
				)
				(arc
					(start 28.502864 -271.88795)
					(mid 28.506584 -271.87897)
					(end 28.515564 -271.87525)
				)
				(arc
					(start 29.988764 -271.87525)
					(mid 29.997744 -271.87897)
					(end 30.001464 -271.88795)
				)
			)
		)
	)
	(zone
		(layer "In1.Cu")
		(hatch none 0.5)
		(connect_pads
			(clearance 0)
		)
		(min_thickness 0.25)
		(keepout
			(tracks not_allowed)
			(vias allowed)
			(pads allowed)
			(copperpour not_allowed)
			(footprints allowed)
		)
		(placement
			(enabled no)
			(sheetname "")
		)
		(fill
			(thermal_gap 0.5)
			(thermal_bridge_width 0.5)
			(island_removal_mode 0)
		)
		(polygon
			(pts
				(arc
					(start 81.189068 -385.31038)
					(mid 80.808068 -385.31038)
					(end 81.189068 -385.31038)
				)
			)
		)
	)
	(zone
		(layer "In1.Cu")
		(hatch none 0.5)
		(connect_pads
			(clearance 0)
		)
		(min_thickness 0.25)
		(keepout
			(tracks not_allowed)
			(vias allowed)
			(pads allowed)
			(copperpour not_allowed)
			(footprints allowed)
		)
		(placement
			(enabled no)
			(sheetname "")
		)
		(fill
			(thermal_gap 0.5)
			(thermal_bridge_width 0.5)
			(island_removal_mode 0)
		)
		(polygon
			(pts
				(arc
					(start 417.018724 -391.822686)
					(mid 417.145724 -391.949686)
					(end 417.272724 -391.822686)
				)
				(arc
					(start 417.272724 -391.746486)
					(mid 417.145724 -391.619486)
					(end 417.018724 -391.746486)
				)
			)
		)
	)
	(zone
		(layer "In1.Cu")
		(hatch none 0.5)
		(connect_pads
			(clearance 0)
		)
		(min_thickness 0.25)
		(keepout
			(tracks not_allowed)
			(vias allowed)
			(pads allowed)
			(copperpour not_allowed)
			(footprints allowed)
		)
		(placement
			(enabled no)
			(sheetname "")
		)
		(fill
			(thermal_gap 0.5)
			(thermal_bridge_width 0.5)
			(island_removal_mode 0)
		)
		(polygon
			(pts
				(arc
					(start 413.117284 -302.982122)
					(mid 413.113564 -302.991102)
					(end 413.104584 -302.994822)
				)
				(arc
					(start 411.631384 -302.994822)
					(mid 411.622404 -302.991102)
					(end 411.618684 -302.982122)
				)
				(arc
					(start 411.618684 -302.487584)
					(mid 411.622404 -302.478604)
					(end 411.631384 -302.474884)
				)
				(arc
					(start 413.104584 -302.474884)
					(mid 413.113564 -302.478604)
					(end 413.117284 -302.487584)
				)
			)
		)
	)
	(zone
		(layer "In1.Cu")
		(hatch none 0.5)
		(connect_pads
			(clearance 0)
		)
		(min_thickness 0.25)
		(keepout
			(tracks not_allowed)
			(vias allowed)
			(pads allowed)
			(copperpour not_allowed)
			(footprints allowed)
		)
		(placement
			(enabled no)
			(sheetname "")
		)
		(fill
			(thermal_gap 0.5)
			(thermal_bridge_width 0.5)
			(island_removal_mode 0)
		)
		(polygon
			(pts
				(arc
					(start 37.545264 -292.782498)
					(mid 37.541544 -292.791478)
					(end 37.532564 -292.795198)
				)
				(arc
					(start 36.059364 -292.795198)
					(mid 36.050384 -292.791478)
					(end 36.046664 -292.782498)
				)
				(arc
					(start 36.046664 -292.28796)
					(mid 36.050384 -292.27898)
					(end 36.059364 -292.27526)
				)
				(arc
					(start 37.532564 -292.27526)
					(mid 37.541544 -292.27898)
					(end 37.545264 -292.28796)
				)
			)
		)
	)
	(zone
		(layer "In1.Cu")
		(hatch none 0.5)
		(connect_pads
			(clearance 0)
		)
		(min_thickness 0.25)
		(keepout
			(tracks not_allowed)
			(vias allowed)
			(pads allowed)
			(copperpour not_allowed)
			(footprints allowed)
		)
		(placement
			(enabled no)
			(sheetname "")
		)
		(fill
			(thermal_gap 0.5)
			(thermal_bridge_width 0.5)
			(island_removal_mode 0)
		)
		(polygon
			(pts
				(arc
					(start 40.98925 -302.982376)
					(mid 40.98553 -302.991356)
					(end 40.97655 -302.995076)
				)
				(arc
					(start 39.50335 -302.995076)
					(mid 39.49437 -302.991356)
					(end 39.49065 -302.982376)
				)
				(arc
					(start 39.49065 -302.487838)
					(mid 39.49437 -302.478858)
					(end 39.50335 -302.475138)
				)
				(arc
					(start 40.97655 -302.475138)
					(mid 40.98553 -302.478858)
					(end 40.98925 -302.487838)
				)
			)
		)
	)
	(zone
		(layer "In1.Cu")
		(hatch none 0.5)
		(connect_pads
			(clearance 0)
		)
		(min_thickness 0.25)
		(keepout
			(tracks not_allowed)
			(vias allowed)
			(pads allowed)
			(copperpour not_allowed)
			(footprints allowed)
		)
		(placement
			(enabled no)
			(sheetname "")
		)
		(fill
			(thermal_gap 0.5)
			(thermal_bridge_width 0.5)
			(island_removal_mode 0)
		)
		(polygon
			(pts
				(arc
					(start 266.29741 -202.682094)
					(mid 266.29369 -202.691074)
					(end 266.28471 -202.694794)
				)
				(arc
					(start 264.81151 -202.694794)
					(mid 264.80253 -202.691074)
					(end 264.79881 -202.682094)
				)
				(arc
					(start 264.79881 -202.187556)
					(mid 264.80253 -202.178576)
					(end 264.81151 -202.174856)
				)
				(arc
					(start 266.28471 -202.174856)
					(mid 266.29369 -202.178576)
					(end 266.29741 -202.187556)
				)
			)
		)
	)
	(zone
		(layer "In1.Cu")
		(hatch none 0.5)
		(connect_pads
			(clearance 0)
		)
		(min_thickness 0.25)
		(keepout
			(tracks not_allowed)
			(vias allowed)
			(pads allowed)
			(copperpour not_allowed)
			(footprints allowed)
		)
		(placement
			(enabled no)
			(sheetname "")
		)
		(fill
			(thermal_gap 0.5)
			(thermal_bridge_width 0.5)
			(island_removal_mode 0)
		)
		(polygon
			(pts
				(arc
					(start 454.937368 -263.03224)
					(mid 454.933648 -263.04122)
					(end 454.924668 -263.04494)
				)
				(arc
					(start 453.451468 -263.04494)
					(mid 453.442488 -263.04122)
					(end 453.438768 -263.03224)
				)
				(arc
					(start 453.438768 -262.537702)
					(mid 453.442488 -262.528722)
					(end 453.451468 -262.525002)
				)
				(arc
					(start 454.924668 -262.525002)
					(mid 454.933648 -262.528722)
					(end 454.937368 -262.537702)
				)
			)
		)
	)
	(zone
		(layer "In1.Cu")
		(hatch none 0.5)
		(connect_pads
			(clearance 0)
		)
		(min_thickness 0.25)
		(keepout
			(tracks not_allowed)
			(vias allowed)
			(pads allowed)
			(copperpour not_allowed)
			(footprints allowed)
		)
		(placement
			(enabled no)
			(sheetname "")
		)
		(fill
			(thermal_gap 0.5)
			(thermal_bridge_width 0.5)
			(island_removal_mode 0)
		)
		(polygon
			(pts
				(arc
					(start 22.45741 -298.732448)
					(mid 22.45369 -298.741428)
					(end 22.44471 -298.745148)
				)
				(arc
					(start 20.97151 -298.745148)
					(mid 20.96253 -298.741428)
					(end 20.95881 -298.732448)
				)
				(arc
					(start 20.95881 -298.23791)
					(mid 20.96253 -298.22893)
					(end 20.97151 -298.22521)
				)
				(arc
					(start 22.44471 -298.22521)
					(mid 22.45369 -298.22893)
					(end 22.45741 -298.23791)
				)
			)
		)
	)
	(zone
		(layer "In1.Cu")
		(hatch none 0.5)
		(connect_pads
			(clearance 0)
		)
		(min_thickness 0.25)
		(keepout
			(tracks not_allowed)
			(vias allowed)
			(pads allowed)
			(copperpour not_allowed)
			(footprints allowed)
		)
		(placement
			(enabled no)
			(sheetname "")
		)
		(fill
			(thermal_gap 0.5)
			(thermal_bridge_width 0.5)
			(island_removal_mode 0)
		)
		(polygon
			(pts
				(arc
					(start 176.821338 -254.532384)
					(mid 176.817618 -254.541364)
					(end 176.808638 -254.545084)
				)
				(arc
					(start 175.335438 -254.545084)
					(mid 175.326458 -254.541364)
					(end 175.322738 -254.532384)
				)
				(arc
					(start 175.322738 -254.037846)
					(mid 175.326458 -254.028866)
					(end 175.335438 -254.025146)
				)
				(arc
					(start 176.808638 -254.025146)
					(mid 176.817618 -254.028866)
					(end 176.821338 -254.037846)
				)
			)
		)
	)
	(zone
		(layer "In1.Cu")
		(hatch none 0.5)
		(connect_pads
			(clearance 0)
		)
		(min_thickness 0.25)
		(keepout
			(tracks not_allowed)
			(vias allowed)
			(pads allowed)
			(copperpour not_allowed)
			(footprints allowed)
		)
		(placement
			(enabled no)
			(sheetname "")
		)
		(fill
			(thermal_gap 0.5)
			(thermal_bridge_width 0.5)
			(island_removal_mode 0)
		)
		(polygon
			(pts
				(arc
					(start 206.5782 -233.035348)
					(mid 205.9178 -233.035348)
					(end 206.5782 -233.035348)
				)
			)
		)
	)
	(zone
		(layer "In1.Cu")
		(hatch none 0.5)
		(connect_pads
			(clearance 0)
		)
		(min_thickness 0.25)
		(keepout
			(tracks not_allowed)
			(vias allowed)
			(pads allowed)
			(copperpour not_allowed)
			(footprints allowed)
		)
		(placement
			(enabled no)
			(sheetname "")
		)
		(fill
			(thermal_gap 0.5)
			(thermal_bridge_width 0.5)
			(island_removal_mode 0)
		)
		(polygon
			(pts
				(arc
					(start 195.353432 -310.632348)
					(mid 195.349712 -310.641328)
					(end 195.340732 -310.645048)
				)
				(arc
					(start 193.867532 -310.645048)
					(mid 193.858552 -310.641328)
					(end 193.854832 -310.632348)
				)
				(arc
					(start 193.854832 -310.13781)
					(mid 193.858552 -310.12883)
					(end 193.867532 -310.12511)
				)
				(arc
					(start 195.340732 -310.12511)
					(mid 195.349712 -310.12883)
					(end 195.353432 -310.13781)
				)
			)
		)
	)
	(zone
		(layer "In1.Cu")
		(hatch none 0.5)
		(connect_pads
			(clearance 0)
		)
		(min_thickness 0.25)
		(keepout
			(tracks not_allowed)
			(vias allowed)
			(pads allowed)
			(copperpour not_allowed)
			(footprints allowed)
		)
		(placement
			(enabled no)
			(sheetname "")
		)
		(fill
			(thermal_gap 0.5)
			(thermal_bridge_width 0.5)
			(island_removal_mode 0)
		)
		(polygon
			(pts
				(arc
					(start 265.87831 -293.384986)
					(mid 265.21791 -293.384986)
					(end 265.87831 -293.384986)
				)
			)
		)
	)
	(zone
		(layer "In1.Cu")
		(hatch none 0.5)
		(connect_pads
			(clearance 0)
		)
		(min_thickness 0.25)
		(keepout
			(tracks not_allowed)
			(vias allowed)
			(pads allowed)
			(copperpour not_allowed)
			(footprints allowed)
		)
		(placement
			(enabled no)
			(sheetname "")
		)
		(fill
			(thermal_gap 0.5)
			(thermal_bridge_width 0.5)
			(island_removal_mode 0)
		)
		(polygon
			(pts
				(arc
					(start 159.198056 -390.761474)
					(mid 158.893256 -390.761474)
					(end 159.198056 -390.761474)
				)
			)
		)
	)
	(zone
		(layer "In1.Cu")
		(hatch none 0.5)
		(connect_pads
			(clearance 0)
		)
		(min_thickness 0.25)
		(keepout
			(tracks not_allowed)
			(vias allowed)
			(pads allowed)
			(copperpour not_allowed)
			(footprints allowed)
		)
		(placement
			(enabled no)
			(sheetname "")
		)
		(fill
			(thermal_gap 0.5)
			(thermal_bridge_width 0.5)
			(island_removal_mode 0)
		)
		(polygon
			(pts
				(arc
					(start 176.821338 -205.232508)
					(mid 176.817618 -205.241488)
					(end 176.808638 -205.245208)
				)
				(arc
					(start 175.335438 -205.245208)
					(mid 175.326458 -205.241488)
					(end 175.322738 -205.232508)
				)
				(arc
					(start 175.322738 -204.73797)
					(mid 175.326458 -204.72899)
					(end 175.335438 -204.72527)
				)
				(arc
					(start 176.808638 -204.72527)
					(mid 176.817618 -204.72899)
					(end 176.821338 -204.73797)
				)
			)
		)
	)
	(zone
		(layer "In1.Cu")
		(hatch none 0.5)
		(connect_pads
			(clearance 0)
		)
		(min_thickness 0.25)
		(keepout
			(tracks not_allowed)
			(vias allowed)
			(pads allowed)
			(copperpour not_allowed)
			(footprints allowed)
		)
		(placement
			(enabled no)
			(sheetname "")
		)
		(fill
			(thermal_gap 0.5)
			(thermal_bridge_width 0.5)
			(island_removal_mode 0)
		)
		(polygon
			(pts
				(arc
					(start 180.265324 -253.6825)
					(mid 180.261604 -253.69148)
					(end 180.252624 -253.6952)
				)
				(arc
					(start 178.779424 -253.6952)
					(mid 178.770444 -253.69148)
					(end 178.766724 -253.6825)
				)
				(arc
					(start 178.766724 -253.187962)
					(mid 178.770444 -253.178982)
					(end 178.779424 -253.175262)
				)
				(arc
					(start 180.252624 -253.175262)
					(mid 180.261604 -253.178982)
					(end 180.265324 -253.187962)
				)
			)
		)
	)
	(zone
		(layer "In1.Cu")
		(hatch none 0.5)
		(connect_pads
			(clearance 0)
		)
		(min_thickness 0.25)
		(keepout
			(tracks not_allowed)
			(vias allowed)
			(pads allowed)
			(copperpour not_allowed)
			(footprints allowed)
		)
		(placement
			(enabled no)
			(sheetname "")
		)
		(fill
			(thermal_gap 0.5)
			(thermal_bridge_width 0.5)
			(island_removal_mode 0)
		)
		(polygon
			(pts
				(arc
					(start 202.897232 -226.482402)
					(mid 202.893512 -226.491382)
					(end 202.884532 -226.495102)
				)
				(arc
					(start 201.411332 -226.495102)
					(mid 201.402352 -226.491382)
					(end 201.398632 -226.482402)
				)
				(arc
					(start 201.398632 -225.987864)
					(mid 201.402352 -225.978884)
					(end 201.411332 -225.975164)
				)
				(arc
					(start 202.884532 -225.975164)
					(mid 202.893512 -225.978884)
					(end 202.897232 -225.987864)
				)
			)
		)
	)
	(zone
		(layer "In1.Cu")
		(hatch none 0.5)
		(connect_pads
			(clearance 0)
		)
		(min_thickness 0.25)
		(keepout
			(tracks not_allowed)
			(vias allowed)
			(pads allowed)
			(copperpour not_allowed)
			(footprints allowed)
		)
		(placement
			(enabled no)
			(sheetname "")
		)
		(fill
			(thermal_gap 0.5)
			(thermal_bridge_width 0.5)
			(island_removal_mode 0)
		)
		(polygon
			(pts
				(arc
					(start 374.27027 -399.143474)
					(mid 373.96547 -399.143474)
					(end 374.27027 -399.143474)
				)
			)
		)
	)
	(zone
		(layer "In1.Cu")
		(hatch none 0.5)
		(connect_pads
			(clearance 0)
		)
		(min_thickness 0.25)
		(keepout
			(tracks not_allowed)
			(vias allowed)
			(pads allowed)
			(copperpour not_allowed)
			(footprints allowed)
		)
		(placement
			(enabled no)
			(sheetname "")
		)
		(fill
			(thermal_gap 0.5)
			(thermal_bridge_width 0.5)
			(island_removal_mode 0)
		)
		(polygon
			(pts
				(arc
					(start 266.29741 -228.18217)
					(mid 266.29369 -228.19115)
					(end 266.28471 -228.19487)
				)
				(arc
					(start 264.81151 -228.19487)
					(mid 264.80253 -228.19115)
					(end 264.79881 -228.18217)
				)
				(arc
					(start 264.79881 -227.687632)
					(mid 264.80253 -227.678652)
					(end 264.81151 -227.674932)
				)
				(arc
					(start 266.28471 -227.674932)
					(mid 266.29369 -227.678652)
					(end 266.29741 -227.687632)
				)
			)
		)
	)
	(zone
		(layer "In1.Cu")
		(hatch none 0.5)
		(connect_pads
			(clearance 0)
		)
		(min_thickness 0.25)
		(keepout
			(tracks not_allowed)
			(vias allowed)
			(pads allowed)
			(copperpour not_allowed)
			(footprints allowed)
		)
		(placement
			(enabled no)
			(sheetname "")
		)
		(fill
			(thermal_gap 0.5)
			(thermal_bridge_width 0.5)
			(island_removal_mode 0)
		)
		(polygon
			(pts
				(arc
					(start 424.761406 -210.33232)
					(mid 424.757686 -210.3413)
					(end 424.748706 -210.34502)
				)
				(arc
					(start 423.275506 -210.34502)
					(mid 423.266526 -210.3413)
					(end 423.262806 -210.33232)
				)
				(arc
					(start 423.262806 -209.837782)
					(mid 423.266526 -209.828802)
					(end 423.275506 -209.825082)
				)
				(arc
					(start 424.748706 -209.825082)
					(mid 424.757686 -209.828802)
					(end 424.761406 -209.837782)
				)
			)
		)
	)
	(zone
		(layer "In1.Cu")
		(hatch none 0.5)
		(connect_pads
			(clearance 0)
		)
		(min_thickness 0.25)
		(keepout
			(tracks not_allowed)
			(vias allowed)
			(pads allowed)
			(copperpour not_allowed)
			(footprints allowed)
		)
		(placement
			(enabled no)
			(sheetname "")
		)
		(fill
			(thermal_gap 0.5)
			(thermal_bridge_width 0.5)
			(island_removal_mode 0)
		)
		(polygon
			(pts
				(arc
					(start 417.217352 -304.682144)
					(mid 417.213632 -304.691124)
					(end 417.204652 -304.694844)
				)
				(arc
					(start 415.731452 -304.694844)
					(mid 415.722472 -304.691124)
					(end 415.718752 -304.682144)
				)
				(arc
					(start 415.718752 -304.187606)
					(mid 415.722472 -304.178626)
					(end 415.731452 -304.174906)
				)
				(arc
					(start 417.204652 -304.174906)
					(mid 417.213632 -304.178626)
					(end 417.217352 -304.187606)
				)
			)
		)
	)
	(zone
		(layer "In1.Cu")
		(hatch none 0.5)
		(connect_pads
			(clearance 0)
		)
		(min_thickness 0.25)
		(keepout
			(tracks not_allowed)
			(vias allowed)
			(pads allowed)
			(copperpour not_allowed)
			(footprints allowed)
		)
		(placement
			(enabled no)
			(sheetname "")
		)
		(fill
			(thermal_gap 0.5)
			(thermal_bridge_width 0.5)
			(island_removal_mode 0)
		)
		(polygon
			(pts
				(arc
					(start 48.770286 -390.761474)
					(mid 48.465486 -390.761474)
					(end 48.770286 -390.761474)
				)
			)
		)
	)
	(zone
		(layer "In1.Cu")
		(hatch none 0.5)
		(connect_pads
			(clearance 0)
		)
		(min_thickness 0.25)
		(keepout
			(tracks not_allowed)
			(vias allowed)
			(pads allowed)
			(copperpour not_allowed)
			(footprints allowed)
		)
		(placement
			(enabled no)
			(sheetname "")
		)
		(fill
			(thermal_gap 0.5)
			(thermal_bridge_width 0.5)
			(island_removal_mode 0)
		)
		(polygon
			(pts
				(arc
					(start 265.87831 -284.034992)
					(mid 265.21791 -284.034992)
					(end 265.87831 -284.034992)
				)
			)
		)
	)
	(zone
		(layer "In1.Cu")
		(hatch none 0.5)
		(connect_pads
			(clearance 0)
		)
		(min_thickness 0.25)
		(keepout
			(tracks not_allowed)
			(vias allowed)
			(pads allowed)
			(copperpour not_allowed)
			(footprints allowed)
		)
		(placement
			(enabled no)
			(sheetname "")
		)
		(fill
			(thermal_gap 0.5)
			(thermal_bridge_width 0.5)
			(island_removal_mode 0)
		)
		(polygon
			(pts
				(arc
					(start 447.393568 -264.732262)
					(mid 447.389848 -264.741242)
					(end 447.380868 -264.744962)
				)
				(arc
					(start 445.907668 -264.744962)
					(mid 445.898688 -264.741242)
					(end 445.894968 -264.732262)
				)
				(arc
					(start 445.894968 -264.237724)
					(mid 445.898688 -264.228744)
					(end 445.907668 -264.225024)
				)
				(arc
					(start 447.380868 -264.225024)
					(mid 447.389848 -264.228744)
					(end 447.393568 -264.237724)
				)
			)
		)
	)
	(zone
		(layer "In1.Cu")
		(hatch none 0.5)
		(connect_pads
			(clearance 0)
		)
		(min_thickness 0.25)
		(keepout
			(tracks not_allowed)
			(vias allowed)
			(pads allowed)
			(copperpour not_allowed)
			(footprints allowed)
		)
		(placement
			(enabled no)
			(sheetname "")
		)
		(fill
			(thermal_gap 0.5)
			(thermal_bridge_width 0.5)
			(island_removal_mode 0)
		)
		(polygon
			(pts
				(arc
					(start 56.077358 -307.232558)
					(mid 56.073638 -307.241538)
					(end 56.064658 -307.245258)
				)
				(arc
					(start 54.591458 -307.245258)
					(mid 54.582478 -307.241538)
					(end 54.578758 -307.232558)
				)
				(arc
					(start 54.578758 -306.73802)
					(mid 54.582478 -306.72904)
					(end 54.591458 -306.72532)
				)
				(arc
					(start 56.064658 -306.72532)
					(mid 56.073638 -306.72904)
					(end 56.077358 -306.73802)
				)
			)
		)
	)
	(zone
		(layer "In1.Cu")
		(hatch none 0.5)
		(connect_pads
			(clearance 0)
		)
		(min_thickness 0.25)
		(keepout
			(tracks not_allowed)
			(vias allowed)
			(pads allowed)
			(copperpour not_allowed)
			(footprints allowed)
		)
		(placement
			(enabled no)
			(sheetname "")
		)
		(fill
			(thermal_gap 0.5)
			(thermal_bridge_width 0.5)
			(island_removal_mode 0)
		)
		(polygon
			(pts
				(arc
					(start 172.72127 -302.982376)
					(mid 172.71755 -302.991356)
					(end 172.70857 -302.995076)
				)
				(arc
					(start 171.23537 -302.995076)
					(mid 171.22639 -302.991356)
					(end 171.22267 -302.982376)
				)
				(arc
					(start 171.22267 -302.487838)
					(mid 171.22639 -302.478858)
					(end 171.23537 -302.475138)
				)
				(arc
					(start 172.70857 -302.475138)
					(mid 172.71755 -302.478858)
					(end 172.72127 -302.487838)
				)
			)
		)
	)
	(zone
		(layer "In1.Cu")
		(hatch none 0.5)
		(connect_pads
			(clearance 0)
		)
		(min_thickness 0.25)
		(keepout
			(tracks not_allowed)
			(vias allowed)
			(pads allowed)
			(copperpour not_allowed)
			(footprints allowed)
		)
		(placement
			(enabled no)
			(sheetname "")
		)
		(fill
			(thermal_gap 0.5)
			(thermal_bridge_width 0.5)
			(island_removal_mode 0)
		)
		(polygon
			(pts
				(arc
					(start 40.98925 -296.182542)
					(mid 40.98553 -296.191522)
					(end 40.97655 -296.195242)
				)
				(arc
					(start 39.50335 -296.195242)
					(mid 39.49437 -296.191522)
					(end 39.49065 -296.182542)
				)
				(arc
					(start 39.49065 -295.688004)
					(mid 39.49437 -295.679024)
					(end 39.50335 -295.675304)
				)
				(arc
					(start 40.97655 -295.675304)
					(mid 40.98553 -295.679024)
					(end 40.98925 -295.688004)
				)
			)
		)
	)
	(zone
		(layer "In1.Cu")
		(hatch none 0.5)
		(connect_pads
			(clearance 0)
		)
		(min_thickness 0.25)
		(keepout
			(tracks not_allowed)
			(vias allowed)
			(pads allowed)
			(copperpour not_allowed)
			(footprints allowed)
		)
		(placement
			(enabled no)
			(sheetname "")
		)
		(fill
			(thermal_gap 0.5)
			(thermal_bridge_width 0.5)
			(island_removal_mode 0)
		)
		(polygon
			(pts
				(arc
					(start 296.473372 -282.582112)
					(mid 296.469652 -282.591092)
					(end 296.460672 -282.594812)
				)
				(arc
					(start 294.987472 -282.594812)
					(mid 294.978492 -282.591092)
					(end 294.974772 -282.582112)
				)
				(arc
					(start 294.974772 -282.087574)
					(mid 294.978492 -282.078594)
					(end 294.987472 -282.074874)
				)
				(arc
					(start 296.460672 -282.074874)
					(mid 296.469652 -282.078594)
					(end 296.473372 -282.087574)
				)
			)
		)
	)
	(zone
		(layer "In1.Cu")
		(hatch none 0.5)
		(connect_pads
			(clearance 0)
		)
		(min_thickness 0.25)
		(keepout
			(tracks not_allowed)
			(vias allowed)
			(pads allowed)
			(copperpour not_allowed)
			(footprints allowed)
		)
		(placement
			(enabled no)
			(sheetname "")
		)
		(fill
			(thermal_gap 0.5)
			(thermal_bridge_width 0.5)
			(island_removal_mode 0)
		)
		(polygon
			(pts
				(arc
					(start 319.46088 -397.849344)
					(mid 319.07988 -397.849344)
					(end 319.46088 -397.849344)
				)
			)
		)
	)
	(zone
		(layer "In1.Cu")
		(hatch none 0.5)
		(connect_pads
			(clearance 0)
		)
		(min_thickness 0.25)
		(keepout
			(tracks not_allowed)
			(vias allowed)
			(pads allowed)
			(copperpour not_allowed)
			(footprints allowed)
		)
		(placement
			(enabled no)
			(sheetname "")
		)
		(fill
			(thermal_gap 0.5)
			(thermal_bridge_width 0.5)
			(island_removal_mode 0)
		)
		(polygon
			(pts
				(arc
					(start 413.117284 -200.132188)
					(mid 413.113564 -200.141168)
					(end 413.104584 -200.144888)
				)
				(arc
					(start 411.631384 -200.144888)
					(mid 411.622404 -200.141168)
					(end 411.618684 -200.132188)
				)
				(arc
					(start 411.618684 -199.63765)
					(mid 411.622404 -199.62867)
					(end 411.631384 -199.62495)
				)
				(arc
					(start 413.104584 -199.62495)
					(mid 413.113564 -199.62867)
					(end 413.117284 -199.63765)
				)
			)
		)
	)
	(zone
		(layer "In1.Cu")
		(hatch none 0.5)
		(connect_pads
			(clearance 0)
		)
		(min_thickness 0.25)
		(keepout
			(tracks not_allowed)
			(vias allowed)
			(pads allowed)
			(copperpour not_allowed)
			(footprints allowed)
		)
		(placement
			(enabled no)
			(sheetname "")
		)
		(fill
			(thermal_gap 0.5)
			(thermal_bridge_width 0.5)
			(island_removal_mode 0)
		)
		(polygon
			(pts
				(arc
					(start 202.897232 -296.182542)
					(mid 202.893512 -296.191522)
					(end 202.884532 -296.195242)
				)
				(arc
					(start 201.411332 -296.195242)
					(mid 201.402352 -296.191522)
					(end 201.398632 -296.182542)
				)
				(arc
					(start 201.398632 -295.688004)
					(mid 201.402352 -295.679024)
					(end 201.411332 -295.675304)
				)
				(arc
					(start 202.884532 -295.675304)
					(mid 202.893512 -295.679024)
					(end 202.897232 -295.688004)
				)
			)
		)
	)
	(zone
		(layer "In1.Cu")
		(hatch none 0.5)
		(connect_pads
			(clearance 0)
		)
		(min_thickness 0.25)
		(keepout
			(tracks not_allowed)
			(vias allowed)
			(pads allowed)
			(copperpour not_allowed)
			(footprints allowed)
		)
		(placement
			(enabled no)
			(sheetname "")
		)
		(fill
			(thermal_gap 0.5)
			(thermal_bridge_width 0.5)
			(island_removal_mode 0)
		)
		(polygon
			(pts
				(arc
					(start 33.445196 -307.232558)
					(mid 33.441476 -307.241538)
					(end 33.432496 -307.245258)
				)
				(arc
					(start 31.959296 -307.245258)
					(mid 31.950316 -307.241538)
					(end 31.946596 -307.232558)
				)
				(arc
					(start 31.946596 -306.73802)
					(mid 31.950316 -306.72904)
					(end 31.959296 -306.72532)
				)
				(arc
					(start 33.432496 -306.72532)
					(mid 33.441476 -306.72904)
					(end 33.445196 -306.73802)
				)
			)
		)
	)
	(zone
		(layer "In1.Cu")
		(hatch none 0.5)
		(connect_pads
			(clearance 0)
		)
		(min_thickness 0.25)
		(keepout
			(tracks not_allowed)
			(vias allowed)
			(pads allowed)
			(copperpour not_allowed)
			(footprints allowed)
		)
		(placement
			(enabled no)
			(sheetname "")
		)
		(fill
			(thermal_gap 0.5)
			(thermal_bridge_width 0.5)
			(island_removal_mode 0)
		)
		(polygon
			(pts
				(arc
					(start 454.937368 -206.932276)
					(mid 454.933648 -206.941256)
					(end 454.924668 -206.944976)
				)
				(arc
					(start 453.451468 -206.944976)
					(mid 453.442488 -206.941256)
					(end 453.438768 -206.932276)
				)
				(arc
					(start 453.438768 -206.437738)
					(mid 453.442488 -206.428758)
					(end 453.451468 -206.425038)
				)
				(arc
					(start 454.924668 -206.425038)
					(mid 454.933648 -206.428758)
					(end 454.937368 -206.437738)
				)
			)
		)
	)
	(zone
		(layer "In1.Cu")
		(hatch none 0.5)
		(connect_pads
			(clearance 0)
		)
		(min_thickness 0.25)
		(keepout
			(tracks not_allowed)
			(vias allowed)
			(pads allowed)
			(copperpour not_allowed)
			(footprints allowed)
		)
		(placement
			(enabled no)
			(sheetname "")
		)
		(fill
			(thermal_gap 0.5)
			(thermal_bridge_width 0.5)
			(island_removal_mode 0)
		)
		(polygon
			(pts
				(arc
					(start 281.385264 -314.882276)
					(mid 281.381544 -314.891256)
					(end 281.372564 -314.894976)
				)
				(arc
					(start 279.899364 -314.894976)
					(mid 279.890384 -314.891256)
					(end 279.886664 -314.882276)
				)
				(arc
					(start 279.886664 -314.387738)
					(mid 279.890384 -314.378758)
					(end 279.899364 -314.375038)
				)
				(arc
					(start 281.372564 -314.375038)
					(mid 281.381544 -314.378758)
					(end 281.385264 -314.387738)
				)
			)
		)
	)
	(zone
		(layer "In1.Cu")
		(hatch none 0.5)
		(connect_pads
			(clearance 0)
		)
		(min_thickness 0.25)
		(keepout
			(tracks not_allowed)
			(vias allowed)
			(pads allowed)
			(copperpour not_allowed)
			(footprints allowed)
		)
		(placement
			(enabled no)
			(sheetname "")
		)
		(fill
			(thermal_gap 0.5)
			(thermal_bridge_width 0.5)
			(island_removal_mode 0)
		)
		(polygon
			(pts
				(arc
					(start 285.485332 -219.682314)
					(mid 285.481612 -219.691294)
					(end 285.472632 -219.695014)
				)
				(arc
					(start 283.999432 -219.695014)
					(mid 283.990452 -219.691294)
					(end 283.986732 -219.682314)
				)
				(arc
					(start 283.986732 -219.187776)
					(mid 283.990452 -219.178796)
					(end 283.999432 -219.175076)
				)
				(arc
					(start 285.472632 -219.175076)
					(mid 285.481612 -219.178796)
					(end 285.485332 -219.187776)
				)
			)
		)
	)
	(zone
		(layer "In1.Cu")
		(hatch none 0.5)
		(connect_pads
			(clearance 0)
		)
		(min_thickness 0.25)
		(keepout
			(tracks not_allowed)
			(vias allowed)
			(pads allowed)
			(copperpour not_allowed)
			(footprints allowed)
		)
		(placement
			(enabled no)
			(sheetname "")
		)
		(fill
			(thermal_gap 0.5)
			(thermal_bridge_width 0.5)
			(island_removal_mode 0)
		)
		(polygon
			(pts
				(arc
					(start 370.670328 -399.143474)
					(mid 370.365528 -399.143474)
					(end 370.670328 -399.143474)
				)
			)
		)
	)
	(zone
		(layer "In1.Cu")
		(hatch none 0.5)
		(connect_pads
			(clearance 0)
		)
		(min_thickness 0.25)
		(keepout
			(tracks not_allowed)
			(vias allowed)
			(pads allowed)
			(copperpour not_allowed)
			(footprints allowed)
		)
		(placement
			(enabled no)
			(sheetname "")
		)
		(fill
			(thermal_gap 0.5)
			(thermal_bridge_width 0.5)
			(island_removal_mode 0)
		)
		(polygon
			(pts
				(arc
					(start 195.353432 -218.83243)
					(mid 195.349712 -218.84141)
					(end 195.340732 -218.84513)
				)
				(arc
					(start 193.867532 -218.84513)
					(mid 193.858552 -218.84141)
					(end 193.854832 -218.83243)
				)
				(arc
					(start 193.854832 -218.337892)
					(mid 193.858552 -218.328912)
					(end 193.867532 -218.325192)
				)
				(arc
					(start 195.340732 -218.325192)
					(mid 195.349712 -218.328912)
					(end 195.353432 -218.337892)
				)
			)
		)
	)
	(zone
		(layer "In1.Cu")
		(hatch none 0.5)
		(connect_pads
			(clearance 0)
		)
		(min_thickness 0.25)
		(keepout
			(tracks not_allowed)
			(vias allowed)
			(pads allowed)
			(copperpour not_allowed)
			(footprints allowed)
		)
		(placement
			(enabled no)
			(sheetname "")
		)
		(fill
			(thermal_gap 0.5)
			(thermal_bridge_width 0.5)
			(island_removal_mode 0)
		)
		(polygon
			(pts
				(arc
					(start 125.760988 -386.003292)
					(mid 125.379988 -386.003292)
					(end 125.760988 -386.003292)
				)
			)
		)
	)
	(zone
		(layer "In1.Cu")
		(hatch none 0.5)
		(connect_pads
			(clearance 0)
		)
		(min_thickness 0.25)
		(keepout
			(tracks not_allowed)
			(vias allowed)
			(pads allowed)
			(copperpour not_allowed)
			(footprints allowed)
		)
		(placement
			(enabled no)
			(sheetname "")
		)
		(fill
			(thermal_gap 0.5)
			(thermal_bridge_width 0.5)
			(island_removal_mode 0)
		)
		(polygon
			(pts
				(arc
					(start 95.118682 -383.440686)
					(mid 95.245682 -383.567686)
					(end 95.372682 -383.440686)
				)
				(arc
					(start 95.372682 -383.364486)
					(mid 95.245682 -383.237486)
					(end 95.118682 -383.364486)
				)
			)
		)
	)
	(zone
		(layer "In1.Cu")
		(hatch none 0.5)
		(connect_pads
			(clearance 0)
		)
		(min_thickness 0.25)
		(keepout
			(tracks not_allowed)
			(vias allowed)
			(pads allowed)
			(copperpour not_allowed)
			(footprints allowed)
		)
		(placement
			(enabled no)
			(sheetname "")
		)
		(fill
			(thermal_gap 0.5)
			(thermal_bridge_width 0.5)
			(island_removal_mode 0)
		)
		(polygon
			(pts
				(arc
					(start 273.841464 -312.332116)
					(mid 273.837744 -312.341096)
					(end 273.828764 -312.344816)
				)
				(arc
					(start 272.355564 -312.344816)
					(mid 272.346584 -312.341096)
					(end 272.342864 -312.332116)
				)
				(arc
					(start 272.342864 -311.837578)
					(mid 272.346584 -311.828598)
					(end 272.355564 -311.824878)
				)
				(arc
					(start 273.828764 -311.824878)
					(mid 273.837744 -311.828598)
					(end 273.841464 -311.837578)
				)
			)
		)
	)
	(zone
		(layer "In1.Cu")
		(hatch none 0.5)
		(connect_pads
			(clearance 0)
		)
		(min_thickness 0.25)
		(keepout
			(tracks not_allowed)
			(vias allowed)
			(pads allowed)
			(copperpour not_allowed)
			(footprints allowed)
		)
		(placement
			(enabled no)
			(sheetname "")
		)
		(fill
			(thermal_gap 0.5)
			(thermal_bridge_width 0.5)
			(island_removal_mode 0)
		)
		(polygon
			(pts
				(arc
					(start 350.788478 -397.849344)
					(mid 350.407478 -397.849344)
					(end 350.788478 -397.849344)
				)
			)
		)
	)
	(zone
		(layer "In1.Cu")
		(hatch none 0.5)
		(connect_pads
			(clearance 0)
		)
		(min_thickness 0.25)
		(keepout
			(tracks not_allowed)
			(vias allowed)
			(pads allowed)
			(copperpour not_allowed)
			(footprints allowed)
		)
		(placement
			(enabled no)
			(sheetname "")
		)
		(fill
			(thermal_gap 0.5)
			(thermal_bridge_width 0.5)
			(island_removal_mode 0)
		)
		(polygon
			(pts
				(arc
					(start 432.30546 -269.832328)
					(mid 432.30174 -269.841308)
					(end 432.29276 -269.845028)
				)
				(arc
					(start 430.81956 -269.845028)
					(mid 430.81058 -269.841308)
					(end 430.80686 -269.832328)
				)
				(arc
					(start 430.80686 -269.33779)
					(mid 430.81058 -269.32881)
					(end 430.81956 -269.32509)
				)
				(arc
					(start 432.29276 -269.32509)
					(mid 432.30174 -269.32881)
					(end 432.30546 -269.33779)
				)
			)
		)
	)
	(zone
		(layer "In1.Cu")
		(hatch none 0.5)
		(connect_pads
			(clearance 0)
		)
		(min_thickness 0.25)
		(keepout
			(tracks not_allowed)
			(vias allowed)
			(pads allowed)
			(copperpour not_allowed)
			(footprints allowed)
		)
		(placement
			(enabled no)
			(sheetname "")
		)
		(fill
			(thermal_gap 0.5)
			(thermal_bridge_width 0.5)
			(island_removal_mode 0)
		)
		(polygon
			(pts
				(arc
					(start 296.473372 -284.282134)
					(mid 296.469652 -284.291114)
					(end 296.460672 -284.294834)
				)
				(arc
					(start 294.987472 -284.294834)
					(mid 294.978492 -284.291114)
					(end 294.974772 -284.282134)
				)
				(arc
					(start 294.974772 -283.787596)
					(mid 294.978492 -283.778616)
					(end 294.987472 -283.774896)
				)
				(arc
					(start 296.460672 -283.774896)
					(mid 296.469652 -283.778616)
					(end 296.473372 -283.787596)
				)
			)
		)
	)
	(zone
		(layer "In1.Cu")
		(hatch none 0.5)
		(connect_pads
			(clearance 0)
		)
		(min_thickness 0.25)
		(keepout
			(tracks not_allowed)
			(vias allowed)
			(pads allowed)
			(copperpour not_allowed)
			(footprints allowed)
		)
		(placement
			(enabled no)
			(sheetname "")
		)
		(fill
			(thermal_gap 0.5)
			(thermal_bridge_width 0.5)
			(island_removal_mode 0)
		)
		(polygon
			(pts
				(arc
					(start 413.117284 -221.382082)
					(mid 413.113564 -221.391062)
					(end 413.104584 -221.394782)
				)
				(arc
					(start 411.631384 -221.394782)
					(mid 411.622404 -221.391062)
					(end 411.618684 -221.382082)
				)
				(arc
					(start 411.618684 -220.887544)
					(mid 411.622404 -220.878564)
					(end 411.631384 -220.874844)
				)
				(arc
					(start 413.104584 -220.874844)
					(mid 413.113564 -220.878564)
					(end 413.117284 -220.887544)
				)
			)
		)
	)
	(zone
		(layer "In1.Cu")
		(hatch none 0.5)
		(connect_pads
			(clearance 0)
		)
		(min_thickness 0.25)
		(keepout
			(tracks not_allowed)
			(vias allowed)
			(pads allowed)
			(copperpour not_allowed)
			(footprints allowed)
		)
		(placement
			(enabled no)
			(sheetname "")
		)
		(fill
			(thermal_gap 0.5)
			(thermal_bridge_width 0.5)
			(island_removal_mode 0)
		)
		(polygon
			(pts
				(arc
					(start 266.29741 -276.632162)
					(mid 266.29369 -276.641142)
					(end 266.28471 -276.644862)
				)
				(arc
					(start 264.81151 -276.644862)
					(mid 264.80253 -276.641142)
					(end 264.79881 -276.632162)
				)
				(arc
					(start 264.79881 -276.137624)
					(mid 264.80253 -276.128644)
					(end 264.81151 -276.124924)
				)
				(arc
					(start 266.28471 -276.124924)
					(mid 266.29369 -276.128644)
					(end 266.29741 -276.137624)
				)
			)
		)
	)
	(zone
		(layer "In1.Cu")
		(hatch none 0.5)
		(connect_pads
			(clearance 0)
		)
		(min_thickness 0.25)
		(keepout
			(tracks not_allowed)
			(vias allowed)
			(pads allowed)
			(copperpour not_allowed)
			(footprints allowed)
		)
		(placement
			(enabled no)
			(sheetname "")
		)
		(fill
			(thermal_gap 0.5)
			(thermal_bridge_width 0.5)
			(island_removal_mode 0)
		)
		(polygon
			(pts
				(arc
					(start 37.545264 -200.98258)
					(mid 37.541544 -200.99156)
					(end 37.532564 -200.99528)
				)
				(arc
					(start 36.059364 -200.99528)
					(mid 36.050384 -200.99156)
					(end 36.046664 -200.98258)
				)
				(arc
					(start 36.046664 -200.488042)
					(mid 36.050384 -200.479062)
					(end 36.059364 -200.475342)
				)
				(arc
					(start 37.532564 -200.475342)
					(mid 37.541544 -200.479062)
					(end 37.545264 -200.488042)
				)
			)
		)
	)
	(zone
		(layer "In1.Cu")
		(hatch none 0.5)
		(connect_pads
			(clearance 0)
		)
		(min_thickness 0.25)
		(keepout
			(tracks not_allowed)
			(vias allowed)
			(pads allowed)
			(copperpour not_allowed)
			(footprints allowed)
		)
		(placement
			(enabled no)
			(sheetname "")
		)
		(fill
			(thermal_gap 0.5)
			(thermal_bridge_width 0.5)
			(island_removal_mode 0)
		)
		(polygon
			(pts
				(arc
					(start 454.937368 -289.3822)
					(mid 454.933648 -289.39118)
					(end 454.924668 -289.3949)
				)
				(arc
					(start 453.451468 -289.3949)
					(mid 453.442488 -289.39118)
					(end 453.438768 -289.3822)
				)
				(arc
					(start 453.438768 -288.887662)
					(mid 453.442488 -288.878682)
					(end 453.451468 -288.874962)
				)
				(arc
					(start 454.924668 -288.874962)
					(mid 454.933648 -288.878682)
					(end 454.937368 -288.887662)
				)
			)
		)
	)
	(zone
		(layer "In1.Cu")
		(hatch none 0.5)
		(connect_pads
			(clearance 0)
		)
		(min_thickness 0.25)
		(keepout
			(tracks not_allowed)
			(vias allowed)
			(pads allowed)
			(copperpour not_allowed)
			(footprints allowed)
		)
		(placement
			(enabled no)
			(sheetname "")
		)
		(fill
			(thermal_gap 0.5)
			(thermal_bridge_width 0.5)
			(island_removal_mode 0)
		)
		(polygon
			(pts
				(arc
					(start 184.365392 -244.332506)
					(mid 184.361672 -244.341486)
					(end 184.352692 -244.345206)
				)
				(arc
					(start 182.879492 -244.345206)
					(mid 182.870512 -244.341486)
					(end 182.866792 -244.332506)
				)
				(arc
					(start 182.866792 -243.837968)
					(mid 182.870512 -243.828988)
					(end 182.879492 -243.825268)
				)
				(arc
					(start 184.352692 -243.825268)
					(mid 184.361672 -243.828988)
					(end 184.365392 -243.837968)
				)
			)
		)
	)
	(zone
		(layer "In1.Cu")
		(hatch none 0.5)
		(connect_pads
			(clearance 0)
		)
		(min_thickness 0.25)
		(keepout
			(tracks not_allowed)
			(vias allowed)
			(pads allowed)
			(copperpour not_allowed)
			(footprints allowed)
		)
		(placement
			(enabled no)
			(sheetname "")
		)
		(fill
			(thermal_gap 0.5)
			(thermal_bridge_width 0.5)
			(island_removal_mode 0)
		)
		(polygon
			(pts
				(arc
					(start 432.30546 -285.132272)
					(mid 432.30174 -285.141252)
					(end 432.29276 -285.144972)
				)
				(arc
					(start 430.81956 -285.144972)
					(mid 430.81058 -285.141252)
					(end 430.80686 -285.132272)
				)
				(arc
					(start 430.80686 -284.637734)
					(mid 430.81058 -284.628754)
					(end 430.81956 -284.625034)
				)
				(arc
					(start 432.29276 -284.625034)
					(mid 432.30174 -284.628754)
					(end 432.30546 -284.637734)
				)
			)
		)
	)
	(zone
		(layer "In1.Cu")
		(hatch none 0.5)
		(connect_pads
			(clearance 0)
		)
		(min_thickness 0.25)
		(keepout
			(tracks not_allowed)
			(vias allowed)
			(pads allowed)
			(copperpour not_allowed)
			(footprints allowed)
		)
		(placement
			(enabled no)
			(sheetname "")
		)
		(fill
			(thermal_gap 0.5)
			(thermal_bridge_width 0.5)
			(island_removal_mode 0)
		)
		(polygon
			(pts
				(arc
					(start 420.661338 -305.532282)
					(mid 420.657618 -305.541262)
					(end 420.648638 -305.544982)
				)
				(arc
					(start 419.175438 -305.544982)
					(mid 419.166458 -305.541262)
					(end 419.162738 -305.532282)
				)
				(arc
					(start 419.162738 -305.037744)
					(mid 419.166458 -305.028764)
					(end 419.175438 -305.025044)
				)
				(arc
					(start 420.648638 -305.025044)
					(mid 420.657618 -305.028764)
					(end 420.661338 -305.037744)
				)
			)
		)
	)
	(zone
		(layer "In1.Cu")
		(hatch none 0.5)
		(connect_pads
			(clearance 0)
		)
		(min_thickness 0.25)
		(keepout
			(tracks not_allowed)
			(vias allowed)
			(pads allowed)
			(copperpour not_allowed)
			(footprints allowed)
		)
		(placement
			(enabled no)
			(sheetname "")
		)
		(fill
			(thermal_gap 0.5)
			(thermal_bridge_width 0.5)
			(island_removal_mode 0)
		)
		(polygon
			(pts
				(arc
					(start 199.4535 -291.082476)
					(mid 199.44978 -291.091456)
					(end 199.4408 -291.095176)
				)
				(arc
					(start 197.9676 -291.095176)
					(mid 197.95862 -291.091456)
					(end 197.9549 -291.082476)
				)
				(arc
					(start 197.9549 -290.587938)
					(mid 197.95862 -290.578958)
					(end 197.9676 -290.575238)
				)
				(arc
					(start 199.4408 -290.575238)
					(mid 199.44978 -290.578958)
					(end 199.4535 -290.587938)
				)
			)
		)
	)
	(zone
		(layer "In1.Cu")
		(hatch none 0.5)
		(connect_pads
			(clearance 0)
		)
		(min_thickness 0.25)
		(keepout
			(tracks not_allowed)
			(vias allowed)
			(pads allowed)
			(copperpour not_allowed)
			(footprints allowed)
		)
		(placement
			(enabled no)
			(sheetname "")
		)
		(fill
			(thermal_gap 0.5)
			(thermal_bridge_width 0.5)
			(island_removal_mode 0)
		)
		(polygon
			(pts
				(arc
					(start 277.941532 -278.332184)
					(mid 277.937812 -278.341164)
					(end 277.928832 -278.344884)
				)
				(arc
					(start 276.455632 -278.344884)
					(mid 276.446652 -278.341164)
					(end 276.442932 -278.332184)
				)
				(arc
					(start 276.442932 -277.837646)
					(mid 276.446652 -277.828666)
					(end 276.455632 -277.824946)
				)
				(arc
					(start 277.928832 -277.824946)
					(mid 277.937812 -277.828666)
					(end 277.941532 -277.837646)
				)
			)
		)
	)
	(zone
		(layer "In1.Cu")
		(hatch none 0.5)
		(connect_pads
			(clearance 0)
		)
		(min_thickness 0.25)
		(keepout
			(tracks not_allowed)
			(vias allowed)
			(pads allowed)
			(copperpour not_allowed)
			(footprints allowed)
		)
		(placement
			(enabled no)
			(sheetname "")
		)
		(fill
			(thermal_gap 0.5)
			(thermal_bridge_width 0.5)
			(island_removal_mode 0)
		)
		(polygon
			(pts
				(arc
					(start 413.418782 -399.701258)
					(mid 413.545782 -399.828258)
					(end 413.672782 -399.701258)
				)
				(arc
					(start 413.672782 -399.625058)
					(mid 413.545782 -399.498058)
					(end 413.418782 -399.625058)
				)
			)
		)
	)
	(zone
		(layer "In1.Cu")
		(hatch none 0.5)
		(connect_pads
			(clearance 0)
		)
		(min_thickness 0.25)
		(keepout
			(tracks not_allowed)
			(vias allowed)
			(pads allowed)
			(copperpour not_allowed)
			(footprints allowed)
		)
		(placement
			(enabled no)
			(sheetname "")
		)
		(fill
			(thermal_gap 0.5)
			(thermal_bridge_width 0.5)
			(island_removal_mode 0)
		)
		(polygon
			(pts
				(arc
					(start 384.96113 -397.156432)
					(mid 384.58013 -397.156432)
					(end 384.96113 -397.156432)
				)
			)
		)
	)
	(zone
		(layer "In1.Cu")
		(hatch none 0.5)
		(connect_pads
			(clearance 0)
		)
		(min_thickness 0.25)
		(keepout
			(tracks not_allowed)
			(vias allowed)
			(pads allowed)
			(copperpour not_allowed)
			(footprints allowed)
		)
		(placement
			(enabled no)
			(sheetname "")
		)
		(fill
			(thermal_gap 0.5)
			(thermal_bridge_width 0.5)
			(island_removal_mode 0)
		)
		(polygon
			(pts
				(arc
					(start 18.357342 -235.832396)
					(mid 18.353622 -235.841376)
					(end 18.344642 -235.845096)
				)
				(arc
					(start 16.871442 -235.845096)
					(mid 16.862462 -235.841376)
					(end 16.858742 -235.832396)
				)
				(arc
					(start 16.858742 -235.337858)
					(mid 16.862462 -235.328878)
					(end 16.871442 -235.325158)
				)
				(arc
					(start 18.344642 -235.325158)
					(mid 18.353622 -235.328878)
					(end 18.357342 -235.337858)
				)
			)
		)
	)
	(zone
		(layer "In1.Cu")
		(hatch none 0.5)
		(connect_pads
			(clearance 0)
		)
		(min_thickness 0.25)
		(keepout
			(tracks not_allowed)
			(vias allowed)
			(pads allowed)
			(copperpour not_allowed)
			(footprints allowed)
		)
		(placement
			(enabled no)
			(sheetname "")
		)
		(fill
			(thermal_gap 0.5)
			(thermal_bridge_width 0.5)
			(island_removal_mode 0)
		)
		(polygon
			(pts
				(arc
					(start 169.277284 -210.332574)
					(mid 169.273564 -210.341554)
					(end 169.264584 -210.345274)
				)
				(arc
					(start 167.791384 -210.345274)
					(mid 167.782404 -210.341554)
					(end 167.778684 -210.332574)
				)
				(arc
					(start 167.778684 -209.838036)
					(mid 167.782404 -209.829056)
					(end 167.791384 -209.825336)
				)
				(arc
					(start 169.264584 -209.825336)
					(mid 169.273564 -209.829056)
					(end 169.277284 -209.838036)
				)
			)
		)
	)
	(zone
		(layer "In1.Cu")
		(hatch none 0.5)
		(connect_pads
			(clearance 0)
		)
		(min_thickness 0.25)
		(keepout
			(tracks not_allowed)
			(vias allowed)
			(pads allowed)
			(copperpour not_allowed)
			(footprints allowed)
		)
		(placement
			(enabled no)
			(sheetname "")
		)
		(fill
			(thermal_gap 0.5)
			(thermal_bridge_width 0.5)
			(island_removal_mode 0)
		)
		(polygon
			(pts
				(arc
					(start 296.473372 -302.982122)
					(mid 296.469652 -302.991102)
					(end 296.460672 -302.994822)
				)
				(arc
					(start 294.987472 -302.994822)
					(mid 294.978492 -302.991102)
					(end 294.974772 -302.982122)
				)
				(arc
					(start 294.974772 -302.487584)
					(mid 294.978492 -302.478604)
					(end 294.987472 -302.474884)
				)
				(arc
					(start 296.460672 -302.474884)
					(mid 296.469652 -302.478604)
					(end 296.473372 -302.487584)
				)
			)
		)
	)
	(zone
		(layer "In1.Cu")
		(hatch none 0.5)
		(connect_pads
			(clearance 0)
		)
		(min_thickness 0.25)
		(keepout
			(tracks not_allowed)
			(vias allowed)
			(pads allowed)
			(copperpour not_allowed)
			(footprints allowed)
		)
		(placement
			(enabled no)
			(sheetname "")
		)
		(fill
			(thermal_gap 0.5)
			(thermal_bridge_width 0.5)
			(island_removal_mode 0)
		)
		(polygon
			(pts
				(arc
					(start 30.001464 -227.33254)
					(mid 29.997744 -227.34152)
					(end 29.988764 -227.34524)
				)
				(arc
					(start 28.515564 -227.34524)
					(mid 28.506584 -227.34152)
					(end 28.502864 -227.33254)
				)
				(arc
					(start 28.502864 -226.838002)
					(mid 28.506584 -226.829022)
					(end 28.515564 -226.825302)
				)
				(arc
					(start 29.988764 -226.825302)
					(mid 29.997744 -226.829022)
					(end 30.001464 -226.838002)
				)
			)
		)
	)
	(zone
		(layer "In1.Cu")
		(hatch none 0.5)
		(connect_pads
			(clearance 0)
		)
		(min_thickness 0.25)
		(keepout
			(tracks not_allowed)
			(vias allowed)
			(pads allowed)
			(copperpour not_allowed)
			(footprints allowed)
		)
		(placement
			(enabled no)
			(sheetname "")
		)
		(fill
			(thermal_gap 0.5)
			(thermal_bridge_width 0.5)
			(island_removal_mode 0)
		)
		(polygon
			(pts
				(arc
					(start 22.45741 -275.782532)
					(mid 22.45369 -275.791512)
					(end 22.44471 -275.795232)
				)
				(arc
					(start 20.97151 -275.795232)
					(mid 20.96253 -275.791512)
					(end 20.95881 -275.782532)
				)
				(arc
					(start 20.95881 -275.287994)
					(mid 20.96253 -275.279014)
					(end 20.97151 -275.275294)
				)
				(arc
					(start 22.44471 -275.275294)
					(mid 22.45369 -275.279014)
					(end 22.45741 -275.287994)
				)
			)
		)
	)
	(zone
		(layer "In1.Cu")
		(hatch none 0.5)
		(connect_pads
			(clearance 0)
		)
		(min_thickness 0.25)
		(keepout
			(tracks not_allowed)
			(vias allowed)
			(pads allowed)
			(copperpour not_allowed)
			(footprints allowed)
		)
		(placement
			(enabled no)
			(sheetname "")
		)
		(fill
			(thermal_gap 0.5)
			(thermal_bridge_width 0.5)
			(island_removal_mode 0)
		)
		(polygon
			(pts
				(arc
					(start 374.891046 -399.701258)
					(mid 375.018046 -399.828258)
					(end 375.145046 -399.701258)
				)
				(arc
					(start 375.145046 -399.625058)
					(mid 375.018046 -399.498058)
					(end 374.891046 -399.625058)
				)
			)
		)
	)
	(zone
		(layer "In1.Cu")
		(hatch none 0.5)
		(connect_pads
			(clearance 0)
		)
		(min_thickness 0.25)
		(keepout
			(tracks not_allowed)
			(vias allowed)
			(pads allowed)
			(copperpour not_allowed)
			(footprints allowed)
		)
		(placement
			(enabled no)
			(sheetname "")
		)
		(fill
			(thermal_gap 0.5)
			(thermal_bridge_width 0.5)
			(island_removal_mode 0)
		)
		(polygon
			(pts
				(arc
					(start 419.088824 -394.385292)
					(mid 418.707824 -394.385292)
					(end 419.088824 -394.385292)
				)
			)
		)
	)
	(zone
		(layer "In1.Cu")
		(hatch none 0.5)
		(connect_pads
			(clearance 0)
		)
		(min_thickness 0.25)
		(keepout
			(tracks not_allowed)
			(vias allowed)
			(pads allowed)
			(copperpour not_allowed)
			(footprints allowed)
		)
		(placement
			(enabled no)
			(sheetname "")
		)
		(fill
			(thermal_gap 0.5)
			(thermal_bridge_width 0.5)
			(island_removal_mode 0)
		)
		(polygon
			(pts
				(arc
					(start 62.590934 -391.319258)
					(mid 62.717934 -391.446258)
					(end 62.844934 -391.319258)
				)
				(arc
					(start 62.844934 -391.243058)
					(mid 62.717934 -391.116058)
					(end 62.590934 -391.243058)
				)
			)
		)
	)
	(zone
		(layer "In1.Cu")
		(hatch none 0.5)
		(connect_pads
			(clearance 0)
		)
		(min_thickness 0.25)
		(keepout
			(tracks not_allowed)
			(vias allowed)
			(pads allowed)
			(copperpour not_allowed)
			(footprints allowed)
		)
		(placement
			(enabled no)
			(sheetname "")
		)
		(fill
			(thermal_gap 0.5)
			(thermal_bridge_width 0.5)
			(island_removal_mode 0)
		)
		(polygon
			(pts
				(arc
					(start 450.8373 -295.33215)
					(mid 450.83358 -295.34113)
					(end 450.8246 -295.34485)
				)
				(arc
					(start 449.3514 -295.34485)
					(mid 449.34242 -295.34113)
					(end 449.3387 -295.33215)
				)
				(arc
					(start 449.3387 -294.837612)
					(mid 449.34242 -294.828632)
					(end 449.3514 -294.824912)
				)
				(arc
					(start 450.8246 -294.824912)
					(mid 450.83358 -294.828632)
					(end 450.8373 -294.837612)
				)
			)
		)
	)
	(zone
		(layer "In1.Cu")
		(hatch none 0.5)
		(connect_pads
			(clearance 0)
		)
		(min_thickness 0.25)
		(keepout
			(tracks not_allowed)
			(vias allowed)
			(pads allowed)
			(copperpour not_allowed)
			(footprints allowed)
		)
		(placement
			(enabled no)
			(sheetname "")
		)
		(fill
			(thermal_gap 0.5)
			(thermal_bridge_width 0.5)
			(island_removal_mode 0)
		)
		(polygon
			(pts
				(arc
					(start 288.929318 -276.632162)
					(mid 288.925598 -276.641142)
					(end 288.916618 -276.644862)
				)
				(arc
					(start 287.443418 -276.644862)
					(mid 287.434438 -276.641142)
					(end 287.430718 -276.632162)
				)
				(arc
					(start 287.430718 -276.137624)
					(mid 287.434438 -276.128644)
					(end 287.443418 -276.124924)
				)
				(arc
					(start 288.916618 -276.124924)
					(mid 288.925598 -276.128644)
					(end 288.929318 -276.137624)
				)
			)
		)
	)
	(zone
		(layer "In1.Cu")
		(hatch none 0.5)
		(connect_pads
			(clearance 0)
		)
		(min_thickness 0.25)
		(keepout
			(tracks not_allowed)
			(vias allowed)
			(pads allowed)
			(copperpour not_allowed)
			(footprints allowed)
		)
		(placement
			(enabled no)
			(sheetname "")
		)
		(fill
			(thermal_gap 0.5)
			(thermal_bridge_width 0.5)
			(island_removal_mode 0)
		)
		(polygon
			(pts
				(arc
					(start 386.270246 -399.143474)
					(mid 385.965446 -399.143474)
					(end 386.270246 -399.143474)
				)
			)
		)
	)
	(zone
		(layer "In1.Cu")
		(hatch none 0.5)
		(connect_pads
			(clearance 0)
		)
		(min_thickness 0.25)
		(keepout
			(tracks not_allowed)
			(vias allowed)
			(pads allowed)
			(copperpour not_allowed)
			(footprints allowed)
		)
		(placement
			(enabled no)
			(sheetname "")
		)
		(fill
			(thermal_gap 0.5)
			(thermal_bridge_width 0.5)
			(island_removal_mode 0)
		)
		(polygon
			(pts
				(arc
					(start 45.089318 -223.932496)
					(mid 45.085598 -223.941476)
					(end 45.076618 -223.945196)
				)
				(arc
					(start 43.603418 -223.945196)
					(mid 43.594438 -223.941476)
					(end 43.590718 -223.932496)
				)
				(arc
					(start 43.590718 -223.437958)
					(mid 43.594438 -223.428978)
					(end 43.603418 -223.425258)
				)
				(arc
					(start 45.076618 -223.425258)
					(mid 45.085598 -223.428978)
					(end 45.089318 -223.437958)
				)
			)
		)
	)
	(zone
		(layer "In1.Cu")
		(hatch none 0.5)
		(connect_pads
			(clearance 0)
		)
		(min_thickness 0.25)
		(keepout
			(tracks not_allowed)
			(vias allowed)
			(pads allowed)
			(copperpour not_allowed)
			(footprints allowed)
		)
		(placement
			(enabled no)
			(sheetname "")
		)
		(fill
			(thermal_gap 0.5)
			(thermal_bridge_width 0.5)
			(island_removal_mode 0)
		)
		(polygon
			(pts
				(arc
					(start 199.4535 -254.532384)
					(mid 199.44978 -254.541364)
					(end 199.4408 -254.545084)
				)
				(arc
					(start 197.9676 -254.545084)
					(mid 197.95862 -254.541364)
					(end 197.9549 -254.532384)
				)
				(arc
					(start 197.9549 -254.037846)
					(mid 197.95862 -254.028866)
					(end 197.9676 -254.025146)
				)
				(arc
					(start 199.4408 -254.025146)
					(mid 199.44978 -254.028866)
					(end 199.4535 -254.037846)
				)
			)
		)
	)
	(zone
		(layer "In1.Cu")
		(hatch none 0.5)
		(connect_pads
			(clearance 0)
		)
		(min_thickness 0.25)
		(keepout
			(tracks not_allowed)
			(vias allowed)
			(pads allowed)
			(copperpour not_allowed)
			(footprints allowed)
		)
		(placement
			(enabled no)
			(sheetname "")
		)
		(fill
			(thermal_gap 0.5)
			(thermal_bridge_width 0.5)
			(island_removal_mode 0)
		)
		(polygon
			(pts
				(arc
					(start 304.017426 -209.482182)
					(mid 304.013706 -209.491162)
					(end 304.004726 -209.494882)
				)
				(arc
					(start 302.531526 -209.494882)
					(mid 302.522546 -209.491162)
					(end 302.518826 -209.482182)
				)
				(arc
					(start 302.518826 -208.987644)
					(mid 302.522546 -208.978664)
					(end 302.531526 -208.974944)
				)
				(arc
					(start 304.004726 -208.974944)
					(mid 304.013706 -208.978664)
					(end 304.017426 -208.987644)
				)
			)
		)
	)
	(zone
		(layer "In1.Cu")
		(hatch none 0.5)
		(connect_pads
			(clearance 0)
		)
		(min_thickness 0.25)
		(keepout
			(tracks not_allowed)
			(vias allowed)
			(pads allowed)
			(copperpour not_allowed)
			(footprints allowed)
		)
		(placement
			(enabled no)
			(sheetname "")
		)
		(fill
			(thermal_gap 0.5)
			(thermal_bridge_width 0.5)
			(island_removal_mode 0)
		)
		(polygon
			(pts
				(arc
					(start 270.397478 -309.78221)
					(mid 270.393758 -309.79119)
					(end 270.384778 -309.79491)
				)
				(arc
					(start 268.911578 -309.79491)
					(mid 268.902598 -309.79119)
					(end 268.898878 -309.78221)
				)
				(arc
					(start 268.898878 -309.287672)
					(mid 268.902598 -309.278692)
					(end 268.911578 -309.274972)
				)
				(arc
					(start 270.384778 -309.274972)
					(mid 270.393758 -309.278692)
					(end 270.397478 -309.287672)
				)
			)
		)
	)
	(zone
		(layer "In1.Cu")
		(hatch none 0.5)
		(connect_pads
			(clearance 0)
		)
		(min_thickness 0.25)
		(keepout
			(tracks not_allowed)
			(vias allowed)
			(pads allowed)
			(copperpour not_allowed)
			(footprints allowed)
		)
		(placement
			(enabled no)
			(sheetname "")
		)
		(fill
			(thermal_gap 0.5)
			(thermal_bridge_width 0.5)
			(island_removal_mode 0)
		)
		(polygon
			(pts
				(arc
					(start 277.941532 -270.682212)
					(mid 277.937812 -270.691192)
					(end 277.928832 -270.694912)
				)
				(arc
					(start 276.455632 -270.694912)
					(mid 276.446652 -270.691192)
					(end 276.442932 -270.682212)
				)
				(arc
					(start 276.442932 -270.187674)
					(mid 276.446652 -270.178694)
					(end 276.455632 -270.174974)
				)
				(arc
					(start 277.928832 -270.174974)
					(mid 277.937812 -270.178694)
					(end 277.941532 -270.187674)
				)
			)
		)
	)
	(zone
		(layer "In1.Cu")
		(hatch none 0.5)
		(connect_pads
			(clearance 0)
		)
		(min_thickness 0.25)
		(keepout
			(tracks not_allowed)
			(vias allowed)
			(pads allowed)
			(copperpour not_allowed)
			(footprints allowed)
		)
		(placement
			(enabled no)
			(sheetname "")
		)
		(fill
			(thermal_gap 0.5)
			(thermal_bridge_width 0.5)
			(island_removal_mode 0)
		)
		(polygon
			(pts
				(arc
					(start 206.9973 -304.682398)
					(mid 206.99358 -304.691378)
					(end 206.9846 -304.695098)
				)
				(arc
					(start 205.5114 -304.695098)
					(mid 205.50242 -304.691378)
					(end 205.4987 -304.682398)
				)
				(arc
					(start 205.4987 -304.18786)
					(mid 205.50242 -304.17888)
					(end 205.5114 -304.17516)
				)
				(arc
					(start 206.9846 -304.17516)
					(mid 206.99358 -304.17888)
					(end 206.9973 -304.18786)
				)
			)
		)
	)
	(zone
		(layer "In1.Cu")
		(hatch none 0.5)
		(connect_pads
			(clearance 0)
		)
		(min_thickness 0.25)
		(keepout
			(tracks not_allowed)
			(vias allowed)
			(pads allowed)
			(copperpour not_allowed)
			(footprints allowed)
		)
		(placement
			(enabled no)
			(sheetname "")
		)
		(fill
			(thermal_gap 0.5)
			(thermal_bridge_width 0.5)
			(island_removal_mode 0)
		)
		(polygon
			(pts
				(arc
					(start 293.029386 -280.032206)
					(mid 293.025666 -280.041186)
					(end 293.016686 -280.044906)
				)
				(arc
					(start 291.543486 -280.044906)
					(mid 291.534506 -280.041186)
					(end 291.530786 -280.032206)
				)
				(arc
					(start 291.530786 -279.537668)
					(mid 291.534506 -279.528688)
					(end 291.543486 -279.524968)
				)
				(arc
					(start 293.016686 -279.524968)
					(mid 293.025666 -279.528688)
					(end 293.029386 -279.537668)
				)
			)
		)
	)
	(zone
		(layer "In1.Cu")
		(hatch none 0.5)
		(connect_pads
			(clearance 0)
		)
		(min_thickness 0.25)
		(keepout
			(tracks not_allowed)
			(vias allowed)
			(pads allowed)
			(copperpour not_allowed)
			(footprints allowed)
		)
		(placement
			(enabled no)
			(sheetname "")
		)
		(fill
			(thermal_gap 0.5)
			(thermal_bridge_width 0.5)
			(island_removal_mode 0)
		)
		(polygon
			(pts
				(arc
					(start 206.5782 -247.485408)
					(mid 205.9178 -247.485408)
					(end 206.5782 -247.485408)
				)
			)
		)
	)
	(zone
		(layer "In1.Cu")
		(hatch none 0.5)
		(connect_pads
			(clearance 0)
		)
		(min_thickness 0.25)
		(keepout
			(tracks not_allowed)
			(vias allowed)
			(pads allowed)
			(copperpour not_allowed)
			(footprints allowed)
		)
		(placement
			(enabled no)
			(sheetname "")
		)
		(fill
			(thermal_gap 0.5)
			(thermal_bridge_width 0.5)
			(island_removal_mode 0)
		)
		(polygon
			(pts
				(arc
					(start 18.357342 -318.282574)
					(mid 18.353622 -318.291554)
					(end 18.344642 -318.295274)
				)
				(arc
					(start 16.871442 -318.295274)
					(mid 16.862462 -318.291554)
					(end 16.858742 -318.282574)
				)
				(arc
					(start 16.858742 -317.788036)
					(mid 16.862462 -317.779056)
					(end 16.871442 -317.775336)
				)
				(arc
					(start 18.344642 -317.775336)
					(mid 18.353622 -317.779056)
					(end 18.357342 -317.788036)
				)
			)
		)
	)
	(zone
		(layer "In1.Cu")
		(hatch none 0.5)
		(connect_pads
			(clearance 0)
		)
		(min_thickness 0.25)
		(keepout
			(tracks not_allowed)
			(vias allowed)
			(pads allowed)
			(copperpour not_allowed)
			(footprints allowed)
		)
		(placement
			(enabled no)
			(sheetname "")
		)
		(fill
			(thermal_gap 0.5)
			(thermal_bridge_width 0.5)
			(island_removal_mode 0)
		)
		(polygon
			(pts
				(arc
					(start 180.265324 -304.682398)
					(mid 180.261604 -304.691378)
					(end 180.252624 -304.695098)
				)
				(arc
					(start 178.779424 -304.695098)
					(mid 178.770444 -304.691378)
					(end 178.766724 -304.682398)
				)
				(arc
					(start 178.766724 -304.18786)
					(mid 178.770444 -304.17888)
					(end 178.779424 -304.17516)
				)
				(arc
					(start 180.252624 -304.17516)
					(mid 180.261604 -304.17888)
					(end 180.265324 -304.18786)
				)
			)
		)
	)
	(zone
		(layer "In1.Cu")
		(hatch none 0.5)
		(connect_pads
			(clearance 0)
		)
		(min_thickness 0.25)
		(keepout
			(tracks not_allowed)
			(vias allowed)
			(pads allowed)
			(copperpour not_allowed)
			(footprints allowed)
		)
		(placement
			(enabled no)
			(sheetname "")
		)
		(fill
			(thermal_gap 0.5)
			(thermal_bridge_width 0.5)
			(island_removal_mode 0)
		)
		(polygon
			(pts
				(arc
					(start 277.941532 -200.982326)
					(mid 277.937812 -200.991306)
					(end 277.928832 -200.995026)
				)
				(arc
					(start 276.455632 -200.995026)
					(mid 276.446652 -200.991306)
					(end 276.442932 -200.982326)
				)
				(arc
					(start 276.442932 -200.487788)
					(mid 276.446652 -200.478808)
					(end 276.455632 -200.475088)
				)
				(arc
					(start 277.928832 -200.475088)
					(mid 277.937812 -200.478808)
					(end 277.941532 -200.487788)
				)
			)
		)
	)
	(zone
		(layer "In1.Cu")
		(hatch none 0.5)
		(connect_pads
			(clearance 0)
		)
		(min_thickness 0.25)
		(keepout
			(tracks not_allowed)
			(vias allowed)
			(pads allowed)
			(copperpour not_allowed)
			(footprints allowed)
		)
		(placement
			(enabled no)
			(sheetname "")
		)
		(fill
			(thermal_gap 0.5)
			(thermal_bridge_width 0.5)
			(island_removal_mode 0)
		)
		(polygon
			(pts
				(arc
					(start 30.001464 -317.432436)
					(mid 29.997744 -317.441416)
					(end 29.988764 -317.445136)
				)
				(arc
					(start 28.515564 -317.445136)
					(mid 28.506584 -317.441416)
					(end 28.502864 -317.432436)
				)
				(arc
					(start 28.502864 -316.937898)
					(mid 28.506584 -316.928918)
					(end 28.515564 -316.925198)
				)
				(arc
					(start 29.988764 -316.925198)
					(mid 29.997744 -316.928918)
					(end 30.001464 -316.937898)
				)
			)
		)
	)
	(zone
		(layer "In1.Cu")
		(hatch none 0.5)
		(connect_pads
			(clearance 0)
		)
		(min_thickness 0.25)
		(keepout
			(tracks not_allowed)
			(vias allowed)
			(pads allowed)
			(copperpour not_allowed)
			(footprints allowed)
		)
		(placement
			(enabled no)
			(sheetname "")
		)
		(fill
			(thermal_gap 0.5)
			(thermal_bridge_width 0.5)
			(island_removal_mode 0)
		)
		(polygon
			(pts
				(arc
					(start 52.633372 -303.832514)
					(mid 52.629652 -303.841494)
					(end 52.620672 -303.845214)
				)
				(arc
					(start 51.147472 -303.845214)
					(mid 51.138492 -303.841494)
					(end 51.134772 -303.832514)
				)
				(arc
					(start 51.134772 -303.337976)
					(mid 51.138492 -303.328996)
					(end 51.147472 -303.325276)
				)
				(arc
					(start 52.620672 -303.325276)
					(mid 52.629652 -303.328996)
					(end 52.633372 -303.337976)
				)
			)
		)
	)
	(zone
		(layer "In1.Cu")
		(hatch none 0.5)
		(connect_pads
			(clearance 0)
		)
		(min_thickness 0.25)
		(keepout
			(tracks not_allowed)
			(vias allowed)
			(pads allowed)
			(copperpour not_allowed)
			(footprints allowed)
		)
		(placement
			(enabled no)
			(sheetname "")
		)
		(fill
			(thermal_gap 0.5)
			(thermal_bridge_width 0.5)
			(island_removal_mode 0)
		)
		(polygon
			(pts
				(arc
					(start 52.633372 -242.632484)
					(mid 52.629652 -242.641464)
					(end 52.620672 -242.645184)
				)
				(arc
					(start 51.147472 -242.645184)
					(mid 51.138492 -242.641464)
					(end 51.134772 -242.632484)
				)
				(arc
					(start 51.134772 -242.137946)
					(mid 51.138492 -242.128966)
					(end 51.147472 -242.125246)
				)
				(arc
					(start 52.620672 -242.125246)
					(mid 52.629652 -242.128966)
					(end 52.633372 -242.137946)
				)
			)
		)
	)
	(zone
		(layer "In1.Cu")
		(hatch none 0.5)
		(connect_pads
			(clearance 0)
		)
		(min_thickness 0.25)
		(keepout
			(tracks not_allowed)
			(vias allowed)
			(pads allowed)
			(copperpour not_allowed)
			(footprints allowed)
		)
		(placement
			(enabled no)
			(sheetname "")
		)
		(fill
			(thermal_gap 0.5)
			(thermal_bridge_width 0.5)
			(island_removal_mode 0)
		)
		(polygon
			(pts
				(arc
					(start 281.385264 -221.382082)
					(mid 281.381544 -221.391062)
					(end 281.372564 -221.394782)
				)
				(arc
					(start 279.899364 -221.394782)
					(mid 279.890384 -221.391062)
					(end 279.886664 -221.382082)
				)
				(arc
					(start 279.886664 -220.887544)
					(mid 279.890384 -220.878564)
					(end 279.899364 -220.874844)
				)
				(arc
					(start 281.372564 -220.874844)
					(mid 281.381544 -220.878564)
					(end 281.385264 -220.887544)
				)
			)
		)
	)
	(zone
		(layer "In1.Cu")
		(hatch none 0.5)
		(connect_pads
			(clearance 0)
		)
		(min_thickness 0.25)
		(keepout
			(tracks not_allowed)
			(vias allowed)
			(pads allowed)
			(copperpour not_allowed)
			(footprints allowed)
		)
		(placement
			(enabled no)
			(sheetname "")
		)
		(fill
			(thermal_gap 0.5)
			(thermal_bridge_width 0.5)
			(island_removal_mode 0)
		)
		(polygon
			(pts
				(arc
					(start 454.937368 -233.282236)
					(mid 454.933648 -233.291216)
					(end 454.924668 -233.294936)
				)
				(arc
					(start 453.451468 -233.294936)
					(mid 453.442488 -233.291216)
					(end 453.438768 -233.282236)
				)
				(arc
					(start 453.438768 -232.787698)
					(mid 453.442488 -232.778718)
					(end 453.451468 -232.774998)
				)
				(arc
					(start 454.924668 -232.774998)
					(mid 454.933648 -232.778718)
					(end 454.937368 -232.787698)
				)
			)
		)
	)
	(zone
		(layer "In1.Cu")
		(hatch none 0.5)
		(connect_pads
			(clearance 0)
		)
		(min_thickness 0.25)
		(keepout
			(tracks not_allowed)
			(vias allowed)
			(pads allowed)
			(copperpour not_allowed)
			(footprints allowed)
		)
		(placement
			(enabled no)
			(sheetname "")
		)
		(fill
			(thermal_gap 0.5)
			(thermal_bridge_width 0.5)
			(island_removal_mode 0)
		)
		(polygon
			(pts
				(arc
					(start 346.318586 -391.822686)
					(mid 346.445586 -391.949686)
					(end 346.572586 -391.822686)
				)
				(arc
					(start 346.572586 -391.746486)
					(mid 346.445586 -391.619486)
					(end 346.318586 -391.746486)
				)
			)
		)
	)
	(zone
		(layer "In1.Cu")
		(hatch none 0.5)
		(connect_pads
			(clearance 0)
		)
		(min_thickness 0.25)
		(keepout
			(tracks not_allowed)
			(vias allowed)
			(pads allowed)
			(copperpour not_allowed)
			(footprints allowed)
		)
		(placement
			(enabled no)
			(sheetname "")
		)
		(fill
			(thermal_gap 0.5)
			(thermal_bridge_width 0.5)
			(island_removal_mode 0)
		)
		(polygon
			(pts
				(arc
					(start 428.205392 -263.882124)
					(mid 428.201672 -263.891104)
					(end 428.192692 -263.894824)
				)
				(arc
					(start 426.719492 -263.894824)
					(mid 426.710512 -263.891104)
					(end 426.706792 -263.882124)
				)
				(arc
					(start 426.706792 -263.387586)
					(mid 426.710512 -263.378606)
					(end 426.719492 -263.374886)
				)
				(arc
					(start 428.192692 -263.374886)
					(mid 428.201672 -263.378606)
					(end 428.205392 -263.387586)
				)
			)
		)
	)
	(zone
		(layer "In1.Cu")
		(hatch none 0.5)
		(connect_pads
			(clearance 0)
		)
		(min_thickness 0.25)
		(keepout
			(tracks not_allowed)
			(vias allowed)
			(pads allowed)
			(copperpour not_allowed)
			(footprints allowed)
		)
		(placement
			(enabled no)
			(sheetname "")
		)
		(fill
			(thermal_gap 0.5)
			(thermal_bridge_width 0.5)
			(island_removal_mode 0)
		)
		(polygon
			(pts
				(arc
					(start 443.2935 -201.83221)
					(mid 443.28978 -201.84119)
					(end 443.2808 -201.84491)
				)
				(arc
					(start 441.8076 -201.84491)
					(mid 441.79862 -201.84119)
					(end 441.7949 -201.83221)
				)
				(arc
					(start 441.7949 -201.337672)
					(mid 441.79862 -201.328692)
					(end 441.8076 -201.324972)
				)
				(arc
					(start 443.2808 -201.324972)
					(mid 443.28978 -201.328692)
					(end 443.2935 -201.337672)
				)
			)
		)
	)
	(zone
		(layer "In1.Cu")
		(hatch none 0.5)
		(connect_pads
			(clearance 0)
		)
		(min_thickness 0.25)
		(keepout
			(tracks not_allowed)
			(vias allowed)
			(pads allowed)
			(copperpour not_allowed)
			(footprints allowed)
		)
		(placement
			(enabled no)
			(sheetname "")
		)
		(fill
			(thermal_gap 0.5)
			(thermal_bridge_width 0.5)
			(island_removal_mode 0)
		)
		(polygon
			(pts
				(arc
					(start 59.4614 -388.774432)
					(mid 59.0804 -388.774432)
					(end 59.4614 -388.774432)
				)
			)
		)
	)
	(zone
		(layer "In1.Cu")
		(hatch none 0.5)
		(connect_pads
			(clearance 0)
		)
		(min_thickness 0.25)
		(keepout
			(tracks not_allowed)
			(vias allowed)
			(pads allowed)
			(copperpour not_allowed)
			(footprints allowed)
		)
		(placement
			(enabled no)
			(sheetname "")
		)
		(fill
			(thermal_gap 0.5)
			(thermal_bridge_width 0.5)
			(island_removal_mode 0)
		)
		(polygon
			(pts
				(arc
					(start 304.017426 -234.13212)
					(mid 304.013706 -234.1411)
					(end 304.004726 -234.14482)
				)
				(arc
					(start 302.531526 -234.14482)
					(mid 302.522546 -234.1411)
					(end 302.518826 -234.13212)
				)
				(arc
					(start 302.518826 -233.637582)
					(mid 302.522546 -233.628602)
					(end 302.531526 -233.624882)
				)
				(arc
					(start 304.004726 -233.624882)
					(mid 304.013706 -233.628602)
					(end 304.017426 -233.637582)
				)
			)
		)
	)
	(zone
		(layer "In1.Cu")
		(hatch none 0.5)
		(connect_pads
			(clearance 0)
		)
		(min_thickness 0.25)
		(keepout
			(tracks not_allowed)
			(vias allowed)
			(pads allowed)
			(copperpour not_allowed)
			(footprints allowed)
		)
		(placement
			(enabled no)
			(sheetname "")
		)
		(fill
			(thermal_gap 0.5)
			(thermal_bridge_width 0.5)
			(island_removal_mode 0)
		)
		(polygon
			(pts
				(arc
					(start 172.72127 -229.882446)
					(mid 172.71755 -229.891426)
					(end 172.70857 -229.895146)
				)
				(arc
					(start 171.23537 -229.895146)
					(mid 171.22639 -229.891426)
					(end 171.22267 -229.882446)
				)
				(arc
					(start 171.22267 -229.387908)
					(mid 171.22639 -229.378928)
					(end 171.23537 -229.375208)
				)
				(arc
					(start 172.70857 -229.375208)
					(mid 172.71755 -229.378928)
					(end 172.72127 -229.387908)
				)
			)
		)
	)
	(zone
		(layer "In1.Cu")
		(hatch none 0.5)
		(connect_pads
			(clearance 0)
		)
		(min_thickness 0.25)
		(keepout
			(tracks not_allowed)
			(vias allowed)
			(pads allowed)
			(copperpour not_allowed)
			(footprints allowed)
		)
		(placement
			(enabled no)
			(sheetname "")
		)
		(fill
			(thermal_gap 0.5)
			(thermal_bridge_width 0.5)
			(island_removal_mode 0)
		)
		(polygon
			(pts
				(arc
					(start 18.357342 -312.33237)
					(mid 18.353622 -312.34135)
					(end 18.344642 -312.34507)
				)
				(arc
					(start 16.871442 -312.34507)
					(mid 16.862462 -312.34135)
					(end 16.858742 -312.33237)
				)
				(arc
					(start 16.858742 -311.837832)
					(mid 16.862462 -311.828852)
					(end 16.871442 -311.825132)
				)
				(arc
					(start 18.344642 -311.825132)
					(mid 18.353622 -311.828852)
					(end 18.357342 -311.837832)
				)
			)
		)
	)
	(zone
		(layer "In1.Cu")
		(hatch none 0.5)
		(connect_pads
			(clearance 0)
		)
		(min_thickness 0.25)
		(keepout
			(tracks not_allowed)
			(vias allowed)
			(pads allowed)
			(copperpour not_allowed)
			(footprints allowed)
		)
		(placement
			(enabled no)
			(sheetname "")
		)
		(fill
			(thermal_gap 0.5)
			(thermal_bridge_width 0.5)
			(island_removal_mode 0)
		)
		(polygon
			(pts
				(arc
					(start 403.08911 -393.69238)
					(mid 402.70811 -393.69238)
					(end 403.08911 -393.69238)
				)
			)
		)
	)
	(zone
		(layer "In1.Cu")
		(hatch none 0.5)
		(connect_pads
			(clearance 0)
		)
		(min_thickness 0.25)
		(keepout
			(tracks not_allowed)
			(vias allowed)
			(pads allowed)
			(copperpour not_allowed)
			(footprints allowed)
		)
		(placement
			(enabled no)
			(sheetname "")
		)
		(fill
			(thermal_gap 0.5)
			(thermal_bridge_width 0.5)
			(island_removal_mode 0)
		)
		(polygon
			(pts
				(arc
					(start 432.30546 -229.032308)
					(mid 432.30174 -229.041288)
					(end 432.29276 -229.045008)
				)
				(arc
					(start 430.81956 -229.045008)
					(mid 430.81058 -229.041288)
					(end 430.80686 -229.032308)
				)
				(arc
					(start 430.80686 -228.53777)
					(mid 430.81058 -228.52879)
					(end 430.81956 -228.52507)
				)
				(arc
					(start 432.29276 -228.52507)
					(mid 432.30174 -228.52879)
					(end 432.30546 -228.53777)
				)
			)
		)
	)
	(zone
		(layer "In1.Cu")
		(hatch none 0.5)
		(connect_pads
			(clearance 0)
		)
		(min_thickness 0.25)
		(keepout
			(tracks not_allowed)
			(vias allowed)
			(pads allowed)
			(copperpour not_allowed)
			(footprints allowed)
		)
		(placement
			(enabled no)
			(sheetname "")
		)
		(fill
			(thermal_gap 0.5)
			(thermal_bridge_width 0.5)
			(island_removal_mode 0)
		)
		(polygon
			(pts
				(arc
					(start 443.2935 -230.73233)
					(mid 443.28978 -230.74131)
					(end 443.2808 -230.74503)
				)
				(arc
					(start 441.8076 -230.74503)
					(mid 441.79862 -230.74131)
					(end 441.7949 -230.73233)
				)
				(arc
					(start 441.7949 -230.237792)
					(mid 441.79862 -230.228812)
					(end 441.8076 -230.225092)
				)
				(arc
					(start 443.2808 -230.225092)
					(mid 443.28978 -230.228812)
					(end 443.2935 -230.237792)
				)
			)
		)
	)
	(zone
		(layer "In1.Cu")
		(hatch none 0.5)
		(connect_pads
			(clearance 0)
		)
		(min_thickness 0.25)
		(keepout
			(tracks not_allowed)
			(vias allowed)
			(pads allowed)
			(copperpour not_allowed)
			(footprints allowed)
		)
		(placement
			(enabled no)
			(sheetname "")
		)
		(fill
			(thermal_gap 0.5)
			(thermal_bridge_width 0.5)
			(island_removal_mode 0)
		)
		(polygon
			(pts
				(arc
					(start 308.117494 -298.732194)
					(mid 308.113774 -298.741174)
					(end 308.104794 -298.744894)
				)
				(arc
					(start 306.631594 -298.744894)
					(mid 306.622614 -298.741174)
					(end 306.618894 -298.732194)
				)
				(arc
					(start 306.618894 -298.237656)
					(mid 306.622614 -298.228676)
					(end 306.631594 -298.224956)
				)
				(arc
					(start 308.104794 -298.224956)
					(mid 308.113774 -298.228676)
					(end 308.117494 -298.237656)
				)
			)
		)
	)
	(zone
		(layer "In1.Cu")
		(hatch none 0.5)
		(connect_pads
			(clearance 0)
		)
		(min_thickness 0.25)
		(keepout
			(tracks not_allowed)
			(vias allowed)
			(pads allowed)
			(copperpour not_allowed)
			(footprints allowed)
		)
		(placement
			(enabled no)
			(sheetname "")
		)
		(fill
			(thermal_gap 0.5)
			(thermal_bridge_width 0.5)
			(island_removal_mode 0)
		)
		(polygon
			(pts
				(arc
					(start 114.090958 -383.440686)
					(mid 114.217958 -383.567686)
					(end 114.344958 -383.440686)
				)
				(arc
					(start 114.344958 -383.364486)
					(mid 114.217958 -383.237486)
					(end 114.090958 -383.364486)
				)
			)
		)
	)
	(zone
		(layer "In1.Cu")
		(hatch none 0.5)
		(connect_pads
			(clearance 0)
		)
		(min_thickness 0.25)
		(keepout
			(tracks not_allowed)
			(vias allowed)
			(pads allowed)
			(copperpour not_allowed)
			(footprints allowed)
		)
		(placement
			(enabled no)
			(sheetname "")
		)
		(fill
			(thermal_gap 0.5)
			(thermal_bridge_width 0.5)
			(island_removal_mode 0)
		)
		(polygon
			(pts
				(arc
					(start 410.398214 -392.30427)
					(mid 410.093414 -392.30427)
					(end 410.398214 -392.30427)
				)
			)
		)
	)
	(zone
		(layer "In1.Cu")
		(hatch none 0.5)
		(connect_pads
			(clearance 0)
		)
		(min_thickness 0.25)
		(keepout
			(tracks not_allowed)
			(vias allowed)
			(pads allowed)
			(copperpour not_allowed)
			(footprints allowed)
		)
		(placement
			(enabled no)
			(sheetname "")
		)
		(fill
			(thermal_gap 0.5)
			(thermal_bridge_width 0.5)
			(island_removal_mode 0)
		)
		(polygon
			(pts
				(arc
					(start 40.98925 -295.332404)
					(mid 40.98553 -295.341384)
					(end 40.97655 -295.345104)
				)
				(arc
					(start 39.50335 -295.345104)
					(mid 39.49437 -295.341384)
					(end 39.49065 -295.332404)
				)
				(arc
					(start 39.49065 -294.837866)
					(mid 39.49437 -294.828886)
					(end 39.50335 -294.825166)
				)
				(arc
					(start 40.97655 -294.825166)
					(mid 40.98553 -294.828886)
					(end 40.98925 -294.837866)
				)
			)
		)
	)
	(zone
		(layer "In1.Cu")
		(hatch none 0.5)
		(connect_pads
			(clearance 0)
		)
		(min_thickness 0.25)
		(keepout
			(tracks not_allowed)
			(vias allowed)
			(pads allowed)
			(copperpour not_allowed)
			(footprints allowed)
		)
		(placement
			(enabled no)
			(sheetname "")
		)
		(fill
			(thermal_gap 0.5)
			(thermal_bridge_width 0.5)
			(island_removal_mode 0)
		)
		(polygon
			(pts
				(arc
					(start 18.357342 -304.682398)
					(mid 18.353622 -304.691378)
					(end 18.344642 -304.695098)
				)
				(arc
					(start 16.871442 -304.695098)
					(mid 16.862462 -304.691378)
					(end 16.858742 -304.682398)
				)
				(arc
					(start 16.858742 -304.18786)
					(mid 16.862462 -304.17888)
					(end 16.871442 -304.17516)
				)
				(arc
					(start 18.344642 -304.17516)
					(mid 18.353622 -304.17888)
					(end 18.357342 -304.18786)
				)
			)
		)
	)
	(zone
		(layer "In1.Cu")
		(hatch none 0.5)
		(connect_pads
			(clearance 0)
		)
		(min_thickness 0.25)
		(keepout
			(tracks not_allowed)
			(vias allowed)
			(pads allowed)
			(copperpour not_allowed)
			(footprints allowed)
		)
		(placement
			(enabled no)
			(sheetname "")
		)
		(fill
			(thermal_gap 0.5)
			(thermal_bridge_width 0.5)
			(island_removal_mode 0)
		)
		(polygon
			(pts
				(arc
					(start 40.98925 -290.232592)
					(mid 40.98553 -290.241572)
					(end 40.97655 -290.245292)
				)
				(arc
					(start 39.50335 -290.245292)
					(mid 39.49437 -290.241572)
					(end 39.49065 -290.232592)
				)
				(arc
					(start 39.49065 -289.738054)
					(mid 39.49437 -289.729074)
					(end 39.50335 -289.725354)
				)
				(arc
					(start 40.97655 -289.725354)
					(mid 40.98553 -289.729074)
					(end 40.98925 -289.738054)
				)
			)
		)
	)
	(zone
		(layer "In1.Cu")
		(hatch none 0.5)
		(connect_pads
			(clearance 0)
		)
		(min_thickness 0.25)
		(keepout
			(tracks not_allowed)
			(vias allowed)
			(pads allowed)
			(copperpour not_allowed)
			(footprints allowed)
		)
		(placement
			(enabled no)
			(sheetname "")
		)
		(fill
			(thermal_gap 0.5)
			(thermal_bridge_width 0.5)
			(island_removal_mode 0)
		)
		(polygon
			(pts
				(arc
					(start 320.990722 -399.701258)
					(mid 321.117722 -399.828258)
					(end 321.244722 -399.701258)
				)
				(arc
					(start 321.244722 -399.625058)
					(mid 321.117722 -399.498058)
					(end 320.990722 -399.625058)
				)
			)
		)
	)
	(zone
		(layer "In1.Cu")
		(hatch none 0.5)
		(connect_pads
			(clearance 0)
		)
		(min_thickness 0.25)
		(keepout
			(tracks not_allowed)
			(vias allowed)
			(pads allowed)
			(copperpour not_allowed)
			(footprints allowed)
		)
		(placement
			(enabled no)
			(sheetname "")
		)
		(fill
			(thermal_gap 0.5)
			(thermal_bridge_width 0.5)
			(island_removal_mode 0)
		)
		(polygon
			(pts
				(arc
					(start 202.897232 -224.78238)
					(mid 202.893512 -224.79136)
					(end 202.884532 -224.79508)
				)
				(arc
					(start 201.411332 -224.79508)
					(mid 201.402352 -224.79136)
					(end 201.398632 -224.78238)
				)
				(arc
					(start 201.398632 -224.287842)
					(mid 201.402352 -224.278862)
					(end 201.411332 -224.275142)
				)
				(arc
					(start 202.884532 -224.275142)
					(mid 202.893512 -224.278862)
					(end 202.897232 -224.287842)
				)
			)
		)
	)
	(zone
		(layer "In1.Cu")
		(hatch none 0.5)
		(connect_pads
			(clearance 0)
		)
		(min_thickness 0.25)
		(keepout
			(tracks not_allowed)
			(vias allowed)
			(pads allowed)
			(copperpour not_allowed)
			(footprints allowed)
		)
		(placement
			(enabled no)
			(sheetname "")
		)
		(fill
			(thermal_gap 0.5)
			(thermal_bridge_width 0.5)
			(island_removal_mode 0)
		)
		(polygon
			(pts
				(arc
					(start 121.291096 -391.319258)
					(mid 121.418096 -391.446258)
					(end 121.545096 -391.319258)
				)
				(arc
					(start 121.545096 -391.243058)
					(mid 121.418096 -391.116058)
					(end 121.291096 -391.243058)
				)
			)
		)
	)
	(zone
		(layer "In1.Cu")
		(hatch none 0.5)
		(connect_pads
			(clearance 0)
		)
		(min_thickness 0.25)
		(keepout
			(tracks not_allowed)
			(vias allowed)
			(pads allowed)
			(copperpour not_allowed)
			(footprints allowed)
		)
		(placement
			(enabled no)
			(sheetname "")
		)
		(fill
			(thermal_gap 0.5)
			(thermal_bridge_width 0.5)
			(island_removal_mode 0)
		)
		(polygon
			(pts
				(arc
					(start 300.57344 -274.082256)
					(mid 300.56972 -274.091236)
					(end 300.56074 -274.094956)
				)
				(arc
					(start 299.08754 -274.094956)
					(mid 299.07856 -274.091236)
					(end 299.07484 -274.082256)
				)
				(arc
					(start 299.07484 -273.587718)
					(mid 299.07856 -273.578738)
					(end 299.08754 -273.575018)
				)
				(arc
					(start 300.56074 -273.575018)
					(mid 300.56972 -273.578738)
					(end 300.57344 -273.587718)
				)
			)
		)
	)
	(zone
		(layer "In1.Cu")
		(hatch none 0.5)
		(connect_pads
			(clearance 0)
		)
		(min_thickness 0.25)
		(keepout
			(tracks not_allowed)
			(vias allowed)
			(pads allowed)
			(copperpour not_allowed)
			(footprints allowed)
		)
		(placement
			(enabled no)
			(sheetname "")
		)
		(fill
			(thermal_gap 0.5)
			(thermal_bridge_width 0.5)
			(island_removal_mode 0)
		)
		(polygon
			(pts
				(arc
					(start 18.357342 -215.432386)
					(mid 18.353622 -215.441366)
					(end 18.344642 -215.445086)
				)
				(arc
					(start 16.871442 -215.445086)
					(mid 16.862462 -215.441366)
					(end 16.858742 -215.432386)
				)
				(arc
					(start 16.858742 -214.937848)
					(mid 16.862462 -214.928868)
					(end 16.871442 -214.925148)
				)
				(arc
					(start 18.344642 -214.925148)
					(mid 18.353622 -214.928868)
					(end 18.357342 -214.937848)
				)
			)
		)
	)
	(zone
		(layer "In1.Cu")
		(hatch none 0.5)
		(connect_pads
			(clearance 0)
		)
		(min_thickness 0.25)
		(keepout
			(tracks not_allowed)
			(vias allowed)
			(pads allowed)
			(copperpour not_allowed)
			(footprints allowed)
		)
		(placement
			(enabled no)
			(sheetname "")
		)
		(fill
			(thermal_gap 0.5)
			(thermal_bridge_width 0.5)
			(island_removal_mode 0)
		)
		(polygon
			(pts
				(arc
					(start 56.077358 -200.132442)
					(mid 56.073638 -200.141422)
					(end 56.064658 -200.145142)
				)
				(arc
					(start 54.591458 -200.145142)
					(mid 54.582478 -200.141422)
					(end 54.578758 -200.132442)
				)
				(arc
					(start 54.578758 -199.637904)
					(mid 54.582478 -199.628924)
					(end 54.591458 -199.625204)
				)
				(arc
					(start 56.064658 -199.625204)
					(mid 56.073638 -199.628924)
					(end 56.077358 -199.637904)
				)
			)
		)
	)
	(zone
		(layer "In1.Cu")
		(hatch none 0.5)
		(connect_pads
			(clearance 0)
		)
		(min_thickness 0.25)
		(keepout
			(tracks not_allowed)
			(vias allowed)
			(pads allowed)
			(copperpour not_allowed)
			(footprints allowed)
		)
		(placement
			(enabled no)
			(sheetname "")
		)
		(fill
			(thermal_gap 0.5)
			(thermal_bridge_width 0.5)
			(island_removal_mode 0)
		)
		(polygon
			(pts
				(arc
					(start 45.089318 -206.93253)
					(mid 45.085598 -206.94151)
					(end 45.076618 -206.94523)
				)
				(arc
					(start 43.603418 -206.94523)
					(mid 43.594438 -206.94151)
					(end 43.590718 -206.93253)
				)
				(arc
					(start 43.590718 -206.437992)
					(mid 43.594438 -206.429012)
					(end 43.603418 -206.425292)
				)
				(arc
					(start 45.076618 -206.425292)
					(mid 45.085598 -206.429012)
					(end 45.089318 -206.437992)
				)
			)
		)
	)
	(zone
		(layer "In1.Cu")
		(hatch none 0.5)
		(connect_pads
			(clearance 0)
		)
		(min_thickness 0.25)
		(keepout
			(tracks not_allowed)
			(vias allowed)
			(pads allowed)
			(copperpour not_allowed)
			(footprints allowed)
		)
		(placement
			(enabled no)
			(sheetname "")
		)
		(fill
			(thermal_gap 0.5)
			(thermal_bridge_width 0.5)
			(island_removal_mode 0)
		)
		(polygon
			(pts
				(arc
					(start 91.51874 -391.319258)
					(mid 91.64574 -391.446258)
					(end 91.77274 -391.319258)
				)
				(arc
					(start 91.77274 -391.243058)
					(mid 91.64574 -391.116058)
					(end 91.51874 -391.243058)
				)
			)
		)
	)
	(zone
		(layer "In1.Cu")
		(hatch none 0.5)
		(connect_pads
			(clearance 0)
		)
		(min_thickness 0.25)
		(keepout
			(tracks not_allowed)
			(vias allowed)
			(pads allowed)
			(copperpour not_allowed)
			(footprints allowed)
		)
		(placement
			(enabled no)
			(sheetname "")
		)
		(fill
			(thermal_gap 0.5)
			(thermal_bridge_width 0.5)
			(island_removal_mode 0)
		)
		(polygon
			(pts
				(arc
					(start 206.9973 -236.682534)
					(mid 206.99358 -236.691514)
					(end 206.9846 -236.695234)
				)
				(arc
					(start 205.5114 -236.695234)
					(mid 205.50242 -236.691514)
					(end 205.4987 -236.682534)
				)
				(arc
					(start 205.4987 -236.187996)
					(mid 205.50242 -236.179016)
					(end 205.5114 -236.175296)
				)
				(arc
					(start 206.9846 -236.175296)
					(mid 206.99358 -236.179016)
					(end 206.9973 -236.187996)
				)
			)
		)
	)
	(zone
		(layer "In1.Cu")
		(hatch none 0.5)
		(connect_pads
			(clearance 0)
		)
		(min_thickness 0.25)
		(keepout
			(tracks not_allowed)
			(vias allowed)
			(pads allowed)
			(copperpour not_allowed)
			(footprints allowed)
		)
		(placement
			(enabled no)
			(sheetname "")
		)
		(fill
			(thermal_gap 0.5)
			(thermal_bridge_width 0.5)
			(island_removal_mode 0)
		)
		(polygon
			(pts
				(arc
					(start 195.353432 -248.582434)
					(mid 195.349712 -248.591414)
					(end 195.340732 -248.595134)
				)
				(arc
					(start 193.867532 -248.595134)
					(mid 193.858552 -248.591414)
					(end 193.854832 -248.582434)
				)
				(arc
					(start 193.854832 -248.087896)
					(mid 193.858552 -248.078916)
					(end 193.867532 -248.075196)
				)
				(arc
					(start 195.340732 -248.075196)
					(mid 195.349712 -248.078916)
					(end 195.353432 -248.087896)
				)
			)
		)
	)
	(zone
		(layer "In1.Cu")
		(hatch none 0.5)
		(connect_pads
			(clearance 0)
		)
		(min_thickness 0.25)
		(keepout
			(tracks not_allowed)
			(vias allowed)
			(pads allowed)
			(copperpour not_allowed)
			(footprints allowed)
		)
		(placement
			(enabled no)
			(sheetname "")
		)
		(fill
			(thermal_gap 0.5)
			(thermal_bridge_width 0.5)
			(island_removal_mode 0)
		)
		(polygon
			(pts
				(arc
					(start 300.57344 -298.732194)
					(mid 300.56972 -298.741174)
					(end 300.56074 -298.744894)
				)
				(arc
					(start 299.08754 -298.744894)
					(mid 299.07856 -298.741174)
					(end 299.07484 -298.732194)
				)
				(arc
					(start 299.07484 -298.237656)
					(mid 299.07856 -298.228676)
					(end 299.08754 -298.224956)
				)
				(arc
					(start 300.56074 -298.224956)
					(mid 300.56972 -298.228676)
					(end 300.57344 -298.237656)
				)
			)
		)
	)
	(zone
		(layer "In1.Cu")
		(hatch none 0.5)
		(connect_pads
			(clearance 0)
		)
		(min_thickness 0.25)
		(keepout
			(tracks not_allowed)
			(vias allowed)
			(pads allowed)
			(copperpour not_allowed)
			(footprints allowed)
		)
		(placement
			(enabled no)
			(sheetname "")
		)
		(fill
			(thermal_gap 0.5)
			(thermal_bridge_width 0.5)
			(island_removal_mode 0)
		)
		(polygon
			(pts
				(arc
					(start 169.277284 -309.782464)
					(mid 169.273564 -309.791444)
					(end 169.264584 -309.795164)
				)
				(arc
					(start 167.791384 -309.795164)
					(mid 167.782404 -309.791444)
					(end 167.778684 -309.782464)
				)
				(arc
					(start 167.778684 -309.287926)
					(mid 167.782404 -309.278946)
					(end 167.791384 -309.275226)
				)
				(arc
					(start 169.264584 -309.275226)
					(mid 169.273564 -309.278946)
					(end 169.277284 -309.287926)
				)
			)
		)
	)
	(zone
		(layer "In1.Cu")
		(hatch none 0.5)
		(connect_pads
			(clearance 0)
		)
		(min_thickness 0.25)
		(keepout
			(tracks not_allowed)
			(vias allowed)
			(pads allowed)
			(copperpour not_allowed)
			(footprints allowed)
		)
		(placement
			(enabled no)
			(sheetname "")
		)
		(fill
			(thermal_gap 0.5)
			(thermal_bridge_width 0.5)
			(island_removal_mode 0)
		)
		(polygon
			(pts
				(arc
					(start 281.385264 -316.582298)
					(mid 281.381544 -316.591278)
					(end 281.372564 -316.594998)
				)
				(arc
					(start 279.899364 -316.594998)
					(mid 279.890384 -316.591278)
					(end 279.886664 -316.582298)
				)
				(arc
					(start 279.886664 -316.08776)
					(mid 279.890384 -316.07878)
					(end 279.899364 -316.07506)
				)
				(arc
					(start 281.372564 -316.07506)
					(mid 281.381544 -316.07878)
					(end 281.385264 -316.08776)
				)
			)
		)
	)
	(zone
		(layer "In1.Cu")
		(hatch none 0.5)
		(connect_pads
			(clearance 0)
		)
		(min_thickness 0.25)
		(keepout
			(tracks not_allowed)
			(vias allowed)
			(pads allowed)
			(copperpour not_allowed)
			(footprints allowed)
		)
		(placement
			(enabled no)
			(sheetname "")
		)
		(fill
			(thermal_gap 0.5)
			(thermal_bridge_width 0.5)
			(island_removal_mode 0)
		)
		(polygon
			(pts
				(arc
					(start 30.001464 -205.232508)
					(mid 29.997744 -205.241488)
					(end 29.988764 -205.245208)
				)
				(arc
					(start 28.515564 -205.245208)
					(mid 28.506584 -205.241488)
					(end 28.502864 -205.232508)
				)
				(arc
					(start 28.502864 -204.73797)
					(mid 28.506584 -204.72899)
					(end 28.515564 -204.72527)
				)
				(arc
					(start 29.988764 -204.72527)
					(mid 29.997744 -204.72899)
					(end 30.001464 -204.73797)
				)
			)
		)
	)
	(zone
		(layer "In1.Cu")
		(hatch none 0.5)
		(connect_pads
			(clearance 0)
		)
		(min_thickness 0.25)
		(keepout
			(tracks not_allowed)
			(vias allowed)
			(pads allowed)
			(copperpour not_allowed)
			(footprints allowed)
		)
		(placement
			(enabled no)
			(sheetname "")
		)
		(fill
			(thermal_gap 0.5)
			(thermal_bridge_width 0.5)
			(island_removal_mode 0)
		)
		(polygon
			(pts
				(arc
					(start 309.57012 -399.143474)
					(mid 309.26532 -399.143474)
					(end 309.57012 -399.143474)
				)
			)
		)
	)
	(zone
		(layer "In1.Cu")
		(hatch none 0.5)
		(connect_pads
			(clearance 0)
		)
		(min_thickness 0.25)
		(keepout
			(tracks not_allowed)
			(vias allowed)
			(pads allowed)
			(copperpour not_allowed)
			(footprints allowed)
		)
		(placement
			(enabled no)
			(sheetname "")
		)
		(fill
			(thermal_gap 0.5)
			(thermal_bridge_width 0.5)
			(island_removal_mode 0)
		)
		(polygon
			(pts
				(arc
					(start 124.161296 -388.774432)
					(mid 123.780296 -388.774432)
					(end 124.161296 -388.774432)
				)
			)
		)
	)
	(zone
		(layer "In1.Cu")
		(hatch none 0.5)
		(connect_pads
			(clearance 0)
		)
		(min_thickness 0.25)
		(keepout
			(tracks not_allowed)
			(vias allowed)
			(pads allowed)
			(copperpour not_allowed)
			(footprints allowed)
		)
		(placement
			(enabled no)
			(sheetname "")
		)
		(fill
			(thermal_gap 0.5)
			(thermal_bridge_width 0.5)
			(island_removal_mode 0)
		)
		(polygon
			(pts
				(arc
					(start 25.901396 -245.18239)
					(mid 25.897676 -245.19137)
					(end 25.888696 -245.19509)
				)
				(arc
					(start 24.415496 -245.19509)
					(mid 24.406516 -245.19137)
					(end 24.402796 -245.18239)
				)
				(arc
					(start 24.402796 -244.687852)
					(mid 24.406516 -244.678872)
					(end 24.415496 -244.675152)
				)
				(arc
					(start 25.888696 -244.675152)
					(mid 25.897676 -244.678872)
					(end 25.901396 -244.687852)
				)
			)
		)
	)
	(zone
		(layer "In1.Cu")
		(hatch none 0.5)
		(connect_pads
			(clearance 0)
		)
		(min_thickness 0.25)
		(keepout
			(tracks not_allowed)
			(vias allowed)
			(pads allowed)
			(copperpour not_allowed)
			(footprints allowed)
		)
		(placement
			(enabled no)
			(sheetname "")
		)
		(fill
			(thermal_gap 0.5)
			(thermal_bridge_width 0.5)
			(island_removal_mode 0)
		)
		(polygon
			(pts
				(arc
					(start 22.45741 -303.832514)
					(mid 22.45369 -303.841494)
					(end 22.44471 -303.845214)
				)
				(arc
					(start 20.97151 -303.845214)
					(mid 20.96253 -303.841494)
					(end 20.95881 -303.832514)
				)
				(arc
					(start 20.95881 -303.337976)
					(mid 20.96253 -303.328996)
					(end 20.97151 -303.325276)
				)
				(arc
					(start 22.44471 -303.325276)
					(mid 22.45369 -303.328996)
					(end 22.45741 -303.337976)
				)
			)
		)
	)
	(zone
		(layer "In1.Cu")
		(hatch none 0.5)
		(connect_pads
			(clearance 0)
		)
		(min_thickness 0.25)
		(keepout
			(tracks not_allowed)
			(vias allowed)
			(pads allowed)
			(copperpour not_allowed)
			(footprints allowed)
		)
		(placement
			(enabled no)
			(sheetname "")
		)
		(fill
			(thermal_gap 0.5)
			(thermal_bridge_width 0.5)
			(island_removal_mode 0)
		)
		(polygon
			(pts
				(arc
					(start 45.089318 -308.082442)
					(mid 45.085598 -308.091422)
					(end 45.076618 -308.095142)
				)
				(arc
					(start 43.603418 -308.095142)
					(mid 43.594438 -308.091422)
					(end 43.590718 -308.082442)
				)
				(arc
					(start 43.590718 -307.587904)
					(mid 43.594438 -307.578924)
					(end 43.603418 -307.575204)
				)
				(arc
					(start 45.076618 -307.575204)
					(mid 45.085598 -307.578924)
					(end 45.089318 -307.587904)
				)
			)
		)
	)
	(zone
		(layer "In1.Cu")
		(hatch none 0.5)
		(connect_pads
			(clearance 0)
		)
		(min_thickness 0.25)
		(keepout
			(tracks not_allowed)
			(vias allowed)
			(pads allowed)
			(copperpour not_allowed)
			(footprints allowed)
		)
		(placement
			(enabled no)
			(sheetname "")
		)
		(fill
			(thermal_gap 0.5)
			(thermal_bridge_width 0.5)
			(island_removal_mode 0)
		)
		(polygon
			(pts
				(arc
					(start 60.177426 -211.182458)
					(mid 60.173706 -211.191438)
					(end 60.164726 -211.195158)
				)
				(arc
					(start 58.691526 -211.195158)
					(mid 58.682546 -211.191438)
					(end 58.678826 -211.182458)
				)
				(arc
					(start 58.678826 -210.68792)
					(mid 58.682546 -210.67894)
					(end 58.691526 -210.67522)
				)
				(arc
					(start 60.164726 -210.67522)
					(mid 60.173706 -210.67894)
					(end 60.177426 -210.68792)
				)
			)
		)
	)
	(zone
		(layer "In1.Cu")
		(hatch none 0.5)
		(connect_pads
			(clearance 0)
		)
		(min_thickness 0.25)
		(keepout
			(tracks not_allowed)
			(vias allowed)
			(pads allowed)
			(copperpour not_allowed)
			(footprints allowed)
		)
		(placement
			(enabled no)
			(sheetname "")
		)
		(fill
			(thermal_gap 0.5)
			(thermal_bridge_width 0.5)
			(island_removal_mode 0)
		)
		(polygon
			(pts
				(arc
					(start 424.761406 -261.332218)
					(mid 424.757686 -261.341198)
					(end 424.748706 -261.344918)
				)
				(arc
					(start 423.275506 -261.344918)
					(mid 423.266526 -261.341198)
					(end 423.262806 -261.332218)
				)
				(arc
					(start 423.262806 -260.83768)
					(mid 423.266526 -260.8287)
					(end 423.275506 -260.82498)
				)
				(arc
					(start 424.748706 -260.82498)
					(mid 424.757686 -260.8287)
					(end 424.761406 -260.83768)
				)
			)
		)
	)
	(zone
		(layer "In1.Cu")
		(hatch none 0.5)
		(connect_pads
			(clearance 0)
		)
		(min_thickness 0.25)
		(keepout
			(tracks not_allowed)
			(vias allowed)
			(pads allowed)
			(copperpour not_allowed)
			(footprints allowed)
		)
		(placement
			(enabled no)
			(sheetname "")
		)
		(fill
			(thermal_gap 0.5)
			(thermal_bridge_width 0.5)
			(island_removal_mode 0)
		)
		(polygon
			(pts
				(arc
					(start 428.205392 -220.532198)
					(mid 428.201672 -220.541178)
					(end 428.192692 -220.544898)
				)
				(arc
					(start 426.719492 -220.544898)
					(mid 426.710512 -220.541178)
					(end 426.706792 -220.532198)
				)
				(arc
					(start 426.706792 -220.03766)
					(mid 426.710512 -220.02868)
					(end 426.719492 -220.02496)
				)
				(arc
					(start 428.192692 -220.02496)
					(mid 428.201672 -220.02868)
					(end 428.205392 -220.03766)
				)
			)
		)
	)
	(zone
		(layer "In1.Cu")
		(hatch none 0.5)
		(connect_pads
			(clearance 0)
		)
		(min_thickness 0.25)
		(keepout
			(tracks not_allowed)
			(vias allowed)
			(pads allowed)
			(copperpour not_allowed)
			(footprints allowed)
		)
		(placement
			(enabled no)
			(sheetname "")
		)
		(fill
			(thermal_gap 0.5)
			(thermal_bridge_width 0.5)
			(island_removal_mode 0)
		)
		(polygon
			(pts
				(arc
					(start 56.077358 -211.182458)
					(mid 56.073638 -211.191438)
					(end 56.064658 -211.195158)
				)
				(arc
					(start 54.591458 -211.195158)
					(mid 54.582478 -211.191438)
					(end 54.578758 -211.182458)
				)
				(arc
					(start 54.578758 -210.68792)
					(mid 54.582478 -210.67894)
					(end 54.591458 -210.67522)
				)
				(arc
					(start 56.064658 -210.67522)
					(mid 56.073638 -210.67894)
					(end 56.077358 -210.68792)
				)
			)
		)
	)
	(zone
		(layer "In1.Cu")
		(hatch none 0.5)
		(connect_pads
			(clearance 0)
		)
		(min_thickness 0.25)
		(keepout
			(tracks not_allowed)
			(vias allowed)
			(pads allowed)
			(copperpour not_allowed)
			(footprints allowed)
		)
		(placement
			(enabled no)
			(sheetname "")
		)
		(fill
			(thermal_gap 0.5)
			(thermal_bridge_width 0.5)
			(island_removal_mode 0)
		)
		(polygon
			(pts
				(arc
					(start 439.849514 -210.33232)
					(mid 439.845794 -210.3413)
					(end 439.836814 -210.34502)
				)
				(arc
					(start 438.363614 -210.34502)
					(mid 438.354634 -210.3413)
					(end 438.350914 -210.33232)
				)
				(arc
					(start 438.350914 -209.837782)
					(mid 438.354634 -209.828802)
					(end 438.363614 -209.825082)
				)
				(arc
					(start 439.836814 -209.825082)
					(mid 439.845794 -209.828802)
					(end 439.849514 -209.837782)
				)
			)
		)
	)
	(zone
		(layer "In1.Cu")
		(hatch none 0.5)
		(connect_pads
			(clearance 0)
		)
		(min_thickness 0.25)
		(keepout
			(tracks not_allowed)
			(vias allowed)
			(pads allowed)
			(copperpour not_allowed)
			(footprints allowed)
		)
		(placement
			(enabled no)
			(sheetname "")
		)
		(fill
			(thermal_gap 0.5)
			(thermal_bridge_width 0.5)
			(island_removal_mode 0)
		)
		(polygon
			(pts
				(arc
					(start 176.821338 -217.982546)
					(mid 176.817618 -217.991526)
					(end 176.808638 -217.995246)
				)
				(arc
					(start 175.335438 -217.995246)
					(mid 175.326458 -217.991526)
					(end 175.322738 -217.982546)
				)
				(arc
					(start 175.322738 -217.488008)
					(mid 175.326458 -217.479028)
					(end 175.335438 -217.475308)
				)
				(arc
					(start 176.808638 -217.475308)
					(mid 176.817618 -217.479028)
					(end 176.821338 -217.488008)
				)
			)
		)
	)
	(zone
		(layer "In1.Cu")
		(hatch none 0.5)
		(connect_pads
			(clearance 0)
		)
		(min_thickness 0.25)
		(keepout
			(tracks not_allowed)
			(vias allowed)
			(pads allowed)
			(copperpour not_allowed)
			(footprints allowed)
		)
		(placement
			(enabled no)
			(sheetname "")
		)
		(fill
			(thermal_gap 0.5)
			(thermal_bridge_width 0.5)
			(island_removal_mode 0)
		)
		(polygon
			(pts
				(arc
					(start 45.089318 -303.832514)
					(mid 45.085598 -303.841494)
					(end 45.076618 -303.845214)
				)
				(arc
					(start 43.603418 -303.845214)
					(mid 43.594438 -303.841494)
					(end 43.590718 -303.832514)
				)
				(arc
					(start 43.590718 -303.337976)
					(mid 43.594438 -303.328996)
					(end 43.603418 -303.325276)
				)
				(arc
					(start 45.076618 -303.325276)
					(mid 45.085598 -303.328996)
					(end 45.089318 -303.337976)
				)
			)
		)
	)
	(zone
		(layer "In1.Cu")
		(hatch none 0.5)
		(connect_pads
			(clearance 0)
		)
		(min_thickness 0.25)
		(keepout
			(tracks not_allowed)
			(vias allowed)
			(pads allowed)
			(copperpour not_allowed)
			(footprints allowed)
		)
		(placement
			(enabled no)
			(sheetname "")
		)
		(fill
			(thermal_gap 0.5)
			(thermal_bridge_width 0.5)
			(island_removal_mode 0)
		)
		(polygon
			(pts
				(arc
					(start 33.445196 -250.282456)
					(mid 33.441476 -250.291436)
					(end 33.432496 -250.295156)
				)
				(arc
					(start 31.959296 -250.295156)
					(mid 31.950316 -250.291436)
					(end 31.946596 -250.282456)
				)
				(arc
					(start 31.946596 -249.787918)
					(mid 31.950316 -249.778938)
					(end 31.959296 -249.775218)
				)
				(arc
					(start 33.432496 -249.775218)
					(mid 33.441476 -249.778938)
					(end 33.445196 -249.787918)
				)
			)
		)
	)
	(zone
		(layer "In1.Cu")
		(hatch none 0.5)
		(connect_pads
			(clearance 0)
		)
		(min_thickness 0.25)
		(keepout
			(tracks not_allowed)
			(vias allowed)
			(pads allowed)
			(copperpour not_allowed)
			(footprints allowed)
		)
		(placement
			(enabled no)
			(sheetname "")
		)
		(fill
			(thermal_gap 0.5)
			(thermal_bridge_width 0.5)
			(island_removal_mode 0)
		)
		(polygon
			(pts
				(arc
					(start 18.357342 -291.93236)
					(mid 18.353622 -291.94134)
					(end 18.344642 -291.94506)
				)
				(arc
					(start 16.871442 -291.94506)
					(mid 16.862462 -291.94134)
					(end 16.858742 -291.93236)
				)
				(arc
					(start 16.858742 -291.437822)
					(mid 16.862462 -291.428842)
					(end 16.871442 -291.425122)
				)
				(arc
					(start 18.344642 -291.425122)
					(mid 18.353622 -291.428842)
					(end 18.357342 -291.437822)
				)
			)
		)
	)
	(zone
		(layer "In1.Cu")
		(hatch none 0.5)
		(connect_pads
			(clearance 0)
		)
		(min_thickness 0.25)
		(keepout
			(tracks not_allowed)
			(vias allowed)
			(pads allowed)
			(copperpour not_allowed)
			(footprints allowed)
		)
		(placement
			(enabled no)
			(sheetname "")
		)
		(fill
			(thermal_gap 0.5)
			(thermal_bridge_width 0.5)
			(island_removal_mode 0)
		)
		(polygon
			(pts
				(arc
					(start 87.189056 -388.774432)
					(mid 86.808056 -388.774432)
					(end 87.189056 -388.774432)
				)
			)
		)
	)
	(zone
		(layer "In1.Cu")
		(hatch none 0.5)
		(connect_pads
			(clearance 0)
		)
		(min_thickness 0.25)
		(keepout
			(tracks not_allowed)
			(vias allowed)
			(pads allowed)
			(copperpour not_allowed)
			(footprints allowed)
		)
		(placement
			(enabled no)
			(sheetname "")
		)
		(fill
			(thermal_gap 0.5)
			(thermal_bridge_width 0.5)
			(island_removal_mode 0)
		)
		(polygon
			(pts
				(arc
					(start 37.545264 -291.082476)
					(mid 37.541544 -291.091456)
					(end 37.532564 -291.095176)
				)
				(arc
					(start 36.059364 -291.095176)
					(mid 36.050384 -291.091456)
					(end 36.046664 -291.082476)
				)
				(arc
					(start 36.046664 -290.587938)
					(mid 36.050384 -290.578958)
					(end 36.059364 -290.575238)
				)
				(arc
					(start 37.532564 -290.575238)
					(mid 37.541544 -290.578958)
					(end 37.545264 -290.587938)
				)
			)
		)
	)
	(zone
		(layer "In1.Cu")
		(hatch none 0.5)
		(connect_pads
			(clearance 0)
		)
		(min_thickness 0.25)
		(keepout
			(tracks not_allowed)
			(vias allowed)
			(pads allowed)
			(copperpour not_allowed)
			(footprints allowed)
		)
		(placement
			(enabled no)
			(sheetname "")
		)
		(fill
			(thermal_gap 0.5)
			(thermal_bridge_width 0.5)
			(island_removal_mode 0)
		)
		(polygon
			(pts
				(arc
					(start 176.821338 -223.932496)
					(mid 176.817618 -223.941476)
					(end 176.808638 -223.945196)
				)
				(arc
					(start 175.335438 -223.945196)
					(mid 175.326458 -223.941476)
					(end 175.322738 -223.932496)
				)
				(arc
					(start 175.322738 -223.437958)
					(mid 175.326458 -223.428978)
					(end 175.335438 -223.425258)
				)
				(arc
					(start 176.808638 -223.425258)
					(mid 176.817618 -223.428978)
					(end 176.821338 -223.437958)
				)
			)
		)
	)
	(zone
		(layer "In1.Cu")
		(hatch none 0.5)
		(connect_pads
			(clearance 0)
		)
		(min_thickness 0.25)
		(keepout
			(tracks not_allowed)
			(vias allowed)
			(pads allowed)
			(copperpour not_allowed)
			(footprints allowed)
		)
		(placement
			(enabled no)
			(sheetname "")
		)
		(fill
			(thermal_gap 0.5)
			(thermal_bridge_width 0.5)
			(island_removal_mode 0)
		)
		(polygon
			(pts
				(arc
					(start 450.8373 -288.532316)
					(mid 450.83358 -288.541296)
					(end 450.8246 -288.545016)
				)
				(arc
					(start 449.3514 -288.545016)
					(mid 449.34242 -288.541296)
					(end 449.3387 -288.532316)
				)
				(arc
					(start 449.3387 -288.037778)
					(mid 449.34242 -288.028798)
					(end 449.3514 -288.025078)
				)
				(arc
					(start 450.8246 -288.025078)
					(mid 450.83358 -288.028798)
					(end 450.8373 -288.037778)
				)
			)
		)
	)
	(zone
		(layer "In1.Cu")
		(hatch none 0.5)
		(connect_pads
			(clearance 0)
		)
		(min_thickness 0.25)
		(keepout
			(tracks not_allowed)
			(vias allowed)
			(pads allowed)
			(copperpour not_allowed)
			(footprints allowed)
		)
		(placement
			(enabled no)
			(sheetname "")
		)
		(fill
			(thermal_gap 0.5)
			(thermal_bridge_width 0.5)
			(island_removal_mode 0)
		)
		(polygon
			(pts
				(arc
					(start 304.017426 -198.432166)
					(mid 304.013706 -198.441146)
					(end 304.004726 -198.444866)
				)
				(arc
					(start 302.531526 -198.444866)
					(mid 302.522546 -198.441146)
					(end 302.518826 -198.432166)
				)
				(arc
					(start 302.518826 -197.937628)
					(mid 302.522546 -197.928648)
					(end 302.531526 -197.924928)
				)
				(arc
					(start 304.004726 -197.924928)
					(mid 304.013706 -197.928648)
					(end 304.017426 -197.937628)
				)
			)
		)
	)
	(zone
		(layer "In1.Cu")
		(hatch none 0.5)
		(connect_pads
			(clearance 0)
		)
		(min_thickness 0.25)
		(keepout
			(tracks not_allowed)
			(vias allowed)
			(pads allowed)
			(copperpour not_allowed)
			(footprints allowed)
		)
		(placement
			(enabled no)
			(sheetname "")
		)
		(fill
			(thermal_gap 0.5)
			(thermal_bridge_width 0.5)
			(island_removal_mode 0)
		)
		(polygon
			(pts
				(arc
					(start 150.689056 -385.31038)
					(mid 150.308056 -385.31038)
					(end 150.689056 -385.31038)
				)
			)
		)
	)
	(zone
		(layer "In1.Cu")
		(hatch none 0.5)
		(connect_pads
			(clearance 0)
		)
		(min_thickness 0.25)
		(keepout
			(tracks not_allowed)
			(vias allowed)
			(pads allowed)
			(copperpour not_allowed)
			(footprints allowed)
		)
		(placement
			(enabled no)
			(sheetname "")
		)
		(fill
			(thermal_gap 0.5)
			(thermal_bridge_width 0.5)
			(island_removal_mode 0)
		)
		(polygon
			(pts
				(arc
					(start 417.488878 -397.156432)
					(mid 417.107878 -397.156432)
					(end 417.488878 -397.156432)
				)
			)
		)
	)
	(zone
		(layer "In1.Cu")
		(hatch none 0.5)
		(connect_pads
			(clearance 0)
		)
		(min_thickness 0.25)
		(keepout
			(tracks not_allowed)
			(vias allowed)
			(pads allowed)
			(copperpour not_allowed)
			(footprints allowed)
		)
		(placement
			(enabled no)
			(sheetname "")
		)
		(fill
			(thermal_gap 0.5)
			(thermal_bridge_width 0.5)
			(island_removal_mode 0)
		)
		(polygon
			(pts
				(arc
					(start 187.809378 -213.732364)
					(mid 187.805658 -213.741344)
					(end 187.796678 -213.745064)
				)
				(arc
					(start 186.323478 -213.745064)
					(mid 186.314498 -213.741344)
					(end 186.310778 -213.732364)
				)
				(arc
					(start 186.310778 -213.237826)
					(mid 186.314498 -213.228846)
					(end 186.323478 -213.225126)
				)
				(arc
					(start 187.796678 -213.225126)
					(mid 187.805658 -213.228846)
					(end 187.809378 -213.237826)
				)
			)
		)
	)
	(zone
		(layer "In1.Cu")
		(hatch none 0.5)
		(connect_pads
			(clearance 0)
		)
		(min_thickness 0.25)
		(keepout
			(tracks not_allowed)
			(vias allowed)
			(pads allowed)
			(copperpour not_allowed)
			(footprints allowed)
		)
		(placement
			(enabled no)
			(sheetname "")
		)
		(fill
			(thermal_gap 0.5)
			(thermal_bridge_width 0.5)
			(island_removal_mode 0)
		)
		(polygon
			(pts
				(arc
					(start 429.872394 -7.672324)
					(mid 429.894712 -7.618442)
					(end 429.948594 -7.596124)
				)
				(arc
					(start 430.985168 -7.596124)
					(mid 431.03905 -7.618442)
					(end 431.061368 -7.672324)
				)
				(arc
					(start 431.061368 -9.071864)
					(mid 431.03905 -9.125746)
					(end 430.985168 -9.148064)
				)
				(arc
					(start 429.948594 -9.148064)
					(mid 429.894712 -9.125746)
					(end 429.872394 -9.071864)
				)
			)
		)
	)
	(zone
		(layer "In1.Cu")
		(hatch none 0.5)
		(connect_pads
			(clearance 0)
		)
		(min_thickness 0.25)
		(keepout
			(tracks not_allowed)
			(vias allowed)
			(pads allowed)
			(copperpour not_allowed)
			(footprints allowed)
		)
		(placement
			(enabled no)
			(sheetname "")
		)
		(fill
			(thermal_gap 0.5)
			(thermal_bridge_width 0.5)
			(island_removal_mode 0)
		)
		(polygon
			(pts
				(arc
					(start 273.841464 -285.982156)
					(mid 273.837744 -285.991136)
					(end 273.828764 -285.994856)
				)
				(arc
					(start 272.355564 -285.994856)
					(mid 272.346584 -285.991136)
					(end 272.342864 -285.982156)
				)
				(arc
					(start 272.342864 -285.487618)
					(mid 272.346584 -285.478638)
					(end 272.355564 -285.474918)
				)
				(arc
					(start 273.828764 -285.474918)
					(mid 273.837744 -285.478638)
					(end 273.841464 -285.487618)
				)
			)
		)
	)
	(zone
		(layer "In1.Cu")
		(hatch none 0.5)
		(connect_pads
			(clearance 0)
		)
		(min_thickness 0.25)
		(keepout
			(tracks not_allowed)
			(vias allowed)
			(pads allowed)
			(copperpour not_allowed)
			(footprints allowed)
		)
		(placement
			(enabled no)
			(sheetname "")
		)
		(fill
			(thermal_gap 0.5)
			(thermal_bridge_width 0.5)
			(island_removal_mode 0)
		)
		(polygon
			(pts
				(arc
					(start 450.8373 -218.832176)
					(mid 450.83358 -218.841156)
					(end 450.8246 -218.844876)
				)
				(arc
					(start 449.3514 -218.844876)
					(mid 449.34242 -218.841156)
					(end 449.3387 -218.832176)
				)
				(arc
					(start 449.3387 -218.337638)
					(mid 449.34242 -218.328658)
					(end 449.3514 -218.324938)
				)
				(arc
					(start 450.8246 -218.324938)
					(mid 450.83358 -218.328658)
					(end 450.8373 -218.337638)
				)
			)
		)
	)
	(zone
		(layer "In1.Cu")
		(hatch none 0.5)
		(connect_pads
			(clearance 0)
		)
		(min_thickness 0.25)
		(keepout
			(tracks not_allowed)
			(vias allowed)
			(pads allowed)
			(copperpour not_allowed)
			(footprints allowed)
		)
		(placement
			(enabled no)
			(sheetname "")
		)
		(fill
			(thermal_gap 0.5)
			(thermal_bridge_width 0.5)
			(island_removal_mode 0)
		)
		(polygon
			(pts
				(arc
					(start 83.118706 -383.440686)
					(mid 83.245706 -383.567686)
					(end 83.372706 -383.440686)
				)
				(arc
					(start 83.372706 -383.364486)
					(mid 83.245706 -383.237486)
					(end 83.118706 -383.364486)
				)
			)
		)
	)
	(zone
		(layer "In1.Cu")
		(hatch none 0.5)
		(connect_pads
			(clearance 0)
		)
		(min_thickness 0.25)
		(keepout
			(tracks not_allowed)
			(vias allowed)
			(pads allowed)
			(copperpour not_allowed)
			(footprints allowed)
		)
		(placement
			(enabled no)
			(sheetname "")
		)
		(fill
			(thermal_gap 0.5)
			(thermal_bridge_width 0.5)
			(island_removal_mode 0)
		)
		(polygon
			(pts
				(arc
					(start 315.314584 0.553974)
					(mid 315.336902 0.607856)
					(end 315.390784 0.630174)
				)
				(arc
					(start 316.002924 0.630174)
					(mid 316.056806 0.607856)
					(end 316.079124 0.553974)
				)
				(arc
					(start 316.079124 -0.543306)
					(mid 316.056806 -0.597188)
					(end 316.002924 -0.619506)
				)
				(arc
					(start 315.390784 -0.619506)
					(mid 315.336902 -0.597188)
					(end 315.314584 -0.543306)
				)
			)
		)
	)
	(zone
		(layer "In1.Cu")
		(hatch none 0.5)
		(connect_pads
			(clearance 0)
		)
		(min_thickness 0.25)
		(keepout
			(tracks not_allowed)
			(vias allowed)
			(pads allowed)
			(copperpour not_allowed)
			(footprints allowed)
		)
		(placement
			(enabled no)
			(sheetname "")
		)
		(fill
			(thermal_gap 0.5)
			(thermal_bridge_width 0.5)
			(island_removal_mode 0)
		)
		(polygon
			(pts
				(arc
					(start 417.217352 -210.33232)
					(mid 417.213632 -210.3413)
					(end 417.204652 -210.34502)
				)
				(arc
					(start 415.731452 -210.34502)
					(mid 415.722472 -210.3413)
					(end 415.718752 -210.33232)
				)
				(arc
					(start 415.718752 -209.837782)
					(mid 415.722472 -209.828802)
					(end 415.731452 -209.825082)
				)
				(arc
					(start 417.204652 -209.825082)
					(mid 417.213632 -209.828802)
					(end 417.217352 -209.837782)
				)
			)
		)
	)
	(zone
		(layer "In1.Cu")
		(hatch none 0.5)
		(connect_pads
			(clearance 0)
		)
		(min_thickness 0.25)
		(keepout
			(tracks not_allowed)
			(vias allowed)
			(pads allowed)
			(copperpour not_allowed)
			(footprints allowed)
		)
		(placement
			(enabled no)
			(sheetname "")
		)
		(fill
			(thermal_gap 0.5)
			(thermal_bridge_width 0.5)
			(island_removal_mode 0)
		)
		(polygon
			(pts
				(arc
					(start 288.929318 -291.932106)
					(mid 288.925598 -291.941086)
					(end 288.916618 -291.944806)
				)
				(arc
					(start 287.443418 -291.944806)
					(mid 287.434438 -291.941086)
					(end 287.430718 -291.932106)
				)
				(arc
					(start 287.430718 -291.437568)
					(mid 287.434438 -291.428588)
					(end 287.443418 -291.424868)
				)
				(arc
					(start 288.916618 -291.424868)
					(mid 288.925598 -291.428588)
					(end 288.929318 -291.437568)
				)
			)
		)
	)
	(zone
		(layer "In1.Cu")
		(hatch none 0.5)
		(connect_pads
			(clearance 0)
		)
		(min_thickness 0.25)
		(keepout
			(tracks not_allowed)
			(vias allowed)
			(pads allowed)
			(copperpour not_allowed)
			(footprints allowed)
		)
		(placement
			(enabled no)
			(sheetname "")
		)
		(fill
			(thermal_gap 0.5)
			(thermal_bridge_width 0.5)
			(island_removal_mode 0)
		)
		(polygon
			(pts
				(arc
					(start 199.4535 -242.632484)
					(mid 199.44978 -242.641464)
					(end 199.4408 -242.645184)
				)
				(arc
					(start 197.9676 -242.645184)
					(mid 197.95862 -242.641464)
					(end 197.9549 -242.632484)
				)
				(arc
					(start 197.9549 -242.137946)
					(mid 197.95862 -242.128966)
					(end 197.9676 -242.125246)
				)
				(arc
					(start 199.4408 -242.125246)
					(mid 199.44978 -242.128966)
					(end 199.4535 -242.137946)
				)
			)
		)
	)
	(zone
		(layer "In1.Cu")
		(hatch none 0.5)
		(connect_pads
			(clearance 0)
		)
		(min_thickness 0.25)
		(keepout
			(tracks not_allowed)
			(vias allowed)
			(pads allowed)
			(copperpour not_allowed)
			(footprints allowed)
		)
		(placement
			(enabled no)
			(sheetname "")
		)
		(fill
			(thermal_gap 0.5)
			(thermal_bridge_width 0.5)
			(island_removal_mode 0)
		)
		(polygon
			(pts
				(arc
					(start 421.19804 -399.143474)
					(mid 420.89324 -399.143474)
					(end 421.19804 -399.143474)
				)
			)
		)
	)
	(zone
		(layer "In1.Cu")
		(hatch none 0.5)
		(connect_pads
			(clearance 0)
		)
		(min_thickness 0.25)
		(keepout
			(tracks not_allowed)
			(vias allowed)
			(pads allowed)
			(copperpour not_allowed)
			(footprints allowed)
		)
		(placement
			(enabled no)
			(sheetname "")
		)
		(fill
			(thermal_gap 0.5)
			(thermal_bridge_width 0.5)
			(island_removal_mode 0)
		)
		(polygon
			(pts
				(arc
					(start 165.177216 -274.932394)
					(mid 165.173496 -274.941374)
					(end 165.164516 -274.945094)
				)
				(arc
					(start 163.691316 -274.945094)
					(mid 163.682336 -274.941374)
					(end 163.678616 -274.932394)
				)
				(arc
					(start 163.678616 -274.437856)
					(mid 163.682336 -274.428876)
					(end 163.691316 -274.425156)
				)
				(arc
					(start 165.164516 -274.425156)
					(mid 165.173496 -274.428876)
					(end 165.177216 -274.437856)
				)
			)
		)
	)
	(zone
		(layer "In1.Cu")
		(hatch none 0.5)
		(connect_pads
			(clearance 0)
		)
		(min_thickness 0.25)
		(keepout
			(tracks not_allowed)
			(vias allowed)
			(pads allowed)
			(copperpour not_allowed)
			(footprints allowed)
		)
		(placement
			(enabled no)
			(sheetname "")
		)
		(fill
			(thermal_gap 0.5)
			(thermal_bridge_width 0.5)
			(island_removal_mode 0)
		)
		(polygon
			(pts
				(arc
					(start 420.661338 -297.88231)
					(mid 420.657618 -297.89129)
					(end 420.648638 -297.89501)
				)
				(arc
					(start 419.175438 -297.89501)
					(mid 419.166458 -297.89129)
					(end 419.162738 -297.88231)
				)
				(arc
					(start 419.162738 -297.387772)
					(mid 419.166458 -297.378792)
					(end 419.175438 -297.375072)
				)
				(arc
					(start 420.648638 -297.375072)
					(mid 420.657618 -297.378792)
					(end 420.661338 -297.387772)
				)
			)
		)
	)
	(zone
		(layer "In1.Cu")
		(hatch none 0.5)
		(connect_pads
			(clearance 0)
		)
		(min_thickness 0.25)
		(keepout
			(tracks not_allowed)
			(vias allowed)
			(pads allowed)
			(copperpour not_allowed)
			(footprints allowed)
		)
		(placement
			(enabled no)
			(sheetname "")
		)
		(fill
			(thermal_gap 0.5)
			(thermal_bridge_width 0.5)
			(island_removal_mode 0)
		)
		(polygon
			(pts
				(arc
					(start 300.57344 -263.03224)
					(mid 300.56972 -263.04122)
					(end 300.56074 -263.04494)
				)
				(arc
					(start 299.08754 -263.04494)
					(mid 299.07856 -263.04122)
					(end 299.07484 -263.03224)
				)
				(arc
					(start 299.07484 -262.537702)
					(mid 299.07856 -262.528722)
					(end 299.08754 -262.525002)
				)
				(arc
					(start 300.56074 -262.525002)
					(mid 300.56972 -262.528722)
					(end 300.57344 -262.537702)
				)
			)
		)
	)
	(zone
		(layer "In1.Cu")
		(hatch none 0.5)
		(connect_pads
			(clearance 0)
		)
		(min_thickness 0.25)
		(keepout
			(tracks not_allowed)
			(vias allowed)
			(pads allowed)
			(copperpour not_allowed)
			(footprints allowed)
		)
		(placement
			(enabled no)
			(sheetname "")
		)
		(fill
			(thermal_gap 0.5)
			(thermal_bridge_width 0.5)
			(island_removal_mode 0)
		)
		(polygon
			(pts
				(arc
					(start 52.661058 -386.003292)
					(mid 52.280058 -386.003292)
					(end 52.661058 -386.003292)
				)
			)
		)
	)
	(zone
		(layer "In1.Cu")
		(hatch none 0.5)
		(connect_pads
			(clearance 0)
		)
		(min_thickness 0.25)
		(keepout
			(tracks not_allowed)
			(vias allowed)
			(pads allowed)
			(copperpour not_allowed)
			(footprints allowed)
		)
		(placement
			(enabled no)
			(sheetname "")
		)
		(fill
			(thermal_gap 0.5)
			(thermal_bridge_width 0.5)
			(island_removal_mode 0)
		)
		(polygon
			(pts
				(arc
					(start 90.898218 -383.92227)
					(mid 90.593418 -383.92227)
					(end 90.898218 -383.92227)
				)
			)
		)
	)
	(zone
		(layer "In1.Cu")
		(hatch none 0.5)
		(connect_pads
			(clearance 0)
		)
		(min_thickness 0.25)
		(keepout
			(tracks not_allowed)
			(vias allowed)
			(pads allowed)
			(copperpour not_allowed)
			(footprints allowed)
		)
		(placement
			(enabled no)
			(sheetname "")
		)
		(fill
			(thermal_gap 0.5)
			(thermal_bridge_width 0.5)
			(island_removal_mode 0)
		)
		(polygon
			(pts
				(arc
					(start 33.445196 -223.082358)
					(mid 33.441476 -223.091338)
					(end 33.432496 -223.095058)
				)
				(arc
					(start 31.959296 -223.095058)
					(mid 31.950316 -223.091338)
					(end 31.946596 -223.082358)
				)
				(arc
					(start 31.946596 -222.58782)
					(mid 31.950316 -222.57884)
					(end 31.959296 -222.57512)
				)
				(arc
					(start 33.432496 -222.57512)
					(mid 33.441476 -222.57884)
					(end 33.445196 -222.58782)
				)
			)
		)
	)
	(zone
		(layer "In1.Cu")
		(hatch none 0.5)
		(connect_pads
			(clearance 0)
		)
		(min_thickness 0.25)
		(keepout
			(tracks not_allowed)
			(vias allowed)
			(pads allowed)
			(copperpour not_allowed)
			(footprints allowed)
		)
		(placement
			(enabled no)
			(sheetname "")
		)
		(fill
			(thermal_gap 0.5)
			(thermal_bridge_width 0.5)
			(island_removal_mode 0)
		)
		(polygon
			(pts
				(arc
					(start 454.937368 -247.732296)
					(mid 454.933648 -247.741276)
					(end 454.924668 -247.744996)
				)
				(arc
					(start 453.451468 -247.744996)
					(mid 453.442488 -247.741276)
					(end 453.438768 -247.732296)
				)
				(arc
					(start 453.438768 -247.237758)
					(mid 453.442488 -247.228778)
					(end 453.451468 -247.225058)
				)
				(arc
					(start 454.924668 -247.225058)
					(mid 454.933648 -247.228778)
					(end 454.937368 -247.237758)
				)
			)
		)
	)
	(zone
		(layer "In1.Cu")
		(hatch none 0.5)
		(connect_pads
			(clearance 0)
		)
		(min_thickness 0.25)
		(keepout
			(tracks not_allowed)
			(vias allowed)
			(pads allowed)
			(copperpour not_allowed)
			(footprints allowed)
		)
		(placement
			(enabled no)
			(sheetname "")
		)
		(fill
			(thermal_gap 0.5)
			(thermal_bridge_width 0.5)
			(island_removal_mode 0)
		)
		(polygon
			(pts
				(arc
					(start 56.077358 -218.83243)
					(mid 56.073638 -218.84141)
					(end 56.064658 -218.84513)
				)
				(arc
					(start 54.591458 -218.84513)
					(mid 54.582478 -218.84141)
					(end 54.578758 -218.83243)
				)
				(arc
					(start 54.578758 -218.337892)
					(mid 54.582478 -218.328912)
					(end 54.591458 -218.325192)
				)
				(arc
					(start 56.064658 -218.325192)
					(mid 56.073638 -218.328912)
					(end 56.077358 -218.337892)
				)
			)
		)
	)
	(zone
		(layer "In1.Cu")
		(hatch none 0.5)
		(connect_pads
			(clearance 0)
		)
		(min_thickness 0.25)
		(keepout
			(tracks not_allowed)
			(vias allowed)
			(pads allowed)
			(copperpour not_allowed)
			(footprints allowed)
		)
		(placement
			(enabled no)
			(sheetname "")
		)
		(fill
			(thermal_gap 0.5)
			(thermal_bridge_width 0.5)
			(island_removal_mode 0)
		)
		(polygon
			(pts
				(arc
					(start 432.30546 -311.482232)
					(mid 432.30174 -311.491212)
					(end 432.29276 -311.494932)
				)
				(arc
					(start 430.81956 -311.494932)
					(mid 430.81058 -311.491212)
					(end 430.80686 -311.482232)
				)
				(arc
					(start 430.80686 -310.987694)
					(mid 430.81058 -310.978714)
					(end 430.81956 -310.974994)
				)
				(arc
					(start 432.29276 -310.974994)
					(mid 432.30174 -310.978714)
					(end 432.30546 -310.987694)
				)
			)
		)
	)
	(zone
		(layer "In1.Cu")
		(hatch none 0.5)
		(connect_pads
			(clearance 0)
		)
		(min_thickness 0.25)
		(keepout
			(tracks not_allowed)
			(vias allowed)
			(pads allowed)
			(copperpour not_allowed)
			(footprints allowed)
		)
		(placement
			(enabled no)
			(sheetname "")
		)
		(fill
			(thermal_gap 0.5)
			(thermal_bridge_width 0.5)
			(island_removal_mode 0)
		)
		(polygon
			(pts
				(arc
					(start 22.45741 -285.132526)
					(mid 22.45369 -285.141506)
					(end 22.44471 -285.145226)
				)
				(arc
					(start 20.97151 -285.145226)
					(mid 20.96253 -285.141506)
					(end 20.95881 -285.132526)
				)
				(arc
					(start 20.95881 -284.637988)
					(mid 20.96253 -284.629008)
					(end 20.97151 -284.625288)
				)
				(arc
					(start 22.44471 -284.625288)
					(mid 22.45369 -284.629008)
					(end 22.45741 -284.637988)
				)
			)
		)
	)
	(zone
		(layer "In1.Cu")
		(hatch none 0.5)
		(connect_pads
			(clearance 0)
		)
		(min_thickness 0.25)
		(keepout
			(tracks not_allowed)
			(vias allowed)
			(pads allowed)
			(copperpour not_allowed)
			(footprints allowed)
		)
		(placement
			(enabled no)
			(sheetname "")
		)
		(fill
			(thermal_gap 0.5)
			(thermal_bridge_width 0.5)
			(island_removal_mode 0)
		)
		(polygon
			(pts
				(arc
					(start 199.4535 -283.432504)
					(mid 199.44978 -283.441484)
					(end 199.4408 -283.445204)
				)
				(arc
					(start 197.9676 -283.445204)
					(mid 197.95862 -283.441484)
					(end 197.9549 -283.432504)
				)
				(arc
					(start 197.9549 -282.937966)
					(mid 197.95862 -282.928986)
					(end 197.9676 -282.925266)
				)
				(arc
					(start 199.4408 -282.925266)
					(mid 199.44978 -282.928986)
					(end 199.4535 -282.937966)
				)
			)
		)
	)
	(zone
		(layer "In1.Cu")
		(hatch none 0.5)
		(connect_pads
			(clearance 0)
		)
		(min_thickness 0.25)
		(keepout
			(tracks not_allowed)
			(vias allowed)
			(pads allowed)
			(copperpour not_allowed)
			(footprints allowed)
		)
		(placement
			(enabled no)
			(sheetname "")
		)
		(fill
			(thermal_gap 0.5)
			(thermal_bridge_width 0.5)
			(island_removal_mode 0)
		)
		(polygon
			(pts
				(arc
					(start 413.117284 -204.382116)
					(mid 413.113564 -204.391096)
					(end 413.104584 -204.394816)
				)
				(arc
					(start 411.631384 -204.394816)
					(mid 411.622404 -204.391096)
					(end 411.618684 -204.382116)
				)
				(arc
					(start 411.618684 -203.887578)
					(mid 411.622404 -203.878598)
					(end 411.631384 -203.874878)
				)
				(arc
					(start 413.104584 -203.874878)
					(mid 413.113564 -203.878598)
					(end 413.117284 -203.887578)
				)
			)
		)
	)
	(zone
		(layer "In1.Cu")
		(hatch none 0.5)
		(connect_pads
			(clearance 0)
		)
		(min_thickness 0.25)
		(keepout
			(tracks not_allowed)
			(vias allowed)
			(pads allowed)
			(copperpour not_allowed)
			(footprints allowed)
		)
		(placement
			(enabled no)
			(sheetname "")
		)
		(fill
			(thermal_gap 0.5)
			(thermal_bridge_width 0.5)
			(island_removal_mode 0)
		)
		(polygon
			(pts
				(arc
					(start 432.30546 -309.78221)
					(mid 432.30174 -309.79119)
					(end 432.29276 -309.79491)
				)
				(arc
					(start 430.81956 -309.79491)
					(mid 430.81058 -309.79119)
					(end 430.80686 -309.78221)
				)
				(arc
					(start 430.80686 -309.287672)
					(mid 430.81058 -309.278692)
					(end 430.81956 -309.274972)
				)
				(arc
					(start 432.29276 -309.274972)
					(mid 432.30174 -309.278692)
					(end 432.30546 -309.287672)
				)
			)
		)
	)
	(zone
		(layer "In1.Cu")
		(hatch none 0.5)
		(connect_pads
			(clearance 0)
		)
		(min_thickness 0.25)
		(keepout
			(tracks not_allowed)
			(vias allowed)
			(pads allowed)
			(copperpour not_allowed)
			(footprints allowed)
		)
		(placement
			(enabled no)
			(sheetname "")
		)
		(fill
			(thermal_gap 0.5)
			(thermal_bridge_width 0.5)
			(island_removal_mode 0)
		)
		(polygon
			(pts
				(arc
					(start 313.790838 -391.822686)
					(mid 313.917838 -391.949686)
					(end 314.044838 -391.822686)
				)
				(arc
					(start 314.044838 -391.746486)
					(mid 313.917838 -391.619486)
					(end 313.790838 -391.746486)
				)
			)
		)
	)
	(zone
		(layer "In1.Cu")
		(hatch none 0.5)
		(connect_pads
			(clearance 0)
		)
		(min_thickness 0.25)
		(keepout
			(tracks not_allowed)
			(vias allowed)
			(pads allowed)
			(copperpour not_allowed)
			(footprints allowed)
		)
		(placement
			(enabled no)
			(sheetname "")
		)
		(fill
			(thermal_gap 0.5)
			(thermal_bridge_width 0.5)
			(island_removal_mode 0)
		)
		(polygon
			(pts
				(arc
					(start 164.61867 -391.319258)
					(mid 164.74567 -391.446258)
					(end 164.87267 -391.319258)
				)
				(arc
					(start 164.87267 -391.243058)
					(mid 164.74567 -391.116058)
					(end 164.61867 -391.243058)
				)
			)
		)
	)
	(zone
		(layer "In1.Cu")
		(hatch none 0.5)
		(connect_pads
			(clearance 0)
		)
		(min_thickness 0.25)
		(keepout
			(tracks not_allowed)
			(vias allowed)
			(pads allowed)
			(copperpour not_allowed)
			(footprints allowed)
		)
		(placement
			(enabled no)
			(sheetname "")
		)
		(fill
			(thermal_gap 0.5)
			(thermal_bridge_width 0.5)
			(island_removal_mode 0)
		)
		(polygon
			(pts
				(arc
					(start 308.117494 -269.832328)
					(mid 308.113774 -269.841308)
					(end 308.104794 -269.845028)
				)
				(arc
					(start 306.631594 -269.845028)
					(mid 306.622614 -269.841308)
					(end 306.618894 -269.832328)
				)
				(arc
					(start 306.618894 -269.33779)
					(mid 306.622614 -269.32881)
					(end 306.631594 -269.32509)
				)
				(arc
					(start 308.104794 -269.32509)
					(mid 308.113774 -269.32881)
					(end 308.117494 -269.33779)
				)
			)
		)
	)
	(zone
		(layer "In1.Cu")
		(hatch none 0.5)
		(connect_pads
			(clearance 0)
		)
		(min_thickness 0.25)
		(keepout
			(tracks not_allowed)
			(vias allowed)
			(pads allowed)
			(copperpour not_allowed)
			(footprints allowed)
		)
		(placement
			(enabled no)
			(sheetname "")
		)
		(fill
			(thermal_gap 0.5)
			(thermal_bridge_width 0.5)
			(island_removal_mode 0)
		)
		(polygon
			(pts
				(arc
					(start 443.2935 -274.93214)
					(mid 443.28978 -274.94112)
					(end 443.2808 -274.94484)
				)
				(arc
					(start 441.8076 -274.94484)
					(mid 441.79862 -274.94112)
					(end 441.7949 -274.93214)
				)
				(arc
					(start 441.7949 -274.437602)
					(mid 441.79862 -274.428622)
					(end 441.8076 -274.424902)
				)
				(arc
					(start 443.2808 -274.424902)
					(mid 443.28978 -274.428622)
					(end 443.2935 -274.437602)
				)
			)
		)
	)
	(zone
		(layer "In1.Cu")
		(hatch none 0.5)
		(connect_pads
			(clearance 0)
		)
		(min_thickness 0.25)
		(keepout
			(tracks not_allowed)
			(vias allowed)
			(pads allowed)
			(copperpour not_allowed)
			(footprints allowed)
		)
		(placement
			(enabled no)
			(sheetname "")
		)
		(fill
			(thermal_gap 0.5)
			(thermal_bridge_width 0.5)
			(island_removal_mode 0)
		)
		(polygon
			(pts
				(arc
					(start 54.661308 -388.774432)
					(mid 54.280308 -388.774432)
					(end 54.661308 -388.774432)
				)
			)
		)
	)
	(zone
		(layer "In1.Cu")
		(hatch none 0.5)
		(connect_pads
			(clearance 0)
		)
		(min_thickness 0.25)
		(keepout
			(tracks not_allowed)
			(vias allowed)
			(pads allowed)
			(copperpour not_allowed)
			(footprints allowed)
		)
		(placement
			(enabled no)
			(sheetname "")
		)
		(fill
			(thermal_gap 0.5)
			(thermal_bridge_width 0.5)
			(island_removal_mode 0)
		)
		(polygon
			(pts
				(arc
					(start 417.217352 -212.882226)
					(mid 417.213632 -212.891206)
					(end 417.204652 -212.894926)
				)
				(arc
					(start 415.731452 -212.894926)
					(mid 415.722472 -212.891206)
					(end 415.718752 -212.882226)
				)
				(arc
					(start 415.718752 -212.387688)
					(mid 415.722472 -212.378708)
					(end 415.731452 -212.374988)
				)
				(arc
					(start 417.204652 -212.374988)
					(mid 417.213632 -212.378708)
					(end 417.217352 -212.387688)
				)
			)
		)
	)
	(zone
		(layer "In1.Cu")
		(hatch none 0.5)
		(connect_pads
			(clearance 0)
		)
		(min_thickness 0.25)
		(keepout
			(tracks not_allowed)
			(vias allowed)
			(pads allowed)
			(copperpour not_allowed)
			(footprints allowed)
		)
		(placement
			(enabled no)
			(sheetname "")
		)
		(fill
			(thermal_gap 0.5)
			(thermal_bridge_width 0.5)
			(island_removal_mode 0)
		)
		(polygon
			(pts
				(arc
					(start 206.9973 -219.682568)
					(mid 206.99358 -219.691548)
					(end 206.9846 -219.695268)
				)
				(arc
					(start 205.5114 -219.695268)
					(mid 205.50242 -219.691548)
					(end 205.4987 -219.682568)
				)
				(arc
					(start 205.4987 -219.18803)
					(mid 205.50242 -219.17905)
					(end 205.5114 -219.17533)
				)
				(arc
					(start 206.9846 -219.17533)
					(mid 206.99358 -219.17905)
					(end 206.9973 -219.18803)
				)
			)
		)
	)
	(zone
		(layer "In1.Cu")
		(hatch none 0.5)
		(connect_pads
			(clearance 0)
		)
		(min_thickness 0.25)
		(keepout
			(tracks not_allowed)
			(vias allowed)
			(pads allowed)
			(copperpour not_allowed)
			(footprints allowed)
		)
		(placement
			(enabled no)
			(sheetname "")
		)
		(fill
			(thermal_gap 0.5)
			(thermal_bridge_width 0.5)
			(island_removal_mode 0)
		)
		(polygon
			(pts
				(arc
					(start 413.117284 -251.982224)
					(mid 413.113564 -251.991204)
					(end 413.104584 -251.994924)
				)
				(arc
					(start 411.631384 -251.994924)
					(mid 411.622404 -251.991204)
					(end 411.618684 -251.982224)
				)
				(arc
					(start 411.618684 -251.487686)
					(mid 411.622404 -251.478706)
					(end 411.631384 -251.474986)
				)
				(arc
					(start 413.104584 -251.474986)
					(mid 413.113564 -251.478706)
					(end 413.117284 -251.487686)
				)
			)
		)
	)
	(zone
		(layer "In1.Cu")
		(hatch none 0.5)
		(connect_pads
			(clearance 0)
		)
		(min_thickness 0.25)
		(keepout
			(tracks not_allowed)
			(vias allowed)
			(pads allowed)
			(copperpour not_allowed)
			(footprints allowed)
		)
		(placement
			(enabled no)
			(sheetname "")
		)
		(fill
			(thermal_gap 0.5)
			(thermal_bridge_width 0.5)
			(island_removal_mode 0)
		)
		(polygon
			(pts
				(arc
					(start 277.941532 -275.782278)
					(mid 277.937812 -275.791258)
					(end 277.928832 -275.794978)
				)
				(arc
					(start 276.455632 -275.794978)
					(mid 276.446652 -275.791258)
					(end 276.442932 -275.782278)
				)
				(arc
					(start 276.442932 -275.28774)
					(mid 276.446652 -275.27876)
					(end 276.455632 -275.27504)
				)
				(arc
					(start 277.928832 -275.27504)
					(mid 277.937812 -275.27876)
					(end 277.941532 -275.28774)
				)
			)
		)
	)
	(zone
		(layer "In1.Cu")
		(hatch none 0.5)
		(connect_pads
			(clearance 0)
		)
		(min_thickness 0.25)
		(keepout
			(tracks not_allowed)
			(vias allowed)
			(pads allowed)
			(copperpour not_allowed)
			(footprints allowed)
		)
		(placement
			(enabled no)
			(sheetname "")
		)
		(fill
			(thermal_gap 0.5)
			(thermal_bridge_width 0.5)
			(island_removal_mode 0)
		)
		(polygon
			(pts
				(arc
					(start 22.45741 -308.082442)
					(mid 22.45369 -308.091422)
					(end 22.44471 -308.095142)
				)
				(arc
					(start 20.97151 -308.095142)
					(mid 20.96253 -308.091422)
					(end 20.95881 -308.082442)
				)
				(arc
					(start 20.95881 -307.587904)
					(mid 20.96253 -307.578924)
					(end 20.97151 -307.575204)
				)
				(arc
					(start 22.44471 -307.575204)
					(mid 22.45369 -307.578924)
					(end 22.45741 -307.587904)
				)
			)
		)
	)
	(zone
		(layer "In1.Cu")
		(hatch none 0.5)
		(connect_pads
			(clearance 0)
		)
		(min_thickness 0.25)
		(keepout
			(tracks not_allowed)
			(vias allowed)
			(pads allowed)
			(copperpour not_allowed)
			(footprints allowed)
		)
		(placement
			(enabled no)
			(sheetname "")
		)
		(fill
			(thermal_gap 0.5)
			(thermal_bridge_width 0.5)
			(island_removal_mode 0)
		)
		(polygon
			(pts
				(arc
					(start 114.961162 -389.467344)
					(mid 114.580162 -389.467344)
					(end 114.961162 -389.467344)
				)
			)
		)
	)
	(zone
		(layer "In1.Cu")
		(hatch none 0.5)
		(connect_pads
			(clearance 0)
		)
		(min_thickness 0.25)
		(keepout
			(tracks not_allowed)
			(vias allowed)
			(pads allowed)
			(copperpour not_allowed)
			(footprints allowed)
		)
		(placement
			(enabled no)
			(sheetname "")
		)
		(fill
			(thermal_gap 0.5)
			(thermal_bridge_width 0.5)
			(island_removal_mode 0)
		)
		(polygon
			(pts
				(arc
					(start 413.117284 -267.282168)
					(mid 413.113564 -267.291148)
					(end 413.104584 -267.294868)
				)
				(arc
					(start 411.631384 -267.294868)
					(mid 411.622404 -267.291148)
					(end 411.618684 -267.282168)
				)
				(arc
					(start 411.618684 -266.78763)
					(mid 411.622404 -266.77865)
					(end 411.631384 -266.77493)
				)
				(arc
					(start 413.104584 -266.77493)
					(mid 413.113564 -266.77865)
					(end 413.117284 -266.78763)
				)
			)
		)
	)
	(zone
		(layer "In1.Cu")
		(hatch none 0.5)
		(connect_pads
			(clearance 0)
		)
		(min_thickness 0.25)
		(keepout
			(tracks not_allowed)
			(vias allowed)
			(pads allowed)
			(copperpour not_allowed)
			(footprints allowed)
		)
		(placement
			(enabled no)
			(sheetname "")
		)
		(fill
			(thermal_gap 0.5)
			(thermal_bridge_width 0.5)
			(island_removal_mode 0)
		)
		(polygon
			(pts
				(arc
					(start 48.66132 -388.774432)
					(mid 48.28032 -388.774432)
					(end 48.66132 -388.774432)
				)
			)
		)
	)
	(zone
		(layer "In1.Cu")
		(hatch none 0.5)
		(connect_pads
			(clearance 0)
		)
		(min_thickness 0.25)
		(keepout
			(tracks not_allowed)
			(vias allowed)
			(pads allowed)
			(copperpour not_allowed)
			(footprints allowed)
		)
		(placement
			(enabled no)
			(sheetname "")
		)
		(fill
			(thermal_gap 0.5)
			(thermal_bridge_width 0.5)
			(island_removal_mode 0)
		)
		(polygon
			(pts
				(arc
					(start 60.177426 -217.982546)
					(mid 60.173706 -217.991526)
					(end 60.164726 -217.995246)
				)
				(arc
					(start 58.691526 -217.995246)
					(mid 58.682546 -217.991526)
					(end 58.678826 -217.982546)
				)
				(arc
					(start 58.678826 -217.488008)
					(mid 58.682546 -217.479028)
					(end 58.691526 -217.475308)
				)
				(arc
					(start 60.164726 -217.475308)
					(mid 60.173706 -217.479028)
					(end 60.177426 -217.488008)
				)
			)
		)
	)
	(zone
		(layer "In1.Cu")
		(hatch none 0.5)
		(connect_pads
			(clearance 0)
		)
		(min_thickness 0.25)
		(keepout
			(tracks not_allowed)
			(vias allowed)
			(pads allowed)
			(copperpour not_allowed)
			(footprints allowed)
		)
		(placement
			(enabled no)
			(sheetname "")
		)
		(fill
			(thermal_gap 0.5)
			(thermal_bridge_width 0.5)
			(island_removal_mode 0)
		)
		(polygon
			(pts
				(arc
					(start 285.485332 -287.682178)
					(mid 285.481612 -287.691158)
					(end 285.472632 -287.694878)
				)
				(arc
					(start 283.999432 -287.694878)
					(mid 283.990452 -287.691158)
					(end 283.986732 -287.682178)
				)
				(arc
					(start 283.986732 -287.18764)
					(mid 283.990452 -287.17866)
					(end 283.999432 -287.17494)
				)
				(arc
					(start 285.472632 -287.17494)
					(mid 285.481612 -287.17866)
					(end 285.485332 -287.18764)
				)
			)
		)
	)
	(zone
		(layer "In1.Cu")
		(hatch none 0.5)
		(connect_pads
			(clearance 0)
		)
		(min_thickness 0.25)
		(keepout
			(tracks not_allowed)
			(vias allowed)
			(pads allowed)
			(copperpour not_allowed)
			(footprints allowed)
		)
		(placement
			(enabled no)
			(sheetname "")
		)
		(fill
			(thermal_gap 0.5)
			(thermal_bridge_width 0.5)
			(island_removal_mode 0)
		)
		(polygon
			(pts
				(arc
					(start 45.089318 -309.782464)
					(mid 45.085598 -309.791444)
					(end 45.076618 -309.795164)
				)
				(arc
					(start 43.603418 -309.795164)
					(mid 43.594438 -309.791444)
					(end 43.590718 -309.782464)
				)
				(arc
					(start 43.590718 -309.287926)
					(mid 43.594438 -309.278946)
					(end 43.603418 -309.275226)
				)
				(arc
					(start 45.076618 -309.275226)
					(mid 45.085598 -309.278946)
					(end 45.089318 -309.287926)
				)
			)
		)
	)
	(zone
		(layer "In1.Cu")
		(hatch none 0.5)
		(connect_pads
			(clearance 0)
		)
		(min_thickness 0.25)
		(keepout
			(tracks not_allowed)
			(vias allowed)
			(pads allowed)
			(copperpour not_allowed)
			(footprints allowed)
		)
		(placement
			(enabled no)
			(sheetname "")
		)
		(fill
			(thermal_gap 0.5)
			(thermal_bridge_width 0.5)
			(island_removal_mode 0)
		)
		(polygon
			(pts
				(arc
					(start 47.67072 -389.276844)
					(mid 47.67072 -389.657844)
					(end 47.67072 -389.276844)
				)
			)
		)
	)
	(zone
		(layer "In1.Cu")
		(hatch none 0.5)
		(connect_pads
			(clearance 0)
		)
		(min_thickness 0.25)
		(keepout
			(tracks not_allowed)
			(vias allowed)
			(pads allowed)
			(copperpour not_allowed)
			(footprints allowed)
		)
		(placement
			(enabled no)
			(sheetname "")
		)
		(fill
			(thermal_gap 0.5)
			(thermal_bridge_width 0.5)
			(island_removal_mode 0)
		)
		(polygon
			(pts
				(arc
					(start 22.45741 -276.632416)
					(mid 22.45369 -276.641396)
					(end 22.44471 -276.645116)
				)
				(arc
					(start 20.97151 -276.645116)
					(mid 20.96253 -276.641396)
					(end 20.95881 -276.632416)
				)
				(arc
					(start 20.95881 -276.137878)
					(mid 20.96253 -276.128898)
					(end 20.97151 -276.125178)
				)
				(arc
					(start 22.44471 -276.125178)
					(mid 22.45369 -276.128898)
					(end 22.45741 -276.137878)
				)
			)
		)
	)
	(zone
		(layer "In1.Cu")
		(hatch none 0.5)
		(connect_pads
			(clearance 0)
		)
		(min_thickness 0.25)
		(keepout
			(tracks not_allowed)
			(vias allowed)
			(pads allowed)
			(copperpour not_allowed)
			(footprints allowed)
		)
		(placement
			(enabled no)
			(sheetname "")
		)
		(fill
			(thermal_gap 0.5)
			(thermal_bridge_width 0.5)
			(island_removal_mode 0)
		)
		(polygon
			(pts
				(arc
					(start 296.473372 -288.532316)
					(mid 296.469652 -288.541296)
					(end 296.460672 -288.545016)
				)
				(arc
					(start 294.987472 -288.545016)
					(mid 294.978492 -288.541296)
					(end 294.974772 -288.532316)
				)
				(arc
					(start 294.974772 -288.037778)
					(mid 294.978492 -288.028798)
					(end 294.987472 -288.025078)
				)
				(arc
					(start 296.460672 -288.025078)
					(mid 296.469652 -288.028798)
					(end 296.473372 -288.037778)
				)
			)
		)
	)
	(zone
		(layer "In1.Cu")
		(hatch none 0.5)
		(connect_pads
			(clearance 0)
		)
		(min_thickness 0.25)
		(keepout
			(tracks not_allowed)
			(vias allowed)
			(pads allowed)
			(copperpour not_allowed)
			(footprints allowed)
		)
		(placement
			(enabled no)
			(sheetname "")
		)
		(fill
			(thermal_gap 0.5)
			(thermal_bridge_width 0.5)
			(island_removal_mode 0)
		)
		(polygon
			(pts
				(arc
					(start 195.353432 -304.682398)
					(mid 195.349712 -304.691378)
					(end 195.340732 -304.695098)
				)
				(arc
					(start 193.867532 -304.695098)
					(mid 193.858552 -304.691378)
					(end 193.854832 -304.682398)
				)
				(arc
					(start 193.854832 -304.18786)
					(mid 193.858552 -304.17888)
					(end 193.867532 -304.17516)
				)
				(arc
					(start 195.340732 -304.17516)
					(mid 195.349712 -304.17888)
					(end 195.353432 -304.18786)
				)
			)
		)
	)
	(zone
		(layer "In1.Cu")
		(hatch none 0.5)
		(connect_pads
			(clearance 0)
		)
		(min_thickness 0.25)
		(keepout
			(tracks not_allowed)
			(vias allowed)
			(pads allowed)
			(copperpour not_allowed)
			(footprints allowed)
		)
		(placement
			(enabled no)
			(sheetname "")
		)
		(fill
			(thermal_gap 0.5)
			(thermal_bridge_width 0.5)
			(island_removal_mode 0)
		)
		(polygon
			(pts
				(arc
					(start 439.849514 -217.982292)
					(mid 439.845794 -217.991272)
					(end 439.836814 -217.994992)
				)
				(arc
					(start 438.363614 -217.994992)
					(mid 438.354634 -217.991272)
					(end 438.350914 -217.982292)
				)
				(arc
					(start 438.350914 -217.487754)
					(mid 438.354634 -217.478774)
					(end 438.363614 -217.475054)
				)
				(arc
					(start 439.836814 -217.475054)
					(mid 439.845794 -217.478774)
					(end 439.849514 -217.487754)
				)
			)
		)
	)
	(zone
		(layer "In1.Cu")
		(hatch none 0.5)
		(connect_pads
			(clearance 0)
		)
		(min_thickness 0.25)
		(keepout
			(tracks not_allowed)
			(vias allowed)
			(pads allowed)
			(copperpour not_allowed)
			(footprints allowed)
		)
		(placement
			(enabled no)
			(sheetname "")
		)
		(fill
			(thermal_gap 0.5)
			(thermal_bridge_width 0.5)
			(island_removal_mode 0)
		)
		(polygon
			(pts
				(arc
					(start 428.205392 -241.782092)
					(mid 428.201672 -241.791072)
					(end 428.192692 -241.794792)
				)
				(arc
					(start 426.719492 -241.794792)
					(mid 426.710512 -241.791072)
					(end 426.706792 -241.782092)
				)
				(arc
					(start 426.706792 -241.287554)
					(mid 426.710512 -241.278574)
					(end 426.719492 -241.274854)
				)
				(arc
					(start 428.192692 -241.274854)
					(mid 428.201672 -241.278574)
					(end 428.205392 -241.287554)
				)
			)
		)
	)
	(zone
		(layer "In1.Cu")
		(hatch none 0.5)
		(connect_pads
			(clearance 0)
		)
		(min_thickness 0.25)
		(keepout
			(tracks not_allowed)
			(vias allowed)
			(pads allowed)
			(copperpour not_allowed)
			(footprints allowed)
		)
		(placement
			(enabled no)
			(sheetname "")
		)
		(fill
			(thermal_gap 0.5)
			(thermal_bridge_width 0.5)
			(island_removal_mode 0)
		)
		(polygon
			(pts
				(arc
					(start 184.365392 -315.732414)
					(mid 184.361672 -315.741394)
					(end 184.352692 -315.745114)
				)
				(arc
					(start 182.879492 -315.745114)
					(mid 182.870512 -315.741394)
					(end 182.866792 -315.732414)
				)
				(arc
					(start 182.866792 -315.237876)
					(mid 182.870512 -315.228896)
					(end 182.879492 -315.225176)
				)
				(arc
					(start 184.352692 -315.225176)
					(mid 184.361672 -315.228896)
					(end 184.365392 -315.237876)
				)
			)
		)
	)
	(zone
		(layer "In1.Cu")
		(hatch none 0.5)
		(connect_pads
			(clearance 0)
		)
		(min_thickness 0.25)
		(keepout
			(tracks not_allowed)
			(vias allowed)
			(pads allowed)
			(copperpour not_allowed)
			(footprints allowed)
		)
		(placement
			(enabled no)
			(sheetname "")
		)
		(fill
			(thermal_gap 0.5)
			(thermal_bridge_width 0.5)
			(island_removal_mode 0)
		)
		(polygon
			(pts
				(arc
					(start 206.5782 -281.48534)
					(mid 205.9178 -281.48534)
					(end 206.5782 -281.48534)
				)
			)
		)
	)
	(zone
		(layer "In1.Cu")
		(hatch none 0.5)
		(connect_pads
			(clearance 0)
		)
		(min_thickness 0.25)
		(keepout
			(tracks not_allowed)
			(vias allowed)
			(pads allowed)
			(copperpour not_allowed)
			(footprints allowed)
		)
		(placement
			(enabled no)
			(sheetname "")
		)
		(fill
			(thermal_gap 0.5)
			(thermal_bridge_width 0.5)
			(island_removal_mode 0)
		)
		(polygon
			(pts
				(arc
					(start 273.841464 -230.73233)
					(mid 273.837744 -230.74131)
					(end 273.828764 -230.74503)
				)
				(arc
					(start 272.355564 -230.74503)
					(mid 272.346584 -230.74131)
					(end 272.342864 -230.73233)
				)
				(arc
					(start 272.342864 -230.237792)
					(mid 272.346584 -230.228812)
					(end 272.355564 -230.225092)
				)
				(arc
					(start 273.828764 -230.225092)
					(mid 273.837744 -230.228812)
					(end 273.841464 -230.237792)
				)
			)
		)
	)
	(zone
		(layer "In1.Cu")
		(hatch none 0.5)
		(connect_pads
			(clearance 0)
		)
		(min_thickness 0.25)
		(keepout
			(tracks not_allowed)
			(vias allowed)
			(pads allowed)
			(copperpour not_allowed)
			(footprints allowed)
		)
		(placement
			(enabled no)
			(sheetname "")
		)
		(fill
			(thermal_gap 0.5)
			(thermal_bridge_width 0.5)
			(island_removal_mode 0)
		)
		(polygon
			(pts
				(arc
					(start 439.849514 -234.982258)
					(mid 439.845794 -234.991238)
					(end 439.836814 -234.994958)
				)
				(arc
					(start 438.363614 -234.994958)
					(mid 438.354634 -234.991238)
					(end 438.350914 -234.982258)
				)
				(arc
					(start 438.350914 -234.48772)
					(mid 438.354634 -234.47874)
					(end 438.363614 -234.47502)
				)
				(arc
					(start 439.836814 -234.47502)
					(mid 439.845794 -234.47874)
					(end 439.849514 -234.48772)
				)
			)
		)
	)
	(zone
		(layer "In1.Cu")
		(hatch none 0.5)
		(connect_pads
			(clearance 0)
		)
		(min_thickness 0.25)
		(keepout
			(tracks not_allowed)
			(vias allowed)
			(pads allowed)
			(copperpour not_allowed)
			(footprints allowed)
		)
		(placement
			(enabled no)
			(sheetname "")
		)
		(fill
			(thermal_gap 0.5)
			(thermal_bridge_width 0.5)
			(island_removal_mode 0)
		)
		(polygon
			(pts
				(arc
					(start 33.445196 -235.832396)
					(mid 33.441476 -235.841376)
					(end 33.432496 -235.845096)
				)
				(arc
					(start 31.959296 -235.845096)
					(mid 31.950316 -235.841376)
					(end 31.946596 -235.832396)
				)
				(arc
					(start 31.946596 -235.337858)
					(mid 31.950316 -235.328878)
					(end 31.959296 -235.325158)
				)
				(arc
					(start 33.432496 -235.325158)
					(mid 33.441476 -235.328878)
					(end 33.445196 -235.337858)
				)
			)
		)
	)
	(zone
		(layer "In1.Cu")
		(hatch none 0.5)
		(connect_pads
			(clearance 0)
		)
		(min_thickness 0.25)
		(keepout
			(tracks not_allowed)
			(vias allowed)
			(pads allowed)
			(copperpour not_allowed)
			(footprints allowed)
		)
		(placement
			(enabled no)
			(sheetname "")
		)
		(fill
			(thermal_gap 0.5)
			(thermal_bridge_width 0.5)
			(island_removal_mode 0)
		)
		(polygon
			(pts
				(arc
					(start 388.090918 -399.701258)
					(mid 388.217918 -399.828258)
					(end 388.344918 -399.701258)
				)
				(arc
					(start 388.344918 -399.625058)
					(mid 388.217918 -399.498058)
					(end 388.090918 -399.625058)
				)
			)
		)
	)
	(zone
		(layer "In1.Cu")
		(hatch none 0.5)
		(connect_pads
			(clearance 0)
		)
		(min_thickness 0.25)
		(keepout
			(tracks not_allowed)
			(vias allowed)
			(pads allowed)
			(copperpour not_allowed)
			(footprints allowed)
		)
		(placement
			(enabled no)
			(sheetname "")
		)
		(fill
			(thermal_gap 0.5)
			(thermal_bridge_width 0.5)
			(island_removal_mode 0)
		)
		(polygon
			(pts
				(arc
					(start 37.545264 -280.03246)
					(mid 37.541544 -280.04144)
					(end 37.532564 -280.04516)
				)
				(arc
					(start 36.059364 -280.04516)
					(mid 36.050384 -280.04144)
					(end 36.046664 -280.03246)
				)
				(arc
					(start 36.046664 -279.537922)
					(mid 36.050384 -279.528942)
					(end 36.059364 -279.525222)
				)
				(arc
					(start 37.532564 -279.525222)
					(mid 37.541544 -279.528942)
					(end 37.545264 -279.537922)
				)
			)
		)
	)
	(zone
		(layer "In1.Cu")
		(hatch none 0.5)
		(connect_pads
			(clearance 0)
		)
		(min_thickness 0.25)
		(keepout
			(tracks not_allowed)
			(vias allowed)
			(pads allowed)
			(copperpour not_allowed)
			(footprints allowed)
		)
		(placement
			(enabled no)
			(sheetname "")
		)
		(fill
			(thermal_gap 0.5)
			(thermal_bridge_width 0.5)
			(island_removal_mode 0)
		)
		(polygon
			(pts
				(arc
					(start 273.841464 -200.132188)
					(mid 273.837744 -200.141168)
					(end 273.828764 -200.144888)
				)
				(arc
					(start 272.355564 -200.144888)
					(mid 272.346584 -200.141168)
					(end 272.342864 -200.132188)
				)
				(arc
					(start 272.342864 -199.63765)
					(mid 272.346584 -199.62867)
					(end 272.355564 -199.62495)
				)
				(arc
					(start 273.828764 -199.62495)
					(mid 273.837744 -199.62867)
					(end 273.841464 -199.63765)
				)
			)
		)
	)
	(zone
		(layer "In1.Cu")
		(hatch none 0.5)
		(connect_pads
			(clearance 0)
		)
		(min_thickness 0.25)
		(keepout
			(tracks not_allowed)
			(vias allowed)
			(pads allowed)
			(copperpour not_allowed)
			(footprints allowed)
		)
		(placement
			(enabled no)
			(sheetname "")
		)
		(fill
			(thermal_gap 0.5)
			(thermal_bridge_width 0.5)
			(island_removal_mode 0)
		)
		(polygon
			(pts
				(arc
					(start 270.397478 -244.332252)
					(mid 270.393758 -244.341232)
					(end 270.384778 -244.344952)
				)
				(arc
					(start 268.911578 -244.344952)
					(mid 268.902598 -244.341232)
					(end 268.898878 -244.332252)
				)
				(arc
					(start 268.898878 -243.837714)
					(mid 268.902598 -243.828734)
					(end 268.911578 -243.825014)
				)
				(arc
					(start 270.384778 -243.825014)
					(mid 270.393758 -243.828734)
					(end 270.397478 -243.837714)
				)
			)
		)
	)
	(zone
		(layer "In1.Cu")
		(hatch none 0.5)
		(connect_pads
			(clearance 0)
		)
		(min_thickness 0.25)
		(keepout
			(tracks not_allowed)
			(vias allowed)
			(pads allowed)
			(copperpour not_allowed)
			(footprints allowed)
		)
		(placement
			(enabled no)
			(sheetname "")
		)
		(fill
			(thermal_gap 0.5)
			(thermal_bridge_width 0.5)
			(island_removal_mode 0)
		)
		(polygon
			(pts
				(arc
					(start 187.809378 -248.582434)
					(mid 187.805658 -248.591414)
					(end 187.796678 -248.595134)
				)
				(arc
					(start 186.323478 -248.595134)
					(mid 186.314498 -248.591414)
					(end 186.310778 -248.582434)
				)
				(arc
					(start 186.310778 -248.087896)
					(mid 186.314498 -248.078916)
					(end 186.323478 -248.075196)
				)
				(arc
					(start 187.796678 -248.075196)
					(mid 187.805658 -248.078916)
					(end 187.809378 -248.087896)
				)
			)
		)
	)
	(zone
		(layer "In1.Cu")
		(hatch none 0.5)
		(connect_pads
			(clearance 0)
		)
		(min_thickness 0.25)
		(keepout
			(tracks not_allowed)
			(vias allowed)
			(pads allowed)
			(copperpour not_allowed)
			(footprints allowed)
		)
		(placement
			(enabled no)
			(sheetname "")
		)
		(fill
			(thermal_gap 0.5)
			(thermal_bridge_width 0.5)
			(island_removal_mode 0)
		)
		(polygon
			(pts
				(arc
					(start 180.265324 -307.232558)
					(mid 180.261604 -307.241538)
					(end 180.252624 -307.245258)
				)
				(arc
					(start 178.779424 -307.245258)
					(mid 178.770444 -307.241538)
					(end 178.766724 -307.232558)
				)
				(arc
					(start 178.766724 -306.73802)
					(mid 178.770444 -306.72904)
					(end 178.779424 -306.72532)
				)
				(arc
					(start 180.252624 -306.72532)
					(mid 180.261604 -306.72904)
					(end 180.265324 -306.73802)
				)
			)
		)
	)
	(zone
		(layer "In1.Cu")
		(hatch none 0.5)
		(connect_pads
			(clearance 0)
		)
		(min_thickness 0.25)
		(keepout
			(tracks not_allowed)
			(vias allowed)
			(pads allowed)
			(copperpour not_allowed)
			(footprints allowed)
		)
		(placement
			(enabled no)
			(sheetname "")
		)
		(fill
			(thermal_gap 0.5)
			(thermal_bridge_width 0.5)
			(island_removal_mode 0)
		)
		(polygon
			(pts
				(arc
					(start 184.365392 -203.532486)
					(mid 184.361672 -203.541466)
					(end 184.352692 -203.545186)
				)
				(arc
					(start 182.879492 -203.545186)
					(mid 182.870512 -203.541466)
					(end 182.866792 -203.532486)
				)
				(arc
					(start 182.866792 -203.037948)
					(mid 182.870512 -203.028968)
					(end 182.879492 -203.025248)
				)
				(arc
					(start 184.352692 -203.025248)
					(mid 184.361672 -203.028968)
					(end 184.365392 -203.037948)
				)
			)
		)
	)
	(zone
		(layer "In1.Cu")
		(hatch none 0.5)
		(connect_pads
			(clearance 0)
		)
		(min_thickness 0.25)
		(keepout
			(tracks not_allowed)
			(vias allowed)
			(pads allowed)
			(copperpour not_allowed)
			(footprints allowed)
		)
		(placement
			(enabled no)
			(sheetname "")
		)
		(fill
			(thermal_gap 0.5)
			(thermal_bridge_width 0.5)
			(island_removal_mode 0)
		)
		(polygon
			(pts
				(arc
					(start 103.808022 -32.842454)
					(mid 103.83034 -32.788572)
					(end 103.884222 -32.766254)
				)
				(arc
					(start 104.112822 -32.766254)
					(mid 104.166704 -32.788572)
					(end 104.189022 -32.842454)
				)
				(arc
					(start 104.189022 -32.994854)
					(mid 104.166704 -33.048736)
					(end 104.112822 -33.071054)
				)
				(arc
					(start 103.884222 -33.071054)
					(mid 103.83034 -33.048736)
					(end 103.808022 -32.994854)
				)
			)
		)
	)
	(zone
		(layer "In1.Cu")
		(hatch none 0.5)
		(connect_pads
			(clearance 0)
		)
		(min_thickness 0.25)
		(keepout
			(tracks not_allowed)
			(vias allowed)
			(pads allowed)
			(copperpour not_allowed)
			(footprints allowed)
		)
		(placement
			(enabled no)
			(sheetname "")
		)
		(fill
			(thermal_gap 0.5)
			(thermal_bridge_width 0.5)
			(island_removal_mode 0)
		)
		(polygon
			(pts
				(arc
					(start 37.545264 -283.432504)
					(mid 37.541544 -283.441484)
					(end 37.532564 -283.445204)
				)
				(arc
					(start 36.059364 -283.445204)
					(mid 36.050384 -283.441484)
					(end 36.046664 -283.432504)
				)
				(arc
					(start 36.046664 -282.937966)
					(mid 36.050384 -282.928986)
					(end 36.059364 -282.925266)
				)
				(arc
					(start 37.532564 -282.925266)
					(mid 37.541544 -282.928986)
					(end 37.545264 -282.937966)
				)
			)
		)
	)
	(zone
		(layer "In1.Cu")
		(hatch none 0.5)
		(connect_pads
			(clearance 0)
		)
		(min_thickness 0.25)
		(keepout
			(tracks not_allowed)
			(vias allowed)
			(pads allowed)
			(copperpour not_allowed)
			(footprints allowed)
		)
		(placement
			(enabled no)
			(sheetname "")
		)
		(fill
			(thermal_gap 0.5)
			(thermal_bridge_width 0.5)
			(island_removal_mode 0)
		)
		(polygon
			(pts
				(arc
					(start 180.265324 -234.132374)
					(mid 180.261604 -234.141354)
					(end 180.252624 -234.145074)
				)
				(arc
					(start 178.779424 -234.145074)
					(mid 178.770444 -234.141354)
					(end 178.766724 -234.132374)
				)
				(arc
					(start 178.766724 -233.637836)
					(mid 178.770444 -233.628856)
					(end 178.779424 -233.625136)
				)
				(arc
					(start 180.252624 -233.625136)
					(mid 180.261604 -233.628856)
					(end 180.265324 -233.637836)
				)
			)
		)
	)
	(zone
		(layer "In1.Cu")
		(hatch none 0.5)
		(connect_pads
			(clearance 0)
		)
		(min_thickness 0.25)
		(keepout
			(tracks not_allowed)
			(vias allowed)
			(pads allowed)
			(copperpour not_allowed)
			(footprints allowed)
		)
		(placement
			(enabled no)
			(sheetname "")
		)
		(fill
			(thermal_gap 0.5)
			(thermal_bridge_width 0.5)
			(island_removal_mode 0)
		)
		(polygon
			(pts
				(arc
					(start 281.385264 -207.78216)
					(mid 281.381544 -207.79114)
					(end 281.372564 -207.79486)
				)
				(arc
					(start 279.899364 -207.79486)
					(mid 279.890384 -207.79114)
					(end 279.886664 -207.78216)
				)
				(arc
					(start 279.886664 -207.287622)
					(mid 279.890384 -207.278642)
					(end 279.899364 -207.274922)
				)
				(arc
					(start 281.372564 -207.274922)
					(mid 281.381544 -207.278642)
					(end 281.385264 -207.287622)
				)
			)
		)
	)
	(zone
		(layer "In1.Cu")
		(hatch none 0.5)
		(connect_pads
			(clearance 0)
		)
		(min_thickness 0.25)
		(keepout
			(tracks not_allowed)
			(vias allowed)
			(pads allowed)
			(copperpour not_allowed)
			(footprints allowed)
		)
		(placement
			(enabled no)
			(sheetname "")
		)
		(fill
			(thermal_gap 0.5)
			(thermal_bridge_width 0.5)
			(island_removal_mode 0)
		)
		(polygon
			(pts
				(arc
					(start 266.29741 -217.132154)
					(mid 266.29369 -217.141134)
					(end 266.28471 -217.144854)
				)
				(arc
					(start 264.81151 -217.144854)
					(mid 264.80253 -217.141134)
					(end 264.79881 -217.132154)
				)
				(arc
					(start 264.79881 -216.637616)
					(mid 264.80253 -216.628636)
					(end 264.81151 -216.624916)
				)
				(arc
					(start 266.28471 -216.624916)
					(mid 266.29369 -216.628636)
					(end 266.29741 -216.637616)
				)
			)
		)
	)
	(zone
		(layer "In1.Cu")
		(hatch none 0.5)
		(connect_pads
			(clearance 0)
		)
		(min_thickness 0.25)
		(keepout
			(tracks not_allowed)
			(vias allowed)
			(pads allowed)
			(copperpour not_allowed)
			(footprints allowed)
		)
		(placement
			(enabled no)
			(sheetname "")
		)
		(fill
			(thermal_gap 0.5)
			(thermal_bridge_width 0.5)
			(island_removal_mode 0)
		)
		(polygon
			(pts
				(arc
					(start 300.57344 -266.432284)
					(mid 300.56972 -266.441264)
					(end 300.56074 -266.444984)
				)
				(arc
					(start 299.08754 -266.444984)
					(mid 299.07856 -266.441264)
					(end 299.07484 -266.432284)
				)
				(arc
					(start 299.07484 -265.937746)
					(mid 299.07856 -265.928766)
					(end 299.08754 -265.925046)
				)
				(arc
					(start 300.56074 -265.925046)
					(mid 300.56972 -265.928766)
					(end 300.57344 -265.937746)
				)
			)
		)
	)
	(zone
		(layer "In1.Cu")
		(hatch none 0.5)
		(connect_pads
			(clearance 0)
		)
		(min_thickness 0.25)
		(keepout
			(tracks not_allowed)
			(vias allowed)
			(pads allowed)
			(copperpour not_allowed)
			(footprints allowed)
		)
		(placement
			(enabled no)
			(sheetname "")
		)
		(fill
			(thermal_gap 0.5)
			(thermal_bridge_width 0.5)
			(island_removal_mode 0)
		)
		(polygon
			(pts
				(arc
					(start 169.277284 -252.832362)
					(mid 169.273564 -252.841342)
					(end 169.264584 -252.845062)
				)
				(arc
					(start 167.791384 -252.845062)
					(mid 167.782404 -252.841342)
					(end 167.778684 -252.832362)
				)
				(arc
					(start 167.778684 -252.337824)
					(mid 167.782404 -252.328844)
					(end 167.791384 -252.325124)
				)
				(arc
					(start 169.264584 -252.325124)
					(mid 169.273564 -252.328844)
					(end 169.277284 -252.337824)
				)
			)
		)
	)
	(zone
		(layer "In1.Cu")
		(hatch none 0.5)
		(connect_pads
			(clearance 0)
		)
		(min_thickness 0.25)
		(keepout
			(tracks not_allowed)
			(vias allowed)
			(pads allowed)
			(copperpour not_allowed)
			(footprints allowed)
		)
		(placement
			(enabled no)
			(sheetname "")
		)
		(fill
			(thermal_gap 0.5)
			(thermal_bridge_width 0.5)
			(island_removal_mode 0)
		)
		(polygon
			(pts
				(arc
					(start 64.99098 -391.319258)
					(mid 65.11798 -391.446258)
					(end 65.24498 -391.319258)
				)
				(arc
					(start 65.24498 -391.243058)
					(mid 65.11798 -391.116058)
					(end 64.99098 -391.243058)
				)
			)
		)
	)
	(zone
		(layer "In1.Cu")
		(hatch none 0.5)
		(connect_pads
			(clearance 0)
		)
		(min_thickness 0.25)
		(keepout
			(tracks not_allowed)
			(vias allowed)
			(pads allowed)
			(copperpour not_allowed)
			(footprints allowed)
		)
		(placement
			(enabled no)
			(sheetname "")
		)
		(fill
			(thermal_gap 0.5)
			(thermal_bridge_width 0.5)
			(island_removal_mode 0)
		)
		(polygon
			(pts
				(arc
					(start 37.545264 -300.43247)
					(mid 37.541544 -300.44145)
					(end 37.532564 -300.44517)
				)
				(arc
					(start 36.059364 -300.44517)
					(mid 36.050384 -300.44145)
					(end 36.046664 -300.43247)
				)
				(arc
					(start 36.046664 -299.937932)
					(mid 36.050384 -299.928952)
					(end 36.059364 -299.925232)
				)
				(arc
					(start 37.532564 -299.925232)
					(mid 37.541544 -299.928952)
					(end 37.545264 -299.937932)
				)
			)
		)
	)
	(zone
		(layer "In1.Cu")
		(hatch none 0.5)
		(connect_pads
			(clearance 0)
		)
		(min_thickness 0.25)
		(keepout
			(tracks not_allowed)
			(vias allowed)
			(pads allowed)
			(copperpour not_allowed)
			(footprints allowed)
		)
		(placement
			(enabled no)
			(sheetname "")
		)
		(fill
			(thermal_gap 0.5)
			(thermal_bridge_width 0.5)
			(island_removal_mode 0)
		)
		(polygon
			(pts
				(arc
					(start 22.45741 -251.13234)
					(mid 22.45369 -251.14132)
					(end 22.44471 -251.14504)
				)
				(arc
					(start 20.97151 -251.14504)
					(mid 20.96253 -251.14132)
					(end 20.95881 -251.13234)
				)
				(arc
					(start 20.95881 -250.637802)
					(mid 20.96253 -250.628822)
					(end 20.97151 -250.625102)
				)
				(arc
					(start 22.44471 -250.625102)
					(mid 22.45369 -250.628822)
					(end 22.45741 -250.637802)
				)
			)
		)
	)
	(zone
		(layer "In1.Cu")
		(hatch none 0.5)
		(connect_pads
			(clearance 0)
		)
		(min_thickness 0.25)
		(keepout
			(tracks not_allowed)
			(vias allowed)
			(pads allowed)
			(copperpour not_allowed)
			(footprints allowed)
		)
		(placement
			(enabled no)
			(sheetname "")
		)
		(fill
			(thermal_gap 0.5)
			(thermal_bridge_width 0.5)
			(island_removal_mode 0)
		)
		(polygon
			(pts
				(arc
					(start 450.8373 -206.082138)
					(mid 450.83358 -206.091118)
					(end 450.8246 -206.094838)
				)
				(arc
					(start 449.3514 -206.094838)
					(mid 449.34242 -206.091118)
					(end 449.3387 -206.082138)
				)
				(arc
					(start 449.3387 -205.5876)
					(mid 449.34242 -205.57862)
					(end 449.3514 -205.5749)
				)
				(arc
					(start 450.8246 -205.5749)
					(mid 450.83358 -205.57862)
					(end 450.8373 -205.5876)
				)
			)
		)
	)
	(zone
		(layer "In1.Cu")
		(hatch none 0.5)
		(connect_pads
			(clearance 0)
		)
		(min_thickness 0.25)
		(keepout
			(tracks not_allowed)
			(vias allowed)
			(pads allowed)
			(copperpour not_allowed)
			(footprints allowed)
		)
		(placement
			(enabled no)
			(sheetname "")
		)
		(fill
			(thermal_gap 0.5)
			(thermal_bridge_width 0.5)
			(island_removal_mode 0)
		)
		(polygon
			(pts
				(arc
					(start 180.265324 -274.932394)
					(mid 180.261604 -274.941374)
					(end 180.252624 -274.945094)
				)
				(arc
					(start 178.779424 -274.945094)
					(mid 178.770444 -274.941374)
					(end 178.766724 -274.932394)
				)
				(arc
					(start 178.766724 -274.437856)
					(mid 178.770444 -274.428876)
					(end 178.779424 -274.425156)
				)
				(arc
					(start 180.252624 -274.425156)
					(mid 180.261604 -274.428876)
					(end 180.265324 -274.437856)
				)
			)
		)
	)
	(zone
		(layer "In1.Cu")
		(hatch none 0.5)
		(connect_pads
			(clearance 0)
		)
		(min_thickness 0.25)
		(keepout
			(tracks not_allowed)
			(vias allowed)
			(pads allowed)
			(copperpour not_allowed)
			(footprints allowed)
		)
		(placement
			(enabled no)
			(sheetname "")
		)
		(fill
			(thermal_gap 0.5)
			(thermal_bridge_width 0.5)
			(island_removal_mode 0)
		)
		(polygon
			(pts
				(arc
					(start 296.473372 -229.882192)
					(mid 296.469652 -229.891172)
					(end 296.460672 -229.894892)
				)
				(arc
					(start 294.987472 -229.894892)
					(mid 294.978492 -229.891172)
					(end 294.974772 -229.882192)
				)
				(arc
					(start 294.974772 -229.387654)
					(mid 294.978492 -229.378674)
					(end 294.987472 -229.374954)
				)
				(arc
					(start 296.460672 -229.374954)
					(mid 296.469652 -229.378674)
					(end 296.473372 -229.387654)
				)
			)
		)
	)
	(zone
		(layer "In1.Cu")
		(hatch none 0.5)
		(connect_pads
			(clearance 0)
		)
		(min_thickness 0.25)
		(keepout
			(tracks not_allowed)
			(vias allowed)
			(pads allowed)
			(copperpour not_allowed)
			(footprints allowed)
		)
		(placement
			(enabled no)
			(sheetname "")
		)
		(fill
			(thermal_gap 0.5)
			(thermal_bridge_width 0.5)
			(island_removal_mode 0)
		)
		(polygon
			(pts
				(arc
					(start 169.277284 -238.382556)
					(mid 169.273564 -238.391536)
					(end 169.264584 -238.395256)
				)
				(arc
					(start 167.791384 -238.395256)
					(mid 167.782404 -238.391536)
					(end 167.778684 -238.382556)
				)
				(arc
					(start 167.778684 -237.888018)
					(mid 167.782404 -237.879038)
					(end 167.791384 -237.875318)
				)
				(arc
					(start 169.264584 -237.875318)
					(mid 169.273564 -237.879038)
					(end 169.277284 -237.888018)
				)
			)
		)
	)
	(zone
		(layer "In1.Cu")
		(hatch none 0.5)
		(connect_pads
			(clearance 0)
		)
		(min_thickness 0.25)
		(keepout
			(tracks not_allowed)
			(vias allowed)
			(pads allowed)
			(copperpour not_allowed)
			(footprints allowed)
		)
		(placement
			(enabled no)
			(sheetname "")
		)
		(fill
			(thermal_gap 0.5)
			(thermal_bridge_width 0.5)
			(island_removal_mode 0)
		)
		(polygon
			(pts
				(arc
					(start 165.177216 -268.982444)
					(mid 165.173496 -268.991424)
					(end 165.164516 -268.995144)
				)
				(arc
					(start 163.691316 -268.995144)
					(mid 163.682336 -268.991424)
					(end 163.678616 -268.982444)
				)
				(arc
					(start 163.678616 -268.487906)
					(mid 163.682336 -268.478926)
					(end 163.691316 -268.475206)
				)
				(arc
					(start 165.164516 -268.475206)
					(mid 165.173496 -268.478926)
					(end 165.177216 -268.487906)
				)
			)
		)
	)
	(zone
		(layer "In1.Cu")
		(hatch none 0.5)
		(connect_pads
			(clearance 0)
		)
		(min_thickness 0.25)
		(keepout
			(tracks not_allowed)
			(vias allowed)
			(pads allowed)
			(copperpour not_allowed)
			(footprints allowed)
		)
		(placement
			(enabled no)
			(sheetname "")
		)
		(fill
			(thermal_gap 0.5)
			(thermal_bridge_width 0.5)
			(island_removal_mode 0)
		)
		(polygon
			(pts
				(arc
					(start 447.393568 -219.682314)
					(mid 447.389848 -219.691294)
					(end 447.380868 -219.695014)
				)
				(arc
					(start 445.907668 -219.695014)
					(mid 445.898688 -219.691294)
					(end 445.894968 -219.682314)
				)
				(arc
					(start 445.894968 -219.187776)
					(mid 445.898688 -219.178796)
					(end 445.907668 -219.175076)
				)
				(arc
					(start 447.380868 -219.175076)
					(mid 447.389848 -219.178796)
					(end 447.393568 -219.187776)
				)
			)
		)
	)
	(zone
		(layer "In1.Cu")
		(hatch none 0.5)
		(connect_pads
			(clearance 0)
		)
		(min_thickness 0.25)
		(keepout
			(tracks not_allowed)
			(vias allowed)
			(pads allowed)
			(copperpour not_allowed)
			(footprints allowed)
		)
		(placement
			(enabled no)
			(sheetname "")
		)
		(fill
			(thermal_gap 0.5)
			(thermal_bridge_width 0.5)
			(island_removal_mode 0)
		)
		(polygon
			(pts
				(arc
					(start 165.177216 -237.532418)
					(mid 165.173496 -237.541398)
					(end 165.164516 -237.545118)
				)
				(arc
					(start 163.691316 -237.545118)
					(mid 163.682336 -237.541398)
					(end 163.678616 -237.532418)
				)
				(arc
					(start 163.678616 -237.03788)
					(mid 163.682336 -237.0289)
					(end 163.691316 -237.02518)
				)
				(arc
					(start 165.164516 -237.02518)
					(mid 165.173496 -237.0289)
					(end 165.177216 -237.03788)
				)
			)
		)
	)
	(zone
		(layer "In1.Cu")
		(hatch none 0.5)
		(connect_pads
			(clearance 0)
		)
		(min_thickness 0.25)
		(keepout
			(tracks not_allowed)
			(vias allowed)
			(pads allowed)
			(copperpour not_allowed)
			(footprints allowed)
		)
		(placement
			(enabled no)
			(sheetname "")
		)
		(fill
			(thermal_gap 0.5)
			(thermal_bridge_width 0.5)
			(island_removal_mode 0)
		)
		(polygon
			(pts
				(arc
					(start 424.761406 -274.082256)
					(mid 424.757686 -274.091236)
					(end 424.748706 -274.094956)
				)
				(arc
					(start 423.275506 -274.094956)
					(mid 423.266526 -274.091236)
					(end 423.262806 -274.082256)
				)
				(arc
					(start 423.262806 -273.587718)
					(mid 423.266526 -273.578738)
					(end 423.275506 -273.575018)
				)
				(arc
					(start 424.748706 -273.575018)
					(mid 424.757686 -273.578738)
					(end 424.761406 -273.587718)
				)
			)
		)
	)
	(zone
		(layer "In1.Cu")
		(hatch none 0.5)
		(connect_pads
			(clearance 0)
		)
		(min_thickness 0.25)
		(keepout
			(tracks not_allowed)
			(vias allowed)
			(pads allowed)
			(copperpour not_allowed)
			(footprints allowed)
		)
		(placement
			(enabled no)
			(sheetname "")
		)
		(fill
			(thermal_gap 0.5)
			(thermal_bridge_width 0.5)
			(island_removal_mode 0)
		)
		(polygon
			(pts
				(arc
					(start 420.661338 -267.282168)
					(mid 420.657618 -267.291148)
					(end 420.648638 -267.294868)
				)
				(arc
					(start 419.175438 -267.294868)
					(mid 419.166458 -267.291148)
					(end 419.162738 -267.282168)
				)
				(arc
					(start 419.162738 -266.78763)
					(mid 419.166458 -266.77865)
					(end 419.175438 -266.77493)
				)
				(arc
					(start 420.648638 -266.77493)
					(mid 420.657618 -266.77865)
					(end 420.661338 -266.78763)
				)
			)
		)
	)
	(zone
		(layer "In1.Cu")
		(hatch none 0.5)
		(connect_pads
			(clearance 0)
		)
		(min_thickness 0.25)
		(keepout
			(tracks not_allowed)
			(vias allowed)
			(pads allowed)
			(copperpour not_allowed)
			(footprints allowed)
		)
		(placement
			(enabled no)
			(sheetname "")
		)
		(fill
			(thermal_gap 0.5)
			(thermal_bridge_width 0.5)
			(island_removal_mode 0)
		)
		(polygon
			(pts
				(arc
					(start 314.660788 -397.849344)
					(mid 314.279788 -397.849344)
					(end 314.660788 -397.849344)
				)
			)
		)
	)
	(zone
		(layer "In1.Cu")
		(hatch none 0.5)
		(connect_pads
			(clearance 0)
		)
		(min_thickness 0.25)
		(keepout
			(tracks not_allowed)
			(vias allowed)
			(pads allowed)
			(copperpour not_allowed)
			(footprints allowed)
		)
		(placement
			(enabled no)
			(sheetname "")
		)
		(fill
			(thermal_gap 0.5)
			(thermal_bridge_width 0.5)
			(island_removal_mode 0)
		)
		(polygon
			(pts
				(arc
					(start 206.9973 -278.332438)
					(mid 206.99358 -278.341418)
					(end 206.9846 -278.345138)
				)
				(arc
					(start 205.5114 -278.345138)
					(mid 205.50242 -278.341418)
					(end 205.4987 -278.332438)
				)
				(arc
					(start 205.4987 -277.8379)
					(mid 205.50242 -277.82892)
					(end 205.5114 -277.8252)
				)
				(arc
					(start 206.9846 -277.8252)
					(mid 206.99358 -277.82892)
					(end 206.9973 -277.8379)
				)
			)
		)
	)
	(zone
		(layer "In1.Cu")
		(hatch none 0.5)
		(connect_pads
			(clearance 0)
		)
		(min_thickness 0.25)
		(keepout
			(tracks not_allowed)
			(vias allowed)
			(pads allowed)
			(copperpour not_allowed)
			(footprints allowed)
		)
		(placement
			(enabled no)
			(sheetname "")
		)
		(fill
			(thermal_gap 0.5)
			(thermal_bridge_width 0.5)
			(island_removal_mode 0)
		)
		(polygon
			(pts
				(arc
					(start 95.118682 -391.319258)
					(mid 95.245682 -391.446258)
					(end 95.372682 -391.319258)
				)
				(arc
					(start 95.372682 -391.243058)
					(mid 95.245682 -391.116058)
					(end 95.118682 -391.243058)
				)
			)
		)
	)
	(zone
		(layer "In1.Cu")
		(hatch none 0.5)
		(connect_pads
			(clearance 0)
		)
		(min_thickness 0.25)
		(keepout
			(tracks not_allowed)
			(vias allowed)
			(pads allowed)
			(copperpour not_allowed)
			(footprints allowed)
		)
		(placement
			(enabled no)
			(sheetname "")
		)
		(fill
			(thermal_gap 0.5)
			(thermal_bridge_width 0.5)
			(island_removal_mode 0)
		)
		(polygon
			(pts
				(arc
					(start 202.897232 -263.882378)
					(mid 202.893512 -263.891358)
					(end 202.884532 -263.895078)
				)
				(arc
					(start 201.411332 -263.895078)
					(mid 201.402352 -263.891358)
					(end 201.398632 -263.882378)
				)
				(arc
					(start 201.398632 -263.38784)
					(mid 201.402352 -263.37886)
					(end 201.411332 -263.37514)
				)
				(arc
					(start 202.884532 -263.37514)
					(mid 202.893512 -263.37886)
					(end 202.897232 -263.38784)
				)
			)
		)
	)
	(zone
		(layer "In1.Cu")
		(hatch none 0.5)
		(connect_pads
			(clearance 0)
		)
		(min_thickness 0.25)
		(keepout
			(tracks not_allowed)
			(vias allowed)
			(pads allowed)
			(copperpour not_allowed)
			(footprints allowed)
		)
		(placement
			(enabled no)
			(sheetname "")
		)
		(fill
			(thermal_gap 0.5)
			(thermal_bridge_width 0.5)
			(island_removal_mode 0)
		)
		(polygon
			(pts
				(arc
					(start 47.57039 -390.761474)
					(mid 47.26559 -390.761474)
					(end 47.57039 -390.761474)
				)
			)
		)
	)
	(zone
		(layer "In1.Cu")
		(hatch none 0.5)
		(connect_pads
			(clearance 0)
		)
		(min_thickness 0.25)
		(keepout
			(tracks not_allowed)
			(vias allowed)
			(pads allowed)
			(copperpour not_allowed)
			(footprints allowed)
		)
		(placement
			(enabled no)
			(sheetname "")
		)
		(fill
			(thermal_gap 0.5)
			(thermal_bridge_width 0.5)
			(island_removal_mode 0)
		)
		(polygon
			(pts
				(arc
					(start 293.029386 -216.28227)
					(mid 293.025666 -216.29125)
					(end 293.016686 -216.29497)
				)
				(arc
					(start 291.543486 -216.29497)
					(mid 291.534506 -216.29125)
					(end 291.530786 -216.28227)
				)
				(arc
					(start 291.530786 -215.787732)
					(mid 291.534506 -215.778752)
					(end 291.543486 -215.775032)
				)
				(arc
					(start 293.016686 -215.775032)
					(mid 293.025666 -215.778752)
					(end 293.029386 -215.787732)
				)
			)
		)
	)
	(zone
		(layer "In1.Cu")
		(hatch none 0.5)
		(connect_pads
			(clearance 0)
		)
		(min_thickness 0.25)
		(keepout
			(tracks not_allowed)
			(vias allowed)
			(pads allowed)
			(copperpour not_allowed)
			(footprints allowed)
		)
		(placement
			(enabled no)
			(sheetname "")
		)
		(fill
			(thermal_gap 0.5)
			(thermal_bridge_width 0.5)
			(island_removal_mode 0)
		)
		(polygon
			(pts
				(arc
					(start 265.87831 -267.035026)
					(mid 265.21791 -267.035026)
					(end 265.87831 -267.035026)
				)
			)
		)
	)
	(zone
		(layer "In1.Cu")
		(hatch none 0.5)
		(connect_pads
			(clearance 0)
		)
		(min_thickness 0.25)
		(keepout
			(tracks not_allowed)
			(vias allowed)
			(pads allowed)
			(copperpour not_allowed)
			(footprints allowed)
		)
		(placement
			(enabled no)
			(sheetname "")
		)
		(fill
			(thermal_gap 0.5)
			(thermal_bridge_width 0.5)
			(island_removal_mode 0)
		)
		(polygon
			(pts
				(arc
					(start 296.473372 -215.432132)
					(mid 296.469652 -215.441112)
					(end 296.460672 -215.444832)
				)
				(arc
					(start 294.987472 -215.444832)
					(mid 294.978492 -215.441112)
					(end 294.974772 -215.432132)
				)
				(arc
					(start 294.974772 -214.937594)
					(mid 294.978492 -214.928614)
					(end 294.987472 -214.924894)
				)
				(arc
					(start 296.460672 -214.924894)
					(mid 296.469652 -214.928614)
					(end 296.473372 -214.937594)
				)
			)
		)
	)
	(zone
		(layer "In1.Cu")
		(hatch none 0.5)
		(connect_pads
			(clearance 0)
		)
		(min_thickness 0.25)
		(keepout
			(tracks not_allowed)
			(vias allowed)
			(pads allowed)
			(copperpour not_allowed)
			(footprints allowed)
		)
		(placement
			(enabled no)
			(sheetname "")
		)
		(fill
			(thermal_gap 0.5)
			(thermal_bridge_width 0.5)
			(island_removal_mode 0)
		)
		(polygon
			(pts
				(arc
					(start 92.71889 -391.319258)
					(mid 92.84589 -391.446258)
					(end 92.97289 -391.319258)
				)
				(arc
					(start 92.97289 -391.243058)
					(mid 92.84589 -391.116058)
					(end 92.71889 -391.243058)
				)
			)
		)
	)
	(zone
		(layer "In1.Cu")
		(hatch none 0.5)
		(connect_pads
			(clearance 0)
		)
		(min_thickness 0.25)
		(keepout
			(tracks not_allowed)
			(vias allowed)
			(pads allowed)
			(copperpour not_allowed)
			(footprints allowed)
		)
		(placement
			(enabled no)
			(sheetname "")
		)
		(fill
			(thermal_gap 0.5)
			(thermal_bridge_width 0.5)
			(island_removal_mode 0)
		)
		(polygon
			(pts
				(arc
					(start 195.353432 -314.032392)
					(mid 195.349712 -314.041372)
					(end 195.340732 -314.045092)
				)
				(arc
					(start 193.867532 -314.045092)
					(mid 193.858552 -314.041372)
					(end 193.854832 -314.032392)
				)
				(arc
					(start 193.854832 -313.537854)
					(mid 193.858552 -313.528874)
					(end 193.867532 -313.525154)
				)
				(arc
					(start 195.340732 -313.525154)
					(mid 195.349712 -313.528874)
					(end 195.353432 -313.537854)
				)
			)
		)
	)
	(zone
		(layer "In1.Cu")
		(hatch none 0.5)
		(connect_pads
			(clearance 0)
		)
		(min_thickness 0.25)
		(keepout
			(tracks not_allowed)
			(vias allowed)
			(pads allowed)
			(copperpour not_allowed)
			(footprints allowed)
		)
		(placement
			(enabled no)
			(sheetname "")
		)
		(fill
			(thermal_gap 0.5)
			(thermal_bridge_width 0.5)
			(island_removal_mode 0)
		)
		(polygon
			(pts
				(arc
					(start 56.077358 -286.832548)
					(mid 56.073638 -286.841528)
					(end 56.064658 -286.845248)
				)
				(arc
					(start 54.591458 -286.845248)
					(mid 54.582478 -286.841528)
					(end 54.578758 -286.832548)
				)
				(arc
					(start 54.578758 -286.33801)
					(mid 54.582478 -286.32903)
					(end 54.591458 -286.32531)
				)
				(arc
					(start 56.064658 -286.32531)
					(mid 56.073638 -286.32903)
					(end 56.077358 -286.33801)
				)
			)
		)
	)
	(zone
		(layer "In1.Cu")
		(hatch none 0.5)
		(connect_pads
			(clearance 0)
		)
		(min_thickness 0.25)
		(keepout
			(tracks not_allowed)
			(vias allowed)
			(pads allowed)
			(copperpour not_allowed)
			(footprints allowed)
		)
		(placement
			(enabled no)
			(sheetname "")
		)
		(fill
			(thermal_gap 0.5)
			(thermal_bridge_width 0.5)
			(island_removal_mode 0)
		)
		(polygon
			(pts
				(arc
					(start 406.689052 -393.69238)
					(mid 406.308052 -393.69238)
					(end 406.689052 -393.69238)
				)
			)
		)
	)
	(zone
		(layer "In1.Cu")
		(hatch none 0.5)
		(connect_pads
			(clearance 0)
		)
		(min_thickness 0.25)
		(keepout
			(tracks not_allowed)
			(vias allowed)
			(pads allowed)
			(copperpour not_allowed)
			(footprints allowed)
		)
		(placement
			(enabled no)
			(sheetname "")
		)
		(fill
			(thermal_gap 0.5)
			(thermal_bridge_width 0.5)
			(island_removal_mode 0)
		)
		(polygon
			(pts
				(arc
					(start 18.357342 -299.582586)
					(mid 18.353622 -299.591566)
					(end 18.344642 -299.595286)
				)
				(arc
					(start 16.871442 -299.595286)
					(mid 16.862462 -299.591566)
					(end 16.858742 -299.582586)
				)
				(arc
					(start 16.858742 -299.088048)
					(mid 16.862462 -299.079068)
					(end 16.871442 -299.075348)
				)
				(arc
					(start 18.344642 -299.075348)
					(mid 18.353622 -299.079068)
					(end 18.357342 -299.088048)
				)
			)
		)
	)
	(zone
		(layer "In1.Cu")
		(hatch none 0.5)
		(connect_pads
			(clearance 0)
		)
		(min_thickness 0.25)
		(keepout
			(tracks not_allowed)
			(vias allowed)
			(pads allowed)
			(copperpour not_allowed)
			(footprints allowed)
		)
		(placement
			(enabled no)
			(sheetname "")
		)
		(fill
			(thermal_gap 0.5)
			(thermal_bridge_width 0.5)
			(island_removal_mode 0)
		)
		(polygon
			(pts
				(arc
					(start 56.077358 -254.532384)
					(mid 56.073638 -254.541364)
					(end 56.064658 -254.545084)
				)
				(arc
					(start 54.591458 -254.545084)
					(mid 54.582478 -254.541364)
					(end 54.578758 -254.532384)
				)
				(arc
					(start 54.578758 -254.037846)
					(mid 54.582478 -254.028866)
					(end 54.591458 -254.025146)
				)
				(arc
					(start 56.064658 -254.025146)
					(mid 56.073638 -254.028866)
					(end 56.077358 -254.037846)
				)
			)
		)
	)
	(zone
		(layer "In1.Cu")
		(hatch none 0.5)
		(connect_pads
			(clearance 0)
		)
		(min_thickness 0.25)
		(keepout
			(tracks not_allowed)
			(vias allowed)
			(pads allowed)
			(copperpour not_allowed)
			(footprints allowed)
		)
		(placement
			(enabled no)
			(sheetname "")
		)
		(fill
			(thermal_gap 0.5)
			(thermal_bridge_width 0.5)
			(island_removal_mode 0)
		)
		(polygon
			(pts
				(arc
					(start 25.901396 -213.732364)
					(mid 25.897676 -213.741344)
					(end 25.888696 -213.745064)
				)
				(arc
					(start 24.415496 -213.745064)
					(mid 24.406516 -213.741344)
					(end 24.402796 -213.732364)
				)
				(arc
					(start 24.402796 -213.237826)
					(mid 24.406516 -213.228846)
					(end 24.415496 -213.225126)
				)
				(arc
					(start 25.888696 -213.225126)
					(mid 25.897676 -213.228846)
					(end 25.901396 -213.237826)
				)
			)
		)
	)
	(zone
		(layer "In1.Cu")
		(hatch none 0.5)
		(connect_pads
			(clearance 0)
		)
		(min_thickness 0.25)
		(keepout
			(tracks not_allowed)
			(vias allowed)
			(pads allowed)
			(copperpour not_allowed)
			(footprints allowed)
		)
		(placement
			(enabled no)
			(sheetname "")
		)
		(fill
			(thermal_gap 0.5)
			(thermal_bridge_width 0.5)
			(island_removal_mode 0)
		)
		(polygon
			(pts
				(arc
					(start 420.661338 -212.032088)
					(mid 420.657618 -212.041068)
					(end 420.648638 -212.044788)
				)
				(arc
					(start 419.175438 -212.044788)
					(mid 419.166458 -212.041068)
					(end 419.162738 -212.032088)
				)
				(arc
					(start 419.162738 -211.53755)
					(mid 419.166458 -211.52857)
					(end 419.175438 -211.52485)
				)
				(arc
					(start 420.648638 -211.52485)
					(mid 420.657618 -211.52857)
					(end 420.661338 -211.53755)
				)
			)
		)
	)
	(zone
		(layer "In1.Cu")
		(hatch none 0.5)
		(connect_pads
			(clearance 0)
		)
		(min_thickness 0.25)
		(keepout
			(tracks not_allowed)
			(vias allowed)
			(pads allowed)
			(copperpour not_allowed)
			(footprints allowed)
		)
		(placement
			(enabled no)
			(sheetname "")
		)
		(fill
			(thermal_gap 0.5)
			(thermal_bridge_width 0.5)
			(island_removal_mode 0)
		)
		(polygon
			(pts
				(arc
					(start 315.570108 -392.30427)
					(mid 315.265308 -392.30427)
					(end 315.570108 -392.30427)
				)
			)
		)
	)
	(zone
		(layer "In1.Cu")
		(hatch none 0.5)
		(connect_pads
			(clearance 0)
		)
		(min_thickness 0.25)
		(keepout
			(tracks not_allowed)
			(vias allowed)
			(pads allowed)
			(copperpour not_allowed)
			(footprints allowed)
		)
		(placement
			(enabled no)
			(sheetname "")
		)
		(fill
			(thermal_gap 0.5)
			(thermal_bridge_width 0.5)
			(island_removal_mode 0)
		)
		(polygon
			(pts
				(arc
					(start 347.627448 -379.360684)
					(mid 347.647372 -379.36992)
					(end 347.669104 -379.37313)
				)
				(arc
					(start 347.863668 -379.37313)
					(mid 347.91755 -379.350812)
					(end 347.939868 -379.29693)
				)
				(arc
					(start 347.939868 -378.61113)
					(mid 347.91755 -378.557248)
					(end 347.863668 -378.53493)
				)
				(arc
					(start 347.669104 -378.53493)
					(mid 347.64736 -378.538098)
					(end 347.627448 -378.547376)
				)
				(arc
					(start 347.331284 -378.740162)
					(mid 347.2896 -378.752384)
					(end 347.247972 -378.739908)
				)
				(arc
					(start 346.954348 -378.547376)
					(mid 346.934424 -378.53814)
					(end 346.912692 -378.53493)
				)
				(arc
					(start 346.718128 -378.53493)
					(mid 346.664246 -378.557248)
					(end 346.641928 -378.61113)
				)
				(arc
					(start 346.641928 -379.29693)
					(mid 346.664246 -379.350812)
					(end 346.718128 -379.37313)
				)
				(arc
					(start 346.913962 -379.37313)
					(mid 346.935706 -379.369962)
					(end 346.955618 -379.360684)
				)
				(arc
					(start 347.249242 -379.168152)
					(mid 347.290898 -379.15575)
					(end 347.332554 -379.168152)
				)
			)
		)
	)
	(zone
		(layer "In1.Cu")
		(hatch none 0.5)
		(connect_pads
			(clearance 0)
		)
		(min_thickness 0.25)
		(keepout
			(tracks not_allowed)
			(vias allowed)
			(pads allowed)
			(copperpour not_allowed)
			(footprints allowed)
		)
		(placement
			(enabled no)
			(sheetname "")
		)
		(fill
			(thermal_gap 0.5)
			(thermal_bridge_width 0.5)
			(island_removal_mode 0)
		)
		(polygon
			(pts
				(arc
					(start 59.861196 -386.003292)
					(mid 59.480196 -386.003292)
					(end 59.861196 -386.003292)
				)
			)
		)
	)
	(zone
		(layer "In1.Cu")
		(hatch none 0.5)
		(connect_pads
			(clearance 0)
		)
		(min_thickness 0.25)
		(keepout
			(tracks not_allowed)
			(vias allowed)
			(pads allowed)
			(copperpour not_allowed)
			(footprints allowed)
		)
		(placement
			(enabled no)
			(sheetname "")
		)
		(fill
			(thermal_gap 0.5)
			(thermal_bridge_width 0.5)
			(island_removal_mode 0)
		)
		(polygon
			(pts
				(arc
					(start 435.749446 -316.582298)
					(mid 435.745726 -316.591278)
					(end 435.736746 -316.594998)
				)
				(arc
					(start 434.263546 -316.594998)
					(mid 434.254566 -316.591278)
					(end 434.250846 -316.582298)
				)
				(arc
					(start 434.250846 -316.08776)
					(mid 434.254566 -316.07878)
					(end 434.263546 -316.07506)
				)
				(arc
					(start 435.736746 -316.07506)
					(mid 435.745726 -316.07878)
					(end 435.749446 -316.08776)
				)
			)
		)
	)
	(zone
		(layer "In1.Cu")
		(hatch none 0.5)
		(connect_pads
			(clearance 0)
		)
		(min_thickness 0.25)
		(keepout
			(tracks not_allowed)
			(vias allowed)
			(pads allowed)
			(copperpour not_allowed)
			(footprints allowed)
		)
		(placement
			(enabled no)
			(sheetname "")
		)
		(fill
			(thermal_gap 0.5)
			(thermal_bridge_width 0.5)
			(island_removal_mode 0)
		)
		(polygon
			(pts
				(arc
					(start 97.188782 -389.467344)
					(mid 96.807782 -389.467344)
					(end 97.188782 -389.467344)
				)
			)
		)
	)
	(zone
		(layer "In1.Cu")
		(hatch none 0.5)
		(connect_pads
			(clearance 0)
		)
		(min_thickness 0.25)
		(keepout
			(tracks not_allowed)
			(vias allowed)
			(pads allowed)
			(copperpour not_allowed)
			(footprints allowed)
		)
		(placement
			(enabled no)
			(sheetname "")
		)
		(fill
			(thermal_gap 0.5)
			(thermal_bridge_width 0.5)
			(island_removal_mode 0)
		)
		(polygon
			(pts
				(arc
					(start 304.017426 -284.282134)
					(mid 304.013706 -284.291114)
					(end 304.004726 -284.294834)
				)
				(arc
					(start 302.531526 -284.294834)
					(mid 302.522546 -284.291114)
					(end 302.518826 -284.282134)
				)
				(arc
					(start 302.518826 -283.787596)
					(mid 302.522546 -283.778616)
					(end 302.531526 -283.774896)
				)
				(arc
					(start 304.004726 -283.774896)
					(mid 304.013706 -283.778616)
					(end 304.017426 -283.787596)
				)
			)
		)
	)
	(zone
		(layer "In1.Cu")
		(hatch none 0.5)
		(connect_pads
			(clearance 0)
		)
		(min_thickness 0.25)
		(keepout
			(tracks not_allowed)
			(vias allowed)
			(pads allowed)
			(copperpour not_allowed)
			(footprints allowed)
		)
		(placement
			(enabled no)
			(sheetname "")
		)
		(fill
			(thermal_gap 0.5)
			(thermal_bridge_width 0.5)
			(island_removal_mode 0)
		)
		(polygon
			(pts
				(arc
					(start 169.277284 -274.08251)
					(mid 169.273564 -274.09149)
					(end 169.264584 -274.09521)
				)
				(arc
					(start 167.791384 -274.09521)
					(mid 167.782404 -274.09149)
					(end 167.778684 -274.08251)
				)
				(arc
					(start 167.778684 -273.587972)
					(mid 167.782404 -273.578992)
					(end 167.791384 -273.575272)
				)
				(arc
					(start 169.264584 -273.575272)
					(mid 169.273564 -273.578992)
					(end 169.277284 -273.587972)
				)
			)
		)
	)
	(zone
		(layer "In1.Cu")
		(hatch none 0.5)
		(connect_pads
			(clearance 0)
		)
		(min_thickness 0.25)
		(keepout
			(tracks not_allowed)
			(vias allowed)
			(pads allowed)
			(copperpour not_allowed)
			(footprints allowed)
		)
		(placement
			(enabled no)
			(sheetname "")
		)
		(fill
			(thermal_gap 0.5)
			(thermal_bridge_width 0.5)
			(island_removal_mode 0)
		)
		(polygon
			(pts
				(arc
					(start 340.318598 -399.701258)
					(mid 340.445598 -399.828258)
					(end 340.572598 -399.701258)
				)
				(arc
					(start 340.572598 -399.625058)
					(mid 340.445598 -399.498058)
					(end 340.318598 -399.625058)
				)
			)
		)
	)
	(zone
		(layer "In1.Cu")
		(hatch none 0.5)
		(connect_pads
			(clearance 0)
		)
		(min_thickness 0.25)
		(keepout
			(tracks not_allowed)
			(vias allowed)
			(pads allowed)
			(copperpour not_allowed)
			(footprints allowed)
		)
		(placement
			(enabled no)
			(sheetname "")
		)
		(fill
			(thermal_gap 0.5)
			(thermal_bridge_width 0.5)
			(island_removal_mode 0)
		)
		(polygon
			(pts
				(arc
					(start 25.901396 -282.582366)
					(mid 25.897676 -282.591346)
					(end 25.888696 -282.595066)
				)
				(arc
					(start 24.415496 -282.595066)
					(mid 24.406516 -282.591346)
					(end 24.402796 -282.582366)
				)
				(arc
					(start 24.402796 -282.087828)
					(mid 24.406516 -282.078848)
					(end 24.415496 -282.075128)
				)
				(arc
					(start 25.888696 -282.075128)
					(mid 25.897676 -282.078848)
					(end 25.901396 -282.087828)
				)
			)
		)
	)
	(zone
		(layer "In1.Cu")
		(hatch none 0.5)
		(connect_pads
			(clearance 0)
		)
		(min_thickness 0.25)
		(keepout
			(tracks not_allowed)
			(vias allowed)
			(pads allowed)
			(copperpour not_allowed)
			(footprints allowed)
		)
		(placement
			(enabled no)
			(sheetname "")
		)
		(fill
			(thermal_gap 0.5)
			(thermal_bridge_width 0.5)
			(island_removal_mode 0)
		)
		(polygon
			(pts
				(arc
					(start 176.821338 -314.032392)
					(mid 176.817618 -314.041372)
					(end 176.808638 -314.045092)
				)
				(arc
					(start 175.335438 -314.045092)
					(mid 175.326458 -314.041372)
					(end 175.322738 -314.032392)
				)
				(arc
					(start 175.322738 -313.537854)
					(mid 175.326458 -313.528874)
					(end 175.335438 -313.525154)
				)
				(arc
					(start 176.808638 -313.525154)
					(mid 176.817618 -313.528874)
					(end 176.821338 -313.537854)
				)
			)
		)
	)
	(zone
		(layer "In1.Cu")
		(hatch none 0.5)
		(connect_pads
			(clearance 0)
		)
		(min_thickness 0.25)
		(keepout
			(tracks not_allowed)
			(vias allowed)
			(pads allowed)
			(copperpour not_allowed)
			(footprints allowed)
		)
		(placement
			(enabled no)
			(sheetname "")
		)
		(fill
			(thermal_gap 0.5)
			(thermal_bridge_width 0.5)
			(island_removal_mode 0)
		)
		(polygon
			(pts
				(arc
					(start 40.98925 -305.532536)
					(mid 40.98553 -305.541516)
					(end 40.97655 -305.545236)
				)
				(arc
					(start 39.50335 -305.545236)
					(mid 39.49437 -305.541516)
					(end 39.49065 -305.532536)
				)
				(arc
					(start 39.49065 -305.037998)
					(mid 39.49437 -305.029018)
					(end 39.50335 -305.025298)
				)
				(arc
					(start 40.97655 -305.025298)
					(mid 40.98553 -305.029018)
					(end 40.98925 -305.037998)
				)
			)
		)
	)
	(zone
		(layer "In1.Cu")
		(hatch none 0.5)
		(connect_pads
			(clearance 0)
		)
		(min_thickness 0.25)
		(keepout
			(tracks not_allowed)
			(vias allowed)
			(pads allowed)
			(copperpour not_allowed)
			(footprints allowed)
		)
		(placement
			(enabled no)
			(sheetname "")
		)
		(fill
			(thermal_gap 0.5)
			(thermal_bridge_width 0.5)
			(island_removal_mode 0)
		)
		(polygon
			(pts
				(arc
					(start 432.30546 -264.732262)
					(mid 432.30174 -264.741242)
					(end 432.29276 -264.744962)
				)
				(arc
					(start 430.81956 -264.744962)
					(mid 430.81058 -264.741242)
					(end 430.80686 -264.732262)
				)
				(arc
					(start 430.80686 -264.237724)
					(mid 430.81058 -264.228744)
					(end 430.81956 -264.225024)
				)
				(arc
					(start 432.29276 -264.225024)
					(mid 432.30174 -264.228744)
					(end 432.30546 -264.237724)
				)
			)
		)
	)
	(zone
		(layer "In1.Cu")
		(hatch none 0.5)
		(connect_pads
			(clearance 0)
		)
		(min_thickness 0.25)
		(keepout
			(tracks not_allowed)
			(vias allowed)
			(pads allowed)
			(copperpour not_allowed)
			(footprints allowed)
		)
		(placement
			(enabled no)
			(sheetname "")
		)
		(fill
			(thermal_gap 0.5)
			(thermal_bridge_width 0.5)
			(island_removal_mode 0)
		)
		(polygon
			(pts
				(arc
					(start 48.533304 -307.232558)
					(mid 48.529584 -307.241538)
					(end 48.520604 -307.245258)
				)
				(arc
					(start 47.047404 -307.245258)
					(mid 47.038424 -307.241538)
					(end 47.034704 -307.232558)
				)
				(arc
					(start 47.034704 -306.73802)
					(mid 47.038424 -306.72904)
					(end 47.047404 -306.72532)
				)
				(arc
					(start 48.520604 -306.72532)
					(mid 48.529584 -306.72904)
					(end 48.533304 -306.73802)
				)
			)
		)
	)
	(zone
		(layer "In1.Cu")
		(hatch none 0.5)
		(connect_pads
			(clearance 0)
		)
		(min_thickness 0.25)
		(keepout
			(tracks not_allowed)
			(vias allowed)
			(pads allowed)
			(copperpour not_allowed)
			(footprints allowed)
		)
		(placement
			(enabled no)
			(sheetname "")
		)
		(fill
			(thermal_gap 0.5)
			(thermal_bridge_width 0.5)
			(island_removal_mode 0)
		)
		(polygon
			(pts
				(arc
					(start 184.365392 -302.132492)
					(mid 184.361672 -302.141472)
					(end 184.352692 -302.145192)
				)
				(arc
					(start 182.879492 -302.145192)
					(mid 182.870512 -302.141472)
					(end 182.866792 -302.132492)
				)
				(arc
					(start 182.866792 -301.637954)
					(mid 182.870512 -301.628974)
					(end 182.879492 -301.625254)
				)
				(arc
					(start 184.352692 -301.625254)
					(mid 184.361672 -301.628974)
					(end 184.365392 -301.637954)
				)
			)
		)
	)
	(zone
		(layer "In1.Cu")
		(hatch none 0.5)
		(connect_pads
			(clearance 0)
		)
		(min_thickness 0.25)
		(keepout
			(tracks not_allowed)
			(vias allowed)
			(pads allowed)
			(copperpour not_allowed)
			(footprints allowed)
		)
		(placement
			(enabled no)
			(sheetname "")
		)
		(fill
			(thermal_gap 0.5)
			(thermal_bridge_width 0.5)
			(island_removal_mode 0)
		)
		(polygon
			(pts
				(arc
					(start 202.897232 -239.23244)
					(mid 202.893512 -239.24142)
					(end 202.884532 -239.24514)
				)
				(arc
					(start 201.411332 -239.24514)
					(mid 201.402352 -239.24142)
					(end 201.398632 -239.23244)
				)
				(arc
					(start 201.398632 -238.737902)
					(mid 201.402352 -238.728922)
					(end 201.411332 -238.725202)
				)
				(arc
					(start 202.884532 -238.725202)
					(mid 202.893512 -238.728922)
					(end 202.897232 -238.737902)
				)
			)
		)
	)
	(zone
		(layer "In1.Cu")
		(hatch none 0.5)
		(connect_pads
			(clearance 0)
		)
		(min_thickness 0.25)
		(keepout
			(tracks not_allowed)
			(vias allowed)
			(pads allowed)
			(copperpour not_allowed)
			(footprints allowed)
		)
		(placement
			(enabled no)
			(sheetname "")
		)
		(fill
			(thermal_gap 0.5)
			(thermal_bridge_width 0.5)
			(island_removal_mode 0)
		)
		(polygon
			(pts
				(arc
					(start 37.545264 -304.682398)
					(mid 37.541544 -304.691378)
					(end 37.532564 -304.695098)
				)
				(arc
					(start 36.059364 -304.695098)
					(mid 36.050384 -304.691378)
					(end 36.046664 -304.682398)
				)
				(arc
					(start 36.046664 -304.18786)
					(mid 36.050384 -304.17888)
					(end 36.059364 -304.17516)
				)
				(arc
					(start 37.532564 -304.17516)
					(mid 37.541544 -304.17888)
					(end 37.545264 -304.18786)
				)
			)
		)
	)
	(zone
		(layer "In1.Cu")
		(hatch none 0.5)
		(connect_pads
			(clearance 0)
		)
		(min_thickness 0.25)
		(keepout
			(tracks not_allowed)
			(vias allowed)
			(pads allowed)
			(copperpour not_allowed)
			(footprints allowed)
		)
		(placement
			(enabled no)
			(sheetname "")
		)
		(fill
			(thermal_gap 0.5)
			(thermal_bridge_width 0.5)
			(island_removal_mode 0)
		)
		(polygon
			(pts
				(arc
					(start 79.518764 -391.319258)
					(mid 79.645764 -391.446258)
					(end 79.772764 -391.319258)
				)
				(arc
					(start 79.772764 -391.243058)
					(mid 79.645764 -391.116058)
					(end 79.518764 -391.243058)
				)
			)
		)
	)
	(zone
		(layer "In1.Cu")
		(hatch none 0.5)
		(connect_pads
			(clearance 0)
		)
		(min_thickness 0.25)
		(keepout
			(tracks not_allowed)
			(vias allowed)
			(pads allowed)
			(copperpour not_allowed)
			(footprints allowed)
		)
		(placement
			(enabled no)
			(sheetname "")
		)
		(fill
			(thermal_gap 0.5)
			(thermal_bridge_width 0.5)
			(island_removal_mode 0)
		)
		(polygon
			(pts
				(arc
					(start 37.545264 -249.432572)
					(mid 37.541544 -249.441552)
					(end 37.532564 -249.445272)
				)
				(arc
					(start 36.059364 -249.445272)
					(mid 36.050384 -249.441552)
					(end 36.046664 -249.432572)
				)
				(arc
					(start 36.046664 -248.938034)
					(mid 36.050384 -248.929054)
					(end 36.059364 -248.925334)
				)
				(arc
					(start 37.532564 -248.925334)
					(mid 37.541544 -248.929054)
					(end 37.545264 -248.938034)
				)
			)
		)
	)
	(zone
		(layer "In1.Cu")
		(hatch none 0.5)
		(connect_pads
			(clearance 0)
		)
		(min_thickness 0.25)
		(keepout
			(tracks not_allowed)
			(vias allowed)
			(pads allowed)
			(copperpour not_allowed)
			(footprints allowed)
		)
		(placement
			(enabled no)
			(sheetname "")
		)
		(fill
			(thermal_gap 0.5)
			(thermal_bridge_width 0.5)
			(island_removal_mode 0)
		)
		(polygon
			(pts
				(arc
					(start 281.385264 -230.73233)
					(mid 281.381544 -230.74131)
					(end 281.372564 -230.74503)
				)
				(arc
					(start 279.899364 -230.74503)
					(mid 279.890384 -230.74131)
					(end 279.886664 -230.73233)
				)
				(arc
					(start 279.886664 -230.237792)
					(mid 279.890384 -230.228812)
					(end 279.899364 -230.225092)
				)
				(arc
					(start 281.372564 -230.225092)
					(mid 281.381544 -230.228812)
					(end 281.385264 -230.237792)
				)
			)
		)
	)
	(zone
		(layer "In1.Cu")
		(hatch none 0.5)
		(connect_pads
			(clearance 0)
		)
		(min_thickness 0.25)
		(keepout
			(tracks not_allowed)
			(vias allowed)
			(pads allowed)
			(copperpour not_allowed)
			(footprints allowed)
		)
		(placement
			(enabled no)
			(sheetname "")
		)
		(fill
			(thermal_gap 0.5)
			(thermal_bridge_width 0.5)
			(island_removal_mode 0)
		)
		(polygon
			(pts
				(arc
					(start 176.821338 -283.432504)
					(mid 176.817618 -283.441484)
					(end 176.808638 -283.445204)
				)
				(arc
					(start 175.335438 -283.445204)
					(mid 175.326458 -283.441484)
					(end 175.322738 -283.432504)
				)
				(arc
					(start 175.322738 -282.937966)
					(mid 175.326458 -282.928986)
					(end 175.335438 -282.925266)
				)
				(arc
					(start 176.808638 -282.925266)
					(mid 176.817618 -282.928986)
					(end 176.821338 -282.937966)
				)
			)
		)
	)
	(zone
		(layer "In1.Cu")
		(hatch none 0.5)
		(connect_pads
			(clearance 0)
		)
		(min_thickness 0.25)
		(keepout
			(tracks not_allowed)
			(vias allowed)
			(pads allowed)
			(copperpour not_allowed)
			(footprints allowed)
		)
		(placement
			(enabled no)
			(sheetname "")
		)
		(fill
			(thermal_gap 0.5)
			(thermal_bridge_width 0.5)
			(island_removal_mode 0)
		)
		(polygon
			(pts
				(arc
					(start 37.545264 -263.032494)
					(mid 37.541544 -263.041474)
					(end 37.532564 -263.045194)
				)
				(arc
					(start 36.059364 -263.045194)
					(mid 36.050384 -263.041474)
					(end 36.046664 -263.032494)
				)
				(arc
					(start 36.046664 -262.537956)
					(mid 36.050384 -262.528976)
					(end 36.059364 -262.525256)
				)
				(arc
					(start 37.532564 -262.525256)
					(mid 37.541544 -262.528976)
					(end 37.545264 -262.537956)
				)
			)
		)
	)
	(zone
		(layer "In1.Cu")
		(hatch none 0.5)
		(connect_pads
			(clearance 0)
		)
		(min_thickness 0.25)
		(keepout
			(tracks not_allowed)
			(vias allowed)
			(pads allowed)
			(copperpour not_allowed)
			(footprints allowed)
		)
		(placement
			(enabled no)
			(sheetname "")
		)
		(fill
			(thermal_gap 0.5)
			(thermal_bridge_width 0.5)
			(island_removal_mode 0)
		)
		(polygon
			(pts
				(arc
					(start 191.909446 -234.982512)
					(mid 191.905726 -234.991492)
					(end 191.896746 -234.995212)
				)
				(arc
					(start 190.423546 -234.995212)
					(mid 190.414566 -234.991492)
					(end 190.410846 -234.982512)
				)
				(arc
					(start 190.410846 -234.487974)
					(mid 190.414566 -234.478994)
					(end 190.423546 -234.475274)
				)
				(arc
					(start 191.896746 -234.475274)
					(mid 191.905726 -234.478994)
					(end 191.909446 -234.487974)
				)
			)
		)
	)
	(zone
		(layer "In1.Cu")
		(hatch none 0.5)
		(connect_pads
			(clearance 0)
		)
		(min_thickness 0.25)
		(keepout
			(tracks not_allowed)
			(vias allowed)
			(pads allowed)
			(copperpour not_allowed)
			(footprints allowed)
		)
		(placement
			(enabled no)
			(sheetname "")
		)
		(fill
			(thermal_gap 0.5)
			(thermal_bridge_width 0.5)
			(island_removal_mode 0)
		)
		(polygon
			(pts
				(arc
					(start 320.660776 -397.849344)
					(mid 320.279776 -397.849344)
					(end 320.660776 -397.849344)
				)
			)
		)
	)
	(zone
		(layer "In1.Cu")
		(hatch none 0.5)
		(connect_pads
			(clearance 0)
		)
		(min_thickness 0.25)
		(keepout
			(tracks not_allowed)
			(vias allowed)
			(pads allowed)
			(copperpour not_allowed)
			(footprints allowed)
		)
		(placement
			(enabled no)
			(sheetname "")
		)
		(fill
			(thermal_gap 0.5)
			(thermal_bridge_width 0.5)
			(island_removal_mode 0)
		)
		(polygon
			(pts
				(arc
					(start 439.849514 -201.83221)
					(mid 439.845794 -201.84119)
					(end 439.836814 -201.84491)
				)
				(arc
					(start 438.363614 -201.84491)
					(mid 438.354634 -201.84119)
					(end 438.350914 -201.83221)
				)
				(arc
					(start 438.350914 -201.337672)
					(mid 438.354634 -201.328692)
					(end 438.363614 -201.324972)
				)
				(arc
					(start 439.836814 -201.324972)
					(mid 439.845794 -201.328692)
					(end 439.849514 -201.337672)
				)
			)
		)
	)
	(zone
		(layer "In1.Cu")
		(hatch none 0.5)
		(connect_pads
			(clearance 0)
		)
		(min_thickness 0.25)
		(keepout
			(tracks not_allowed)
			(vias allowed)
			(pads allowed)
			(copperpour not_allowed)
			(footprints allowed)
		)
		(placement
			(enabled no)
			(sheetname "")
		)
		(fill
			(thermal_gap 0.5)
			(thermal_bridge_width 0.5)
			(island_removal_mode 0)
		)
		(polygon
			(pts
				(arc
					(start 40.98925 -241.782346)
					(mid 40.98553 -241.791326)
					(end 40.97655 -241.795046)
				)
				(arc
					(start 39.50335 -241.795046)
					(mid 39.49437 -241.791326)
					(end 39.49065 -241.782346)
				)
				(arc
					(start 39.49065 -241.287808)
					(mid 39.49437 -241.278828)
					(end 39.50335 -241.275108)
				)
				(arc
					(start 40.97655 -241.275108)
					(mid 40.98553 -241.278828)
					(end 40.98925 -241.287808)
				)
			)
		)
	)
	(zone
		(layer "In1.Cu")
		(hatch none 0.5)
		(connect_pads
			(clearance 0)
		)
		(min_thickness 0.25)
		(keepout
			(tracks not_allowed)
			(vias allowed)
			(pads allowed)
			(copperpour not_allowed)
			(footprints allowed)
		)
		(placement
			(enabled no)
			(sheetname "")
		)
		(fill
			(thermal_gap 0.5)
			(thermal_bridge_width 0.5)
			(island_removal_mode 0)
		)
		(polygon
			(pts
				(arc
					(start 273.841464 -280.88209)
					(mid 273.837744 -280.89107)
					(end 273.828764 -280.89479)
				)
				(arc
					(start 272.355564 -280.89479)
					(mid 272.346584 -280.89107)
					(end 272.342864 -280.88209)
				)
				(arc
					(start 272.342864 -280.387552)
					(mid 272.346584 -280.378572)
					(end 272.355564 -280.374852)
				)
				(arc
					(start 273.828764 -280.374852)
					(mid 273.837744 -280.378572)
					(end 273.841464 -280.387552)
				)
			)
		)
	)
	(zone
		(layer "In1.Cu")
		(hatch none 0.5)
		(connect_pads
			(clearance 0)
		)
		(min_thickness 0.25)
		(keepout
			(tracks not_allowed)
			(vias allowed)
			(pads allowed)
			(copperpour not_allowed)
			(footprints allowed)
		)
		(placement
			(enabled no)
			(sheetname "")
		)
		(fill
			(thermal_gap 0.5)
			(thermal_bridge_width 0.5)
			(island_removal_mode 0)
		)
		(polygon
			(pts
				(arc
					(start 288.929318 -245.182136)
					(mid 288.925598 -245.191116)
					(end 288.916618 -245.194836)
				)
				(arc
					(start 287.443418 -245.194836)
					(mid 287.434438 -245.191116)
					(end 287.430718 -245.182136)
				)
				(arc
					(start 287.430718 -244.687598)
					(mid 287.434438 -244.678618)
					(end 287.443418 -244.674898)
				)
				(arc
					(start 288.916618 -244.674898)
					(mid 288.925598 -244.678618)
					(end 288.929318 -244.687598)
				)
			)
		)
	)
	(zone
		(layer "In1.Cu")
		(hatch none 0.5)
		(connect_pads
			(clearance 0)
		)
		(min_thickness 0.25)
		(keepout
			(tracks not_allowed)
			(vias allowed)
			(pads allowed)
			(copperpour not_allowed)
			(footprints allowed)
		)
		(placement
			(enabled no)
			(sheetname "")
		)
		(fill
			(thermal_gap 0.5)
			(thermal_bridge_width 0.5)
			(island_removal_mode 0)
		)
		(polygon
			(pts
				(arc
					(start 172.72127 -279.182576)
					(mid 172.71755 -279.191556)
					(end 172.70857 -279.195276)
				)
				(arc
					(start 171.23537 -279.195276)
					(mid 171.22639 -279.191556)
					(end 171.22267 -279.182576)
				)
				(arc
					(start 171.22267 -278.688038)
					(mid 171.22639 -278.679058)
					(end 171.23537 -278.675338)
				)
				(arc
					(start 172.70857 -278.675338)
					(mid 172.71755 -278.679058)
					(end 172.72127 -278.688038)
				)
			)
		)
	)
	(zone
		(layer "In1.Cu")
		(hatch none 0.5)
		(connect_pads
			(clearance 0)
		)
		(min_thickness 0.25)
		(keepout
			(tracks not_allowed)
			(vias allowed)
			(pads allowed)
			(copperpour not_allowed)
			(footprints allowed)
		)
		(placement
			(enabled no)
			(sheetname "")
		)
		(fill
			(thermal_gap 0.5)
			(thermal_bridge_width 0.5)
			(island_removal_mode 0)
		)
		(polygon
			(pts
				(arc
					(start 199.4535 -246.032528)
					(mid 199.44978 -246.041508)
					(end 199.4408 -246.045228)
				)
				(arc
					(start 197.9676 -246.045228)
					(mid 197.95862 -246.041508)
					(end 197.9549 -246.032528)
				)
				(arc
					(start 197.9549 -245.53799)
					(mid 197.95862 -245.52901)
					(end 197.9676 -245.52529)
				)
				(arc
					(start 199.4408 -245.52529)
					(mid 199.44978 -245.52901)
					(end 199.4535 -245.53799)
				)
			)
		)
	)
	(zone
		(layer "In1.Cu")
		(hatch none 0.5)
		(connect_pads
			(clearance 0)
		)
		(min_thickness 0.25)
		(keepout
			(tracks not_allowed)
			(vias allowed)
			(pads allowed)
			(copperpour not_allowed)
			(footprints allowed)
		)
		(placement
			(enabled no)
			(sheetname "")
		)
		(fill
			(thermal_gap 0.5)
			(thermal_bridge_width 0.5)
			(island_removal_mode 0)
		)
		(polygon
			(pts
				(arc
					(start 417.217352 -242.63223)
					(mid 417.213632 -242.64121)
					(end 417.204652 -242.64493)
				)
				(arc
					(start 415.731452 -242.64493)
					(mid 415.722472 -242.64121)
					(end 415.718752 -242.63223)
				)
				(arc
					(start 415.718752 -242.137692)
					(mid 415.722472 -242.128712)
					(end 415.731452 -242.124992)
				)
				(arc
					(start 417.204652 -242.124992)
					(mid 417.213632 -242.128712)
					(end 417.217352 -242.137692)
				)
			)
		)
	)
	(zone
		(layer "In1.Cu")
		(hatch none 0.5)
		(connect_pads
			(clearance 0)
		)
		(min_thickness 0.25)
		(keepout
			(tracks not_allowed)
			(vias allowed)
			(pads allowed)
			(copperpour not_allowed)
			(footprints allowed)
		)
		(placement
			(enabled no)
			(sheetname "")
		)
		(fill
			(thermal_gap 0.5)
			(thermal_bridge_width 0.5)
			(island_removal_mode 0)
		)
		(polygon
			(pts
				(arc
					(start 148.397976 -383.92227)
					(mid 148.093176 -383.92227)
					(end 148.397976 -383.92227)
				)
			)
		)
	)
	(zone
		(layer "In1.Cu")
		(hatch none 0.5)
		(connect_pads
			(clearance 0)
		)
		(min_thickness 0.25)
		(keepout
			(tracks not_allowed)
			(vias allowed)
			(pads allowed)
			(copperpour not_allowed)
			(footprints allowed)
		)
		(placement
			(enabled no)
			(sheetname "")
		)
		(fill
			(thermal_gap 0.5)
			(thermal_bridge_width 0.5)
			(island_removal_mode 0)
		)
		(polygon
			(pts
				(arc
					(start 45.089318 -289.382454)
					(mid 45.085598 -289.391434)
					(end 45.076618 -289.395154)
				)
				(arc
					(start 43.603418 -289.395154)
					(mid 43.594438 -289.391434)
					(end 43.590718 -289.382454)
				)
				(arc
					(start 43.590718 -288.887916)
					(mid 43.594438 -288.878936)
					(end 43.603418 -288.875216)
				)
				(arc
					(start 45.076618 -288.875216)
					(mid 45.085598 -288.878936)
					(end 45.089318 -288.887916)
				)
			)
		)
	)
	(zone
		(layer "In1.Cu")
		(hatch none 0.5)
		(connect_pads
			(clearance 0)
		)
		(min_thickness 0.25)
		(keepout
			(tracks not_allowed)
			(vias allowed)
			(pads allowed)
			(copperpour not_allowed)
			(footprints allowed)
		)
		(placement
			(enabled no)
			(sheetname "")
		)
		(fill
			(thermal_gap 0.5)
			(thermal_bridge_width 0.5)
			(island_removal_mode 0)
		)
		(polygon
			(pts
				(arc
					(start 411.59811 -392.30427)
					(mid 411.29331 -392.30427)
					(end 411.59811 -392.30427)
				)
			)
		)
	)
	(zone
		(layer "In1.Cu")
		(hatch none 0.5)
		(connect_pads
			(clearance 0)
		)
		(min_thickness 0.25)
		(keepout
			(tracks not_allowed)
			(vias allowed)
			(pads allowed)
			(copperpour not_allowed)
			(footprints allowed)
		)
		(placement
			(enabled no)
			(sheetname "")
		)
		(fill
			(thermal_gap 0.5)
			(thermal_bridge_width 0.5)
			(island_removal_mode 0)
		)
		(polygon
			(pts
				(arc
					(start 206.9973 -300.43247)
					(mid 206.99358 -300.44145)
					(end 206.9846 -300.44517)
				)
				(arc
					(start 205.5114 -300.44517)
					(mid 205.50242 -300.44145)
					(end 205.4987 -300.43247)
				)
				(arc
					(start 205.4987 -299.937932)
					(mid 205.50242 -299.928952)
					(end 205.5114 -299.925232)
				)
				(arc
					(start 206.9846 -299.925232)
					(mid 206.99358 -299.928952)
					(end 206.9973 -299.937932)
				)
			)
		)
	)
	(zone
		(layer "In1.Cu")
		(hatch none 0.5)
		(connect_pads
			(clearance 0)
		)
		(min_thickness 0.25)
		(keepout
			(tracks not_allowed)
			(vias allowed)
			(pads allowed)
			(copperpour not_allowed)
			(footprints allowed)
		)
		(placement
			(enabled no)
			(sheetname "")
		)
		(fill
			(thermal_gap 0.5)
			(thermal_bridge_width 0.5)
			(island_removal_mode 0)
		)
		(polygon
			(pts
				(arc
					(start 184.365392 -231.582468)
					(mid 184.361672 -231.591448)
					(end 184.352692 -231.595168)
				)
				(arc
					(start 182.879492 -231.595168)
					(mid 182.870512 -231.591448)
					(end 182.866792 -231.582468)
				)
				(arc
					(start 182.866792 -231.08793)
					(mid 182.870512 -231.07895)
					(end 182.879492 -231.07523)
				)
				(arc
					(start 184.352692 -231.07523)
					(mid 184.361672 -231.07895)
					(end 184.365392 -231.08793)
				)
			)
		)
	)
	(zone
		(layer "In1.Cu")
		(hatch none 0.5)
		(connect_pads
			(clearance 0)
		)
		(min_thickness 0.25)
		(keepout
			(tracks not_allowed)
			(vias allowed)
			(pads allowed)
			(copperpour not_allowed)
			(footprints allowed)
		)
		(placement
			(enabled no)
			(sheetname "")
		)
		(fill
			(thermal_gap 0.5)
			(thermal_bridge_width 0.5)
			(island_removal_mode 0)
		)
		(polygon
			(pts
				(arc
					(start 191.909446 -317.432436)
					(mid 191.905726 -317.441416)
					(end 191.896746 -317.445136)
				)
				(arc
					(start 190.423546 -317.445136)
					(mid 190.414566 -317.441416)
					(end 190.410846 -317.432436)
				)
				(arc
					(start 190.410846 -316.937898)
					(mid 190.414566 -316.928918)
					(end 190.423546 -316.925198)
				)
				(arc
					(start 191.896746 -316.925198)
					(mid 191.905726 -316.928918)
					(end 191.909446 -316.937898)
				)
			)
		)
	)
	(zone
		(layer "In1.Cu")
		(hatch none 0.5)
		(connect_pads
			(clearance 0)
		)
		(min_thickness 0.25)
		(keepout
			(tracks not_allowed)
			(vias allowed)
			(pads allowed)
			(copperpour not_allowed)
			(footprints allowed)
		)
		(placement
			(enabled no)
			(sheetname "")
		)
		(fill
			(thermal_gap 0.5)
			(thermal_bridge_width 0.5)
			(island_removal_mode 0)
		)
		(polygon
			(pts
				(arc
					(start 265.87831 -235.585)
					(mid 265.21791 -235.585)
					(end 265.87831 -235.585)
				)
			)
		)
	)
	(zone
		(layer "In1.Cu")
		(hatch none 0.5)
		(connect_pads
			(clearance 0)
		)
		(min_thickness 0.25)
		(keepout
			(tracks not_allowed)
			(vias allowed)
			(pads allowed)
			(copperpour not_allowed)
			(footprints allowed)
		)
		(placement
			(enabled no)
			(sheetname "")
		)
		(fill
			(thermal_gap 0.5)
			(thermal_bridge_width 0.5)
			(island_removal_mode 0)
		)
		(polygon
			(pts
				(arc
					(start 82.388964 -385.31038)
					(mid 82.007964 -385.31038)
					(end 82.388964 -385.31038)
				)
			)
		)
	)
	(zone
		(layer "In1.Cu")
		(hatch none 0.5)
		(connect_pads
			(clearance 0)
		)
		(min_thickness 0.25)
		(keepout
			(tracks not_allowed)
			(vias allowed)
			(pads allowed)
			(copperpour not_allowed)
			(footprints allowed)
		)
		(placement
			(enabled no)
			(sheetname "")
		)
		(fill
			(thermal_gap 0.5)
			(thermal_bridge_width 0.5)
			(island_removal_mode 0)
		)
		(polygon
			(pts
				(arc
					(start 40.98925 -277.482554)
					(mid 40.98553 -277.491534)
					(end 40.97655 -277.495254)
				)
				(arc
					(start 39.50335 -277.495254)
					(mid 39.49437 -277.491534)
					(end 39.49065 -277.482554)
				)
				(arc
					(start 39.49065 -276.988016)
					(mid 39.49437 -276.979036)
					(end 39.50335 -276.975316)
				)
				(arc
					(start 40.97655 -276.975316)
					(mid 40.98553 -276.979036)
					(end 40.98925 -276.988016)
				)
			)
		)
	)
	(zone
		(layer "In1.Cu")
		(hatch none 0.5)
		(connect_pads
			(clearance 0)
		)
		(min_thickness 0.25)
		(keepout
			(tracks not_allowed)
			(vias allowed)
			(pads allowed)
			(copperpour not_allowed)
			(footprints allowed)
		)
		(placement
			(enabled no)
			(sheetname "")
		)
		(fill
			(thermal_gap 0.5)
			(thermal_bridge_width 0.5)
			(island_removal_mode 0)
		)
		(polygon
			(pts
				(arc
					(start 435.749446 -234.13212)
					(mid 435.745726 -234.1411)
					(end 435.736746 -234.14482)
				)
				(arc
					(start 434.263546 -234.14482)
					(mid 434.254566 -234.1411)
					(end 434.250846 -234.13212)
				)
				(arc
					(start 434.250846 -233.637582)
					(mid 434.254566 -233.628602)
					(end 434.263546 -233.624882)
				)
				(arc
					(start 435.736746 -233.624882)
					(mid 435.745726 -233.628602)
					(end 435.749446 -233.637582)
				)
			)
		)
	)
	(zone
		(layer "In1.Cu")
		(hatch none 0.5)
		(connect_pads
			(clearance 0)
		)
		(min_thickness 0.25)
		(keepout
			(tracks not_allowed)
			(vias allowed)
			(pads allowed)
			(copperpour not_allowed)
			(footprints allowed)
		)
		(placement
			(enabled no)
			(sheetname "")
		)
		(fill
			(thermal_gap 0.5)
			(thermal_bridge_width 0.5)
			(island_removal_mode 0)
		)
		(polygon
			(pts
				(arc
					(start 420.661338 -245.182136)
					(mid 420.657618 -245.191116)
					(end 420.648638 -245.194836)
				)
				(arc
					(start 419.175438 -245.194836)
					(mid 419.166458 -245.191116)
					(end 419.162738 -245.182136)
				)
				(arc
					(start 419.162738 -244.687598)
					(mid 419.166458 -244.678618)
					(end 419.175438 -244.674898)
				)
				(arc
					(start 420.648638 -244.674898)
					(mid 420.657618 -244.678618)
					(end 420.661338 -244.687598)
				)
			)
		)
	)
	(zone
		(layer "In1.Cu")
		(hatch none 0.5)
		(connect_pads
			(clearance 0)
		)
		(min_thickness 0.25)
		(keepout
			(tracks not_allowed)
			(vias allowed)
			(pads allowed)
			(copperpour not_allowed)
			(footprints allowed)
		)
		(placement
			(enabled no)
			(sheetname "")
		)
		(fill
			(thermal_gap 0.5)
			(thermal_bridge_width 0.5)
			(island_removal_mode 0)
		)
		(polygon
			(pts
				(arc
					(start 450.8373 -235.832142)
					(mid 450.83358 -235.841122)
					(end 450.8246 -235.844842)
				)
				(arc
					(start 449.3514 -235.844842)
					(mid 449.34242 -235.841122)
					(end 449.3387 -235.832142)
				)
				(arc
					(start 449.3387 -235.337604)
					(mid 449.34242 -235.328624)
					(end 449.3514 -235.324904)
				)
				(arc
					(start 450.8246 -235.324904)
					(mid 450.83358 -235.328624)
					(end 450.8373 -235.337604)
				)
			)
		)
	)
	(zone
		(layer "In1.Cu")
		(hatch none 0.5)
		(connect_pads
			(clearance 0)
		)
		(min_thickness 0.25)
		(keepout
			(tracks not_allowed)
			(vias allowed)
			(pads allowed)
			(copperpour not_allowed)
			(footprints allowed)
		)
		(placement
			(enabled no)
			(sheetname "")
		)
		(fill
			(thermal_gap 0.5)
			(thermal_bridge_width 0.5)
			(island_removal_mode 0)
		)
		(polygon
			(pts
				(arc
					(start 424.761406 -214.582248)
					(mid 424.757686 -214.591228)
					(end 424.748706 -214.594948)
				)
				(arc
					(start 423.275506 -214.594948)
					(mid 423.266526 -214.591228)
					(end 423.262806 -214.582248)
				)
				(arc
					(start 423.262806 -214.08771)
					(mid 423.266526 -214.07873)
					(end 423.275506 -214.07501)
				)
				(arc
					(start 424.748706 -214.07501)
					(mid 424.757686 -214.07873)
					(end 424.761406 -214.08771)
				)
			)
		)
	)
	(zone
		(layer "In1.Cu")
		(hatch none 0.5)
		(connect_pads
			(clearance 0)
		)
		(min_thickness 0.25)
		(keepout
			(tracks not_allowed)
			(vias allowed)
			(pads allowed)
			(copperpour not_allowed)
			(footprints allowed)
		)
		(placement
			(enabled no)
			(sheetname "")
		)
		(fill
			(thermal_gap 0.5)
			(thermal_bridge_width 0.5)
			(island_removal_mode 0)
		)
		(polygon
			(pts
				(arc
					(start 172.72127 -304.682398)
					(mid 172.71755 -304.691378)
					(end 172.70857 -304.695098)
				)
				(arc
					(start 171.23537 -304.695098)
					(mid 171.22639 -304.691378)
					(end 171.22267 -304.682398)
				)
				(arc
					(start 171.22267 -304.18786)
					(mid 171.22639 -304.17888)
					(end 171.23537 -304.17516)
				)
				(arc
					(start 172.70857 -304.17516)
					(mid 172.71755 -304.17888)
					(end 172.72127 -304.18786)
				)
			)
		)
	)
	(zone
		(layer "In1.Cu")
		(hatch none 0.5)
		(connect_pads
			(clearance 0)
		)
		(min_thickness 0.25)
		(keepout
			(tracks not_allowed)
			(vias allowed)
			(pads allowed)
			(copperpour not_allowed)
			(footprints allowed)
		)
		(placement
			(enabled no)
			(sheetname "")
		)
		(fill
			(thermal_gap 0.5)
			(thermal_bridge_width 0.5)
			(island_removal_mode 0)
		)
		(polygon
			(pts
				(arc
					(start 419.41877 -391.822686)
					(mid 419.54577 -391.949686)
					(end 419.67277 -391.822686)
				)
				(arc
					(start 419.67277 -391.746486)
					(mid 419.54577 -391.619486)
					(end 419.41877 -391.746486)
				)
			)
		)
	)
	(zone
		(layer "In1.Cu")
		(hatch none 0.5)
		(connect_pads
			(clearance 0)
		)
		(min_thickness 0.25)
		(keepout
			(tracks not_allowed)
			(vias allowed)
			(pads allowed)
			(copperpour not_allowed)
			(footprints allowed)
		)
		(placement
			(enabled no)
			(sheetname "")
		)
		(fill
			(thermal_gap 0.5)
			(thermal_bridge_width 0.5)
			(island_removal_mode 0)
		)
		(polygon
			(pts
				(arc
					(start 195.353432 -229.882446)
					(mid 195.349712 -229.891426)
					(end 195.340732 -229.895146)
				)
				(arc
					(start 193.867532 -229.895146)
					(mid 193.858552 -229.891426)
					(end 193.854832 -229.882446)
				)
				(arc
					(start 193.854832 -229.387908)
					(mid 193.858552 -229.378928)
					(end 193.867532 -229.375208)
				)
				(arc
					(start 195.340732 -229.375208)
					(mid 195.349712 -229.378928)
					(end 195.353432 -229.387908)
				)
			)
		)
	)
	(zone
		(layer "In1.Cu")
		(hatch none 0.5)
		(connect_pads
			(clearance 0)
		)
		(min_thickness 0.25)
		(keepout
			(tracks not_allowed)
			(vias allowed)
			(pads allowed)
			(copperpour not_allowed)
			(footprints allowed)
		)
		(placement
			(enabled no)
			(sheetname "")
		)
		(fill
			(thermal_gap 0.5)
			(thermal_bridge_width 0.5)
			(island_removal_mode 0)
		)
		(polygon
			(pts
				(arc
					(start 202.897232 -198.43242)
					(mid 202.893512 -198.4414)
					(end 202.884532 -198.44512)
				)
				(arc
					(start 201.411332 -198.44512)
					(mid 201.402352 -198.4414)
					(end 201.398632 -198.43242)
				)
				(arc
					(start 201.398632 -197.937882)
					(mid 201.402352 -197.928902)
					(end 201.411332 -197.925182)
				)
				(arc
					(start 202.884532 -197.925182)
					(mid 202.893512 -197.928902)
					(end 202.897232 -197.937882)
				)
			)
		)
	)
	(zone
		(layer "In1.Cu")
		(hatch none 0.5)
		(connect_pads
			(clearance 0)
		)
		(min_thickness 0.25)
		(keepout
			(tracks not_allowed)
			(vias allowed)
			(pads allowed)
			(copperpour not_allowed)
			(footprints allowed)
		)
		(placement
			(enabled no)
			(sheetname "")
		)
		(fill
			(thermal_gap 0.5)
			(thermal_bridge_width 0.5)
			(island_removal_mode 0)
		)
		(polygon
			(pts
				(arc
					(start 417.217352 -281.732228)
					(mid 417.213632 -281.741208)
					(end 417.204652 -281.744928)
				)
				(arc
					(start 415.731452 -281.744928)
					(mid 415.722472 -281.741208)
					(end 415.718752 -281.732228)
				)
				(arc
					(start 415.718752 -281.23769)
					(mid 415.722472 -281.22871)
					(end 415.731452 -281.22499)
				)
				(arc
					(start 417.204652 -281.22499)
					(mid 417.213632 -281.22871)
					(end 417.217352 -281.23769)
				)
			)
		)
	)
	(zone
		(layer "In1.Cu")
		(hatch none 0.5)
		(connect_pads
			(clearance 0)
		)
		(min_thickness 0.25)
		(keepout
			(tracks not_allowed)
			(vias allowed)
			(pads allowed)
			(copperpour not_allowed)
			(footprints allowed)
		)
		(placement
			(enabled no)
			(sheetname "")
		)
		(fill
			(thermal_gap 0.5)
			(thermal_bridge_width 0.5)
			(island_removal_mode 0)
		)
		(polygon
			(pts
				(arc
					(start 432.30546 -302.132238)
					(mid 432.30174 -302.141218)
					(end 432.29276 -302.144938)
				)
				(arc
					(start 430.81956 -302.144938)
					(mid 430.81058 -302.141218)
					(end 430.80686 -302.132238)
				)
				(arc
					(start 430.80686 -301.6377)
					(mid 430.81058 -301.62872)
					(end 430.81956 -301.625)
				)
				(arc
					(start 432.29276 -301.625)
					(mid 432.30174 -301.62872)
					(end 432.30546 -301.6377)
				)
			)
		)
	)
	(zone
		(layer "In1.Cu")
		(hatch none 0.5)
		(connect_pads
			(clearance 0)
		)
		(min_thickness 0.25)
		(keepout
			(tracks not_allowed)
			(vias allowed)
			(pads allowed)
			(copperpour not_allowed)
			(footprints allowed)
		)
		(placement
			(enabled no)
			(sheetname "")
		)
		(fill
			(thermal_gap 0.5)
			(thermal_bridge_width 0.5)
			(island_removal_mode 0)
		)
		(polygon
			(pts
				(arc
					(start 439.849514 -287.682178)
					(mid 439.845794 -287.691158)
					(end 439.836814 -287.694878)
				)
				(arc
					(start 438.363614 -287.694878)
					(mid 438.354634 -287.691158)
					(end 438.350914 -287.682178)
				)
				(arc
					(start 438.350914 -287.18764)
					(mid 438.354634 -287.17866)
					(end 438.363614 -287.17494)
				)
				(arc
					(start 439.836814 -287.17494)
					(mid 439.845794 -287.17866)
					(end 439.849514 -287.18764)
				)
			)
		)
	)
	(zone
		(layer "In1.Cu")
		(hatch none 0.5)
		(connect_pads
			(clearance 0)
		)
		(min_thickness 0.25)
		(keepout
			(tracks not_allowed)
			(vias allowed)
			(pads allowed)
			(copperpour not_allowed)
			(footprints allowed)
		)
		(placement
			(enabled no)
			(sheetname "")
		)
		(fill
			(thermal_gap 0.5)
			(thermal_bridge_width 0.5)
			(island_removal_mode 0)
		)
		(polygon
			(pts
				(arc
					(start 344.497914 -399.143474)
					(mid 344.193114 -399.143474)
					(end 344.497914 -399.143474)
				)
			)
		)
	)
	(zone
		(layer "In1.Cu")
		(hatch none 0.5)
		(connect_pads
			(clearance 0)
		)
		(min_thickness 0.25)
		(keepout
			(tracks not_allowed)
			(vias allowed)
			(pads allowed)
			(copperpour not_allowed)
			(footprints allowed)
		)
		(placement
			(enabled no)
			(sheetname "")
		)
		(fill
			(thermal_gap 0.5)
			(thermal_bridge_width 0.5)
			(island_removal_mode 0)
		)
		(polygon
			(pts
				(arc
					(start 48.533304 -245.18239)
					(mid 48.529584 -245.19137)
					(end 48.520604 -245.19509)
				)
				(arc
					(start 47.047404 -245.19509)
					(mid 47.038424 -245.19137)
					(end 47.034704 -245.18239)
				)
				(arc
					(start 47.034704 -244.687852)
					(mid 47.038424 -244.678872)
					(end 47.047404 -244.675152)
				)
				(arc
					(start 48.520604 -244.675152)
					(mid 48.529584 -244.678872)
					(end 48.533304 -244.687852)
				)
			)
		)
	)
	(zone
		(layer "In1.Cu")
		(hatch none 0.5)
		(connect_pads
			(clearance 0)
		)
		(min_thickness 0.25)
		(keepout
			(tracks not_allowed)
			(vias allowed)
			(pads allowed)
			(copperpour not_allowed)
			(footprints allowed)
		)
		(placement
			(enabled no)
			(sheetname "")
		)
		(fill
			(thermal_gap 0.5)
			(thermal_bridge_width 0.5)
			(island_removal_mode 0)
		)
		(polygon
			(pts
				(arc
					(start 191.909446 -268.13256)
					(mid 191.905726 -268.14154)
					(end 191.896746 -268.14526)
				)
				(arc
					(start 190.423546 -268.14526)
					(mid 190.414566 -268.14154)
					(end 190.410846 -268.13256)
				)
				(arc
					(start 190.410846 -267.638022)
					(mid 190.414566 -267.629042)
					(end 190.423546 -267.625322)
				)
				(arc
					(start 191.896746 -267.625322)
					(mid 191.905726 -267.629042)
					(end 191.909446 -267.638022)
				)
			)
		)
	)
	(zone
		(layer "In1.Cu")
		(hatch none 0.5)
		(connect_pads
			(clearance 0)
		)
		(min_thickness 0.25)
		(keepout
			(tracks not_allowed)
			(vias allowed)
			(pads allowed)
			(copperpour not_allowed)
			(footprints allowed)
		)
		(placement
			(enabled no)
			(sheetname "")
		)
		(fill
			(thermal_gap 0.5)
			(thermal_bridge_width 0.5)
			(island_removal_mode 0)
		)
		(polygon
			(pts
				(arc
					(start 296.473372 -265.582146)
					(mid 296.469652 -265.591126)
					(end 296.460672 -265.594846)
				)
				(arc
					(start 294.987472 -265.594846)
					(mid 294.978492 -265.591126)
					(end 294.974772 -265.582146)
				)
				(arc
					(start 294.974772 -265.087608)
					(mid 294.978492 -265.078628)
					(end 294.987472 -265.074908)
				)
				(arc
					(start 296.460672 -265.074908)
					(mid 296.469652 -265.078628)
					(end 296.473372 -265.087608)
				)
			)
		)
	)
	(zone
		(layer "In1.Cu")
		(hatch none 0.5)
		(connect_pads
			(clearance 0)
		)
		(min_thickness 0.25)
		(keepout
			(tracks not_allowed)
			(vias allowed)
			(pads allowed)
			(copperpour not_allowed)
			(footprints allowed)
		)
		(placement
			(enabled no)
			(sheetname "")
		)
		(fill
			(thermal_gap 0.5)
			(thermal_bridge_width 0.5)
			(island_removal_mode 0)
		)
		(polygon
			(pts
				(arc
					(start 288.929318 -218.832176)
					(mid 288.925598 -218.841156)
					(end 288.916618 -218.844876)
				)
				(arc
					(start 287.443418 -218.844876)
					(mid 287.434438 -218.841156)
					(end 287.430718 -218.832176)
				)
				(arc
					(start 287.430718 -218.337638)
					(mid 287.434438 -218.328658)
					(end 287.443418 -218.324938)
				)
				(arc
					(start 288.916618 -218.324938)
					(mid 288.925598 -218.328658)
					(end 288.929318 -218.337638)
				)
			)
		)
	)
	(zone
		(layer "In1.Cu")
		(hatch none 0.5)
		(connect_pads
			(clearance 0)
		)
		(min_thickness 0.25)
		(keepout
			(tracks not_allowed)
			(vias allowed)
			(pads allowed)
			(copperpour not_allowed)
			(footprints allowed)
		)
		(placement
			(enabled no)
			(sheetname "")
		)
		(fill
			(thermal_gap 0.5)
			(thermal_bridge_width 0.5)
			(island_removal_mode 0)
		)
		(polygon
			(pts
				(arc
					(start 308.117494 -199.282304)
					(mid 308.113774 -199.291284)
					(end 308.104794 -199.295004)
				)
				(arc
					(start 306.631594 -199.295004)
					(mid 306.622614 -199.291284)
					(end 306.618894 -199.282304)
				)
				(arc
					(start 306.618894 -198.787766)
					(mid 306.622614 -198.778786)
					(end 306.631594 -198.775066)
				)
				(arc
					(start 308.104794 -198.775066)
					(mid 308.113774 -198.778786)
					(end 308.117494 -198.787766)
				)
			)
		)
	)
	(zone
		(layer "In1.Cu")
		(hatch none 0.5)
		(connect_pads
			(clearance 0)
		)
		(min_thickness 0.25)
		(keepout
			(tracks not_allowed)
			(vias allowed)
			(pads allowed)
			(copperpour not_allowed)
			(footprints allowed)
		)
		(placement
			(enabled no)
			(sheetname "")
		)
		(fill
			(thermal_gap 0.5)
			(thermal_bridge_width 0.5)
			(island_removal_mode 0)
		)
		(polygon
			(pts
				(arc
					(start 184.365392 -236.682534)
					(mid 184.361672 -236.691514)
					(end 184.352692 -236.695234)
				)
				(arc
					(start 182.879492 -236.695234)
					(mid 182.870512 -236.691514)
					(end 182.866792 -236.682534)
				)
				(arc
					(start 182.866792 -236.187996)
					(mid 182.870512 -236.179016)
					(end 182.879492 -236.175296)
				)
				(arc
					(start 184.352692 -236.175296)
					(mid 184.361672 -236.179016)
					(end 184.365392 -236.187996)
				)
			)
		)
	)
	(zone
		(layer "In1.Cu")
		(hatch none 0.5)
		(connect_pads
			(clearance 0)
		)
		(min_thickness 0.25)
		(keepout
			(tracks not_allowed)
			(vias allowed)
			(pads allowed)
			(copperpour not_allowed)
			(footprints allowed)
		)
		(placement
			(enabled no)
			(sheetname "")
		)
		(fill
			(thermal_gap 0.5)
			(thermal_bridge_width 0.5)
			(island_removal_mode 0)
		)
		(polygon
			(pts
				(arc
					(start 432.30546 -247.732296)
					(mid 432.30174 -247.741276)
					(end 432.29276 -247.744996)
				)
				(arc
					(start 430.81956 -247.744996)
					(mid 430.81058 -247.741276)
					(end 430.80686 -247.732296)
				)
				(arc
					(start 430.80686 -247.237758)
					(mid 430.81058 -247.228778)
					(end 430.81956 -247.225058)
				)
				(arc
					(start 432.29276 -247.225058)
					(mid 432.30174 -247.228778)
					(end 432.30546 -247.237758)
				)
			)
		)
	)
	(zone
		(layer "In1.Cu")
		(hatch none 0.5)
		(connect_pads
			(clearance 0)
		)
		(min_thickness 0.25)
		(keepout
			(tracks not_allowed)
			(vias allowed)
			(pads allowed)
			(copperpour not_allowed)
			(footprints allowed)
		)
		(placement
			(enabled no)
			(sheetname "")
		)
		(fill
			(thermal_gap 0.5)
			(thermal_bridge_width 0.5)
			(island_removal_mode 0)
		)
		(polygon
			(pts
				(arc
					(start 419.998144 -392.30427)
					(mid 419.693344 -392.30427)
					(end 419.998144 -392.30427)
				)
			)
		)
	)
	(zone
		(layer "In1.Cu")
		(hatch none 0.5)
		(connect_pads
			(clearance 0)
		)
		(min_thickness 0.25)
		(keepout
			(tracks not_allowed)
			(vias allowed)
			(pads allowed)
			(copperpour not_allowed)
			(footprints allowed)
		)
		(placement
			(enabled no)
			(sheetname "")
		)
		(fill
			(thermal_gap 0.5)
			(thermal_bridge_width 0.5)
			(island_removal_mode 0)
		)
		(polygon
			(pts
				(arc
					(start 54.191154 -383.440686)
					(mid 54.318154 -383.567686)
					(end 54.445154 -383.440686)
				)
				(arc
					(start 54.445154 -383.364486)
					(mid 54.318154 -383.237486)
					(end 54.191154 -383.364486)
				)
			)
		)
	)
	(zone
		(layer "In1.Cu")
		(hatch none 0.5)
		(connect_pads
			(clearance 0)
		)
		(min_thickness 0.25)
		(keepout
			(tracks not_allowed)
			(vias allowed)
			(pads allowed)
			(copperpour not_allowed)
			(footprints allowed)
		)
		(placement
			(enabled no)
			(sheetname "")
		)
		(fill
			(thermal_gap 0.5)
			(thermal_bridge_width 0.5)
			(island_removal_mode 0)
		)
		(polygon
			(pts
				(arc
					(start 125.760988 -389.467344)
					(mid 125.379988 -389.467344)
					(end 125.760988 -389.467344)
				)
			)
		)
	)
	(zone
		(layer "In1.Cu")
		(hatch none 0.5)
		(connect_pads
			(clearance 0)
		)
		(min_thickness 0.25)
		(keepout
			(tracks not_allowed)
			(vias allowed)
			(pads allowed)
			(copperpour not_allowed)
			(footprints allowed)
		)
		(placement
			(enabled no)
			(sheetname "")
		)
		(fill
			(thermal_gap 0.5)
			(thermal_bridge_width 0.5)
			(island_removal_mode 0)
		)
		(polygon
			(pts
				(arc
					(start 191.909446 -201.832464)
					(mid 191.905726 -201.841444)
					(end 191.896746 -201.845164)
				)
				(arc
					(start 190.423546 -201.845164)
					(mid 190.414566 -201.841444)
					(end 190.410846 -201.832464)
				)
				(arc
					(start 190.410846 -201.337926)
					(mid 190.414566 -201.328946)
					(end 190.423546 -201.325226)
				)
				(arc
					(start 191.896746 -201.325226)
					(mid 191.905726 -201.328946)
					(end 191.909446 -201.337926)
				)
			)
		)
	)
	(zone
		(layer "In1.Cu")
		(hatch none 0.5)
		(connect_pads
			(clearance 0)
		)
		(min_thickness 0.25)
		(keepout
			(tracks not_allowed)
			(vias allowed)
			(pads allowed)
			(copperpour not_allowed)
			(footprints allowed)
		)
		(placement
			(enabled no)
			(sheetname "")
		)
		(fill
			(thermal_gap 0.5)
			(thermal_bridge_width 0.5)
			(island_removal_mode 0)
		)
		(polygon
			(pts
				(arc
					(start 405.488902 -393.69238)
					(mid 405.107902 -393.69238)
					(end 405.488902 -393.69238)
				)
			)
		)
	)
	(zone
		(layer "In1.Cu")
		(hatch none 0.5)
		(connect_pads
			(clearance 0)
		)
		(min_thickness 0.25)
		(keepout
			(tracks not_allowed)
			(vias allowed)
			(pads allowed)
			(copperpour not_allowed)
			(footprints allowed)
		)
		(placement
			(enabled no)
			(sheetname "")
		)
		(fill
			(thermal_gap 0.5)
			(thermal_bridge_width 0.5)
			(island_removal_mode 0)
		)
		(polygon
			(pts
				(arc
					(start 64.661034 -386.003292)
					(mid 64.280034 -386.003292)
					(end 64.661034 -386.003292)
				)
			)
		)
	)
	(zone
		(layer "In1.Cu")
		(hatch none 0.5)
		(connect_pads
			(clearance 0)
		)
		(min_thickness 0.25)
		(keepout
			(tracks not_allowed)
			(vias allowed)
			(pads allowed)
			(copperpour not_allowed)
			(footprints allowed)
		)
		(placement
			(enabled no)
			(sheetname "")
		)
		(fill
			(thermal_gap 0.5)
			(thermal_bridge_width 0.5)
			(island_removal_mode 0)
		)
		(polygon
			(pts
				(arc
					(start 56.077358 -209.482436)
					(mid 56.073638 -209.491416)
					(end 56.064658 -209.495136)
				)
				(arc
					(start 54.591458 -209.495136)
					(mid 54.582478 -209.491416)
					(end 54.578758 -209.482436)
				)
				(arc
					(start 54.578758 -208.987898)
					(mid 54.582478 -208.978918)
					(end 54.591458 -208.975198)
				)
				(arc
					(start 56.064658 -208.975198)
					(mid 56.073638 -208.978918)
					(end 56.077358 -208.987898)
				)
			)
		)
	)
	(zone
		(layer "In1.Cu")
		(hatch none 0.5)
		(connect_pads
			(clearance 0)
		)
		(min_thickness 0.25)
		(keepout
			(tracks not_allowed)
			(vias allowed)
			(pads allowed)
			(copperpour not_allowed)
			(footprints allowed)
		)
		(placement
			(enabled no)
			(sheetname "")
		)
		(fill
			(thermal_gap 0.5)
			(thermal_bridge_width 0.5)
			(island_removal_mode 0)
		)
		(polygon
			(pts
				(arc
					(start 206.5782 -203.285344)
					(mid 205.9178 -203.285344)
					(end 206.5782 -203.285344)
				)
			)
		)
	)
	(zone
		(layer "In1.Cu")
		(hatch none 0.5)
		(connect_pads
			(clearance 0)
		)
		(min_thickness 0.25)
		(keepout
			(tracks not_allowed)
			(vias allowed)
			(pads allowed)
			(copperpour not_allowed)
			(footprints allowed)
		)
		(placement
			(enabled no)
			(sheetname "")
		)
		(fill
			(thermal_gap 0.5)
			(thermal_bridge_width 0.5)
			(island_removal_mode 0)
		)
		(polygon
			(pts
				(arc
					(start 17.823434 -105.41381)
					(mid 17.841395 -105.406371)
					(end 17.848834 -105.38841)
				)
				(arc
					(start 17.848834 -105.173272)
					(mid 17.856273 -105.155311)
					(end 17.874234 -105.147872)
				)
				(arc
					(start 17.883378 -105.147872)
					(mid 17.901339 -105.140433)
					(end 17.908778 -105.122472)
				)
				(arc
					(start 17.908778 -105.007664)
					(mid 17.879569 -104.937782)
					(end 17.809464 -104.909112)
				)
				(arc
					(start 17.50822 -104.909112)
					(mid 17.438115 -104.937782)
					(end 17.408906 -105.007664)
				)
				(arc
					(start 17.408906 -105.122472)
					(mid 17.416345 -105.140433)
					(end 17.434306 -105.147872)
				)
				(arc
					(start 17.44345 -105.147872)
					(mid 17.461411 -105.155311)
					(end 17.46885 -105.173272)
				)
				(arc
					(start 17.46885 -105.38841)
					(mid 17.476289 -105.406371)
					(end 17.49425 -105.41381)
				)
			)
		)
	)
	(zone
		(layer "In1.Cu")
		(hatch none 0.5)
		(connect_pads
			(clearance 0)
		)
		(min_thickness 0.25)
		(keepout
			(tracks not_allowed)
			(vias allowed)
			(pads allowed)
			(copperpour not_allowed)
			(footprints allowed)
		)
		(placement
			(enabled no)
			(sheetname "")
		)
		(fill
			(thermal_gap 0.5)
			(thermal_bridge_width 0.5)
			(island_removal_mode 0)
		)
		(polygon
			(pts
				(arc
					(start 348.097856 -392.30427)
					(mid 347.793056 -392.30427)
					(end 348.097856 -392.30427)
				)
			)
		)
	)
	(zone
		(layer "In1.Cu")
		(hatch none 0.5)
		(connect_pads
			(clearance 0)
		)
		(min_thickness 0.25)
		(keepout
			(tracks not_allowed)
			(vias allowed)
			(pads allowed)
			(copperpour not_allowed)
			(footprints allowed)
		)
		(placement
			(enabled no)
			(sheetname "")
		)
		(fill
			(thermal_gap 0.5)
			(thermal_bridge_width 0.5)
			(island_removal_mode 0)
		)
		(polygon
			(pts
				(arc
					(start 191.909446 -249.432572)
					(mid 191.905726 -249.441552)
					(end 191.896746 -249.445272)
				)
				(arc
					(start 190.423546 -249.445272)
					(mid 190.414566 -249.441552)
					(end 190.410846 -249.432572)
				)
				(arc
					(start 190.410846 -248.938034)
					(mid 190.414566 -248.929054)
					(end 190.423546 -248.925334)
				)
				(arc
					(start 191.896746 -248.925334)
					(mid 191.905726 -248.929054)
					(end 191.909446 -248.938034)
				)
			)
		)
	)
	(zone
		(layer "In1.Cu")
		(hatch none 0.5)
		(connect_pads
			(clearance 0)
		)
		(min_thickness 0.25)
		(keepout
			(tracks not_allowed)
			(vias allowed)
			(pads allowed)
			(copperpour not_allowed)
			(footprints allowed)
		)
		(placement
			(enabled no)
			(sheetname "")
		)
		(fill
			(thermal_gap 0.5)
			(thermal_bridge_width 0.5)
			(island_removal_mode 0)
		)
		(polygon
			(pts
				(arc
					(start 172.72127 -314.032392)
					(mid 172.71755 -314.041372)
					(end 172.70857 -314.045092)
				)
				(arc
					(start 171.23537 -314.045092)
					(mid 171.22639 -314.041372)
					(end 171.22267 -314.032392)
				)
				(arc
					(start 171.22267 -313.537854)
					(mid 171.22639 -313.528874)
					(end 171.23537 -313.525154)
				)
				(arc
					(start 172.70857 -313.525154)
					(mid 172.71755 -313.528874)
					(end 172.72127 -313.537854)
				)
			)
		)
	)
	(zone
		(layer "In1.Cu")
		(hatch none 0.5)
		(connect_pads
			(clearance 0)
		)
		(min_thickness 0.25)
		(keepout
			(tracks not_allowed)
			(vias allowed)
			(pads allowed)
			(copperpour not_allowed)
			(footprints allowed)
		)
		(placement
			(enabled no)
			(sheetname "")
		)
		(fill
			(thermal_gap 0.5)
			(thermal_bridge_width 0.5)
			(island_removal_mode 0)
		)
		(polygon
			(pts
				(arc
					(start 172.72127 -251.982478)
					(mid 172.71755 -251.991458)
					(end 172.70857 -251.995178)
				)
				(arc
					(start 171.23537 -251.995178)
					(mid 171.22639 -251.991458)
					(end 171.22267 -251.982478)
				)
				(arc
					(start 171.22267 -251.48794)
					(mid 171.22639 -251.47896)
					(end 171.23537 -251.47524)
				)
				(arc
					(start 172.70857 -251.47524)
					(mid 172.71755 -251.47896)
					(end 172.72127 -251.48794)
				)
			)
		)
	)
	(zone
		(layer "In1.Cu")
		(hatch none 0.5)
		(connect_pads
			(clearance 0)
		)
		(min_thickness 0.25)
		(keepout
			(tracks not_allowed)
			(vias allowed)
			(pads allowed)
			(copperpour not_allowed)
			(footprints allowed)
		)
		(placement
			(enabled no)
			(sheetname "")
		)
		(fill
			(thermal_gap 0.5)
			(thermal_bridge_width 0.5)
			(island_removal_mode 0)
		)
		(polygon
			(pts
				(arc
					(start 277.941532 -210.33232)
					(mid 277.937812 -210.3413)
					(end 277.928832 -210.34502)
				)
				(arc
					(start 276.455632 -210.34502)
					(mid 276.446652 -210.3413)
					(end 276.442932 -210.33232)
				)
				(arc
					(start 276.442932 -209.837782)
					(mid 276.446652 -209.828802)
					(end 276.455632 -209.825082)
				)
				(arc
					(start 277.928832 -209.825082)
					(mid 277.937812 -209.828802)
					(end 277.941532 -209.837782)
				)
			)
		)
	)
	(zone
		(layer "In1.Cu")
		(hatch none 0.5)
		(connect_pads
			(clearance 0)
		)
		(min_thickness 0.25)
		(keepout
			(tracks not_allowed)
			(vias allowed)
			(pads allowed)
			(copperpour not_allowed)
			(footprints allowed)
		)
		(placement
			(enabled no)
			(sheetname "")
		)
		(fill
			(thermal_gap 0.5)
			(thermal_bridge_width 0.5)
			(island_removal_mode 0)
		)
		(polygon
			(pts
				(arc
					(start 42.362628 -7.672324)
					(mid 42.384946 -7.618442)
					(end 42.438828 -7.596124)
				)
				(arc
					(start 43.475402 -7.596124)
					(mid 43.529284 -7.618442)
					(end 43.551602 -7.672324)
				)
				(arc
					(start 43.551602 -9.071864)
					(mid 43.529284 -9.125746)
					(end 43.475402 -9.148064)
				)
				(arc
					(start 42.438828 -9.148064)
					(mid 42.384946 -9.125746)
					(end 42.362628 -9.071864)
				)
			)
		)
	)
	(zone
		(layer "In1.Cu")
		(hatch none 0.5)
		(connect_pads
			(clearance 0)
		)
		(min_thickness 0.25)
		(keepout
			(tracks not_allowed)
			(vias allowed)
			(pads allowed)
			(copperpour not_allowed)
			(footprints allowed)
		)
		(placement
			(enabled no)
			(sheetname "")
		)
		(fill
			(thermal_gap 0.5)
			(thermal_bridge_width 0.5)
			(island_removal_mode 0)
		)
		(polygon
			(pts
				(arc
					(start 285.485332 -308.082188)
					(mid 285.481612 -308.091168)
					(end 285.472632 -308.094888)
				)
				(arc
					(start 283.999432 -308.094888)
					(mid 283.990452 -308.091168)
					(end 283.986732 -308.082188)
				)
				(arc
					(start 283.986732 -307.58765)
					(mid 283.990452 -307.57867)
					(end 283.999432 -307.57495)
				)
				(arc
					(start 285.472632 -307.57495)
					(mid 285.481612 -307.57867)
					(end 285.485332 -307.58765)
				)
			)
		)
	)
	(zone
		(layer "In1.Cu")
		(hatch none 0.5)
		(connect_pads
			(clearance 0)
		)
		(min_thickness 0.25)
		(keepout
			(tracks not_allowed)
			(vias allowed)
			(pads allowed)
			(copperpour not_allowed)
			(footprints allowed)
		)
		(placement
			(enabled no)
			(sheetname "")
		)
		(fill
			(thermal_gap 0.5)
			(thermal_bridge_width 0.5)
			(island_removal_mode 0)
		)
		(polygon
			(pts
				(arc
					(start 45.089318 -220.532452)
					(mid 45.085598 -220.541432)
					(end 45.076618 -220.545152)
				)
				(arc
					(start 43.603418 -220.545152)
					(mid 43.594438 -220.541432)
					(end 43.590718 -220.532452)
				)
				(arc
					(start 43.590718 -220.037914)
					(mid 43.594438 -220.028934)
					(end 43.603418 -220.025214)
				)
				(arc
					(start 45.076618 -220.025214)
					(mid 45.085598 -220.028934)
					(end 45.089318 -220.037914)
				)
			)
		)
	)
	(zone
		(layer "In1.Cu")
		(hatch none 0.5)
		(connect_pads
			(clearance 0)
		)
		(min_thickness 0.25)
		(keepout
			(tracks not_allowed)
			(vias allowed)
			(pads allowed)
			(copperpour not_allowed)
			(footprints allowed)
		)
		(placement
			(enabled no)
			(sheetname "")
		)
		(fill
			(thermal_gap 0.5)
			(thermal_bridge_width 0.5)
			(island_removal_mode 0)
		)
		(polygon
			(pts
				(arc
					(start 59.4614 -385.31038)
					(mid 59.0804 -385.31038)
					(end 59.4614 -385.31038)
				)
			)
		)
	)
	(zone
		(layer "In1.Cu")
		(hatch none 0.5)
		(connect_pads
			(clearance 0)
		)
		(min_thickness 0.25)
		(keepout
			(tracks not_allowed)
			(vias allowed)
			(pads allowed)
			(copperpour not_allowed)
			(footprints allowed)
		)
		(placement
			(enabled no)
			(sheetname "")
		)
		(fill
			(thermal_gap 0.5)
			(thermal_bridge_width 0.5)
			(island_removal_mode 0)
		)
		(polygon
			(pts
				(arc
					(start 432.30546 -270.682212)
					(mid 432.30174 -270.691192)
					(end 432.29276 -270.694912)
				)
				(arc
					(start 430.81956 -270.694912)
					(mid 430.81058 -270.691192)
					(end 430.80686 -270.682212)
				)
				(arc
					(start 430.80686 -270.187674)
					(mid 430.81058 -270.178694)
					(end 430.81956 -270.174974)
				)
				(arc
					(start 432.29276 -270.174974)
					(mid 432.30174 -270.178694)
					(end 432.30546 -270.187674)
				)
			)
		)
	)
	(zone
		(layer "In1.Cu")
		(hatch none 0.5)
		(connect_pads
			(clearance 0)
		)
		(min_thickness 0.25)
		(keepout
			(tracks not_allowed)
			(vias allowed)
			(pads allowed)
			(copperpour not_allowed)
			(footprints allowed)
		)
		(placement
			(enabled no)
			(sheetname "")
		)
		(fill
			(thermal_gap 0.5)
			(thermal_bridge_width 0.5)
			(island_removal_mode 0)
		)
		(polygon
			(pts
				(arc
					(start 383.870454 -392.30427)
					(mid 383.565654 -392.30427)
					(end 383.870454 -392.30427)
				)
			)
		)
	)
	(zone
		(layer "In1.Cu")
		(hatch none 0.5)
		(connect_pads
			(clearance 0)
		)
		(min_thickness 0.25)
		(keepout
			(tracks not_allowed)
			(vias allowed)
			(pads allowed)
			(copperpour not_allowed)
			(footprints allowed)
		)
		(placement
			(enabled no)
			(sheetname "")
		)
		(fill
			(thermal_gap 0.5)
			(thermal_bridge_width 0.5)
			(island_removal_mode 0)
		)
		(polygon
			(pts
				(arc
					(start 285.485332 -274.082256)
					(mid 285.481612 -274.091236)
					(end 285.472632 -274.094956)
				)
				(arc
					(start 283.999432 -274.094956)
					(mid 283.990452 -274.091236)
					(end 283.986732 -274.082256)
				)
				(arc
					(start 283.986732 -273.587718)
					(mid 283.990452 -273.578738)
					(end 283.999432 -273.575018)
				)
				(arc
					(start 285.472632 -273.575018)
					(mid 285.481612 -273.578738)
					(end 285.485332 -273.587718)
				)
			)
		)
	)
	(zone
		(layer "In1.Cu")
		(hatch none 0.5)
		(connect_pads
			(clearance 0)
		)
		(min_thickness 0.25)
		(keepout
			(tracks not_allowed)
			(vias allowed)
			(pads allowed)
			(copperpour not_allowed)
			(footprints allowed)
		)
		(placement
			(enabled no)
			(sheetname "")
		)
		(fill
			(thermal_gap 0.5)
			(thermal_bridge_width 0.5)
			(island_removal_mode 0)
		)
		(polygon
			(pts
				(arc
					(start 187.809378 -312.33237)
					(mid 187.805658 -312.34135)
					(end 187.796678 -312.34507)
				)
				(arc
					(start 186.323478 -312.34507)
					(mid 186.314498 -312.34135)
					(end 186.310778 -312.33237)
				)
				(arc
					(start 186.310778 -311.837832)
					(mid 186.314498 -311.828852)
					(end 186.323478 -311.825132)
				)
				(arc
					(start 187.796678 -311.825132)
					(mid 187.805658 -311.828852)
					(end 187.809378 -311.837832)
				)
			)
		)
	)
	(zone
		(layer "In1.Cu")
		(hatch none 0.5)
		(connect_pads
			(clearance 0)
		)
		(min_thickness 0.25)
		(keepout
			(tracks not_allowed)
			(vias allowed)
			(pads allowed)
			(copperpour not_allowed)
			(footprints allowed)
		)
		(placement
			(enabled no)
			(sheetname "")
		)
		(fill
			(thermal_gap 0.5)
			(thermal_bridge_width 0.5)
			(island_removal_mode 0)
		)
		(polygon
			(pts
				(arc
					(start 383.870454 -399.143474)
					(mid 383.565654 -399.143474)
					(end 383.870454 -399.143474)
				)
			)
		)
	)
	(zone
		(layer "In1.Cu")
		(hatch none 0.5)
		(connect_pads
			(clearance 0)
		)
		(min_thickness 0.25)
		(keepout
			(tracks not_allowed)
			(vias allowed)
			(pads allowed)
			(copperpour not_allowed)
			(footprints allowed)
		)
		(placement
			(enabled no)
			(sheetname "")
		)
		(fill
			(thermal_gap 0.5)
			(thermal_bridge_width 0.5)
			(island_removal_mode 0)
		)
		(polygon
			(pts
				(arc
					(start 420.661338 -314.882276)
					(mid 420.657618 -314.891256)
					(end 420.648638 -314.894976)
				)
				(arc
					(start 419.175438 -314.894976)
					(mid 419.166458 -314.891256)
					(end 419.162738 -314.882276)
				)
				(arc
					(start 419.162738 -314.387738)
					(mid 419.166458 -314.378758)
					(end 419.175438 -314.375038)
				)
				(arc
					(start 420.648638 -314.375038)
					(mid 420.657618 -314.378758)
					(end 420.661338 -314.387738)
				)
			)
		)
	)
	(zone
		(layer "In1.Cu")
		(hatch none 0.5)
		(connect_pads
			(clearance 0)
		)
		(min_thickness 0.25)
		(keepout
			(tracks not_allowed)
			(vias allowed)
			(pads allowed)
			(copperpour not_allowed)
			(footprints allowed)
		)
		(placement
			(enabled no)
			(sheetname "")
		)
		(fill
			(thermal_gap 0.5)
			(thermal_bridge_width 0.5)
			(island_removal_mode 0)
		)
		(polygon
			(pts
				(arc
					(start 206.9973 -268.13256)
					(mid 206.99358 -268.14154)
					(end 206.9846 -268.14526)
				)
				(arc
					(start 205.5114 -268.14526)
					(mid 205.50242 -268.14154)
					(end 205.4987 -268.13256)
				)
				(arc
					(start 205.4987 -267.638022)
					(mid 205.50242 -267.629042)
					(end 205.5114 -267.625322)
				)
				(arc
					(start 206.9846 -267.625322)
					(mid 206.99358 -267.629042)
					(end 206.9973 -267.638022)
				)
			)
		)
	)
	(zone
		(layer "In1.Cu")
		(hatch none 0.5)
		(connect_pads
			(clearance 0)
		)
		(min_thickness 0.25)
		(keepout
			(tracks not_allowed)
			(vias allowed)
			(pads allowed)
			(copperpour not_allowed)
			(footprints allowed)
		)
		(placement
			(enabled no)
			(sheetname "")
		)
		(fill
			(thermal_gap 0.5)
			(thermal_bridge_width 0.5)
			(island_removal_mode 0)
		)
		(polygon
			(pts
				(arc
					(start 91.188794 -386.003292)
					(mid 90.807794 -386.003292)
					(end 91.188794 -386.003292)
				)
			)
		)
	)
	(zone
		(layer "In1.Cu")
		(hatch none 0.5)
		(connect_pads
			(clearance 0)
		)
		(min_thickness 0.25)
		(keepout
			(tracks not_allowed)
			(vias allowed)
			(pads allowed)
			(copperpour not_allowed)
			(footprints allowed)
		)
		(placement
			(enabled no)
			(sheetname "")
		)
		(fill
			(thermal_gap 0.5)
			(thermal_bridge_width 0.5)
			(island_removal_mode 0)
		)
		(polygon
			(pts
				(arc
					(start 273.841464 -228.18217)
					(mid 273.837744 -228.19115)
					(end 273.828764 -228.19487)
				)
				(arc
					(start 272.355564 -228.19487)
					(mid 272.346584 -228.19115)
					(end 272.342864 -228.18217)
				)
				(arc
					(start 272.342864 -227.687632)
					(mid 272.346584 -227.678652)
					(end 272.355564 -227.674932)
				)
				(arc
					(start 273.828764 -227.674932)
					(mid 273.837744 -227.678652)
					(end 273.841464 -227.687632)
				)
			)
		)
	)
	(zone
		(layer "In1.Cu")
		(hatch none 0.5)
		(connect_pads
			(clearance 0)
		)
		(min_thickness 0.25)
		(keepout
			(tracks not_allowed)
			(vias allowed)
			(pads allowed)
			(copperpour not_allowed)
			(footprints allowed)
		)
		(placement
			(enabled no)
			(sheetname "")
		)
		(fill
			(thermal_gap 0.5)
			(thermal_bridge_width 0.5)
			(island_removal_mode 0)
		)
		(polygon
			(pts
				(arc
					(start 187.809378 -314.032392)
					(mid 187.805658 -314.041372)
					(end 187.796678 -314.045092)
				)
				(arc
					(start 186.323478 -314.045092)
					(mid 186.314498 -314.041372)
					(end 186.310778 -314.032392)
				)
				(arc
					(start 186.310778 -313.537854)
					(mid 186.314498 -313.528874)
					(end 186.323478 -313.525154)
				)
				(arc
					(start 187.796678 -313.525154)
					(mid 187.805658 -313.528874)
					(end 187.809378 -313.537854)
				)
			)
		)
	)
	(zone
		(layer "In1.Cu")
		(hatch none 0.5)
		(connect_pads
			(clearance 0)
		)
		(min_thickness 0.25)
		(keepout
			(tracks not_allowed)
			(vias allowed)
			(pads allowed)
			(copperpour not_allowed)
			(footprints allowed)
		)
		(placement
			(enabled no)
			(sheetname "")
		)
		(fill
			(thermal_gap 0.5)
			(thermal_bridge_width 0.5)
			(island_removal_mode 0)
		)
		(polygon
			(pts
				(arc
					(start 52.633372 -300.43247)
					(mid 52.629652 -300.44145)
					(end 52.620672 -300.44517)
				)
				(arc
					(start 51.147472 -300.44517)
					(mid 51.138492 -300.44145)
					(end 51.134772 -300.43247)
				)
				(arc
					(start 51.134772 -299.937932)
					(mid 51.138492 -299.928952)
					(end 51.147472 -299.925232)
				)
				(arc
					(start 52.620672 -299.925232)
					(mid 52.629652 -299.928952)
					(end 52.633372 -299.937932)
				)
			)
		)
	)
	(zone
		(layer "In1.Cu")
		(hatch none 0.5)
		(connect_pads
			(clearance 0)
		)
		(min_thickness 0.25)
		(keepout
			(tracks not_allowed)
			(vias allowed)
			(pads allowed)
			(copperpour not_allowed)
			(footprints allowed)
		)
		(placement
			(enabled no)
			(sheetname "")
		)
		(fill
			(thermal_gap 0.5)
			(thermal_bridge_width 0.5)
			(island_removal_mode 0)
		)
		(polygon
			(pts
				(arc
					(start 187.809378 -263.882378)
					(mid 187.805658 -263.891358)
					(end 187.796678 -263.895078)
				)
				(arc
					(start 186.323478 -263.895078)
					(mid 186.314498 -263.891358)
					(end 186.310778 -263.882378)
				)
				(arc
					(start 186.310778 -263.38784)
					(mid 186.314498 -263.37886)
					(end 186.323478 -263.37514)
				)
				(arc
					(start 187.796678 -263.37514)
					(mid 187.805658 -263.37886)
					(end 187.809378 -263.38784)
				)
			)
		)
	)
	(zone
		(layer "In1.Cu")
		(hatch none 0.5)
		(connect_pads
			(clearance 0)
		)
		(min_thickness 0.25)
		(keepout
			(tracks not_allowed)
			(vias allowed)
			(pads allowed)
			(copperpour not_allowed)
			(footprints allowed)
		)
		(placement
			(enabled no)
			(sheetname "")
		)
		(fill
			(thermal_gap 0.5)
			(thermal_bridge_width 0.5)
			(island_removal_mode 0)
		)
		(polygon
			(pts
				(arc
					(start 48.533304 -279.182576)
					(mid 48.529584 -279.191556)
					(end 48.520604 -279.195276)
				)
				(arc
					(start 47.047404 -279.195276)
					(mid 47.038424 -279.191556)
					(end 47.034704 -279.182576)
				)
				(arc
					(start 47.034704 -278.688038)
					(mid 47.038424 -278.679058)
					(end 47.047404 -278.675338)
				)
				(arc
					(start 48.520604 -278.675338)
					(mid 48.529584 -278.679058)
					(end 48.533304 -278.688038)
				)
			)
		)
	)
	(zone
		(layer "In1.Cu")
		(hatch none 0.5)
		(connect_pads
			(clearance 0)
		)
		(min_thickness 0.25)
		(keepout
			(tracks not_allowed)
			(vias allowed)
			(pads allowed)
			(copperpour not_allowed)
			(footprints allowed)
		)
		(placement
			(enabled no)
			(sheetname "")
		)
		(fill
			(thermal_gap 0.5)
			(thermal_bridge_width 0.5)
			(island_removal_mode 0)
		)
		(polygon
			(pts
				(arc
					(start 454.937368 -272.382234)
					(mid 454.933648 -272.391214)
					(end 454.924668 -272.394934)
				)
				(arc
					(start 453.451468 -272.394934)
					(mid 453.442488 -272.391214)
					(end 453.438768 -272.382234)
				)
				(arc
					(start 453.438768 -271.887696)
					(mid 453.442488 -271.878716)
					(end 453.451468 -271.874996)
				)
				(arc
					(start 454.924668 -271.874996)
					(mid 454.933648 -271.878716)
					(end 454.937368 -271.887696)
				)
			)
		)
	)
	(zone
		(layer "In1.Cu")
		(hatch none 0.5)
		(connect_pads
			(clearance 0)
		)
		(min_thickness 0.25)
		(keepout
			(tracks not_allowed)
			(vias allowed)
			(pads allowed)
			(copperpour not_allowed)
			(footprints allowed)
		)
		(placement
			(enabled no)
			(sheetname "")
		)
		(fill
			(thermal_gap 0.5)
			(thermal_bridge_width 0.5)
			(island_removal_mode 0)
		)
		(polygon
			(pts
				(arc
					(start 424.761406 -246.032274)
					(mid 424.757686 -246.041254)
					(end 424.748706 -246.044974)
				)
				(arc
					(start 423.275506 -246.044974)
					(mid 423.266526 -246.041254)
					(end 423.262806 -246.032274)
				)
				(arc
					(start 423.262806 -245.537736)
					(mid 423.266526 -245.528756)
					(end 423.275506 -245.525036)
				)
				(arc
					(start 424.748706 -245.525036)
					(mid 424.757686 -245.528756)
					(end 424.761406 -245.537736)
				)
			)
		)
	)
	(zone
		(layer "In1.Cu")
		(hatch none 0.5)
		(connect_pads
			(clearance 0)
		)
		(min_thickness 0.25)
		(keepout
			(tracks not_allowed)
			(vias allowed)
			(pads allowed)
			(copperpour not_allowed)
			(footprints allowed)
		)
		(placement
			(enabled no)
			(sheetname "")
		)
		(fill
			(thermal_gap 0.5)
			(thermal_bridge_width 0.5)
			(island_removal_mode 0)
		)
		(polygon
			(pts
				(arc
					(start 156.689044 -388.774432)
					(mid 156.308044 -388.774432)
					(end 156.689044 -388.774432)
				)
			)
		)
	)
	(zone
		(layer "In1.Cu")
		(hatch none 0.5)
		(connect_pads
			(clearance 0)
		)
		(min_thickness 0.25)
		(keepout
			(tracks not_allowed)
			(vias allowed)
			(pads allowed)
			(copperpour not_allowed)
			(footprints allowed)
		)
		(placement
			(enabled no)
			(sheetname "")
		)
		(fill
			(thermal_gap 0.5)
			(thermal_bridge_width 0.5)
			(island_removal_mode 0)
		)
		(polygon
			(pts
				(arc
					(start 417.217352 -263.03224)
					(mid 417.213632 -263.04122)
					(end 417.204652 -263.04494)
				)
				(arc
					(start 415.731452 -263.04494)
					(mid 415.722472 -263.04122)
					(end 415.718752 -263.03224)
				)
				(arc
					(start 415.718752 -262.537702)
					(mid 415.722472 -262.528722)
					(end 415.731452 -262.525002)
				)
				(arc
					(start 417.204652 -262.525002)
					(mid 417.213632 -262.528722)
					(end 417.217352 -262.537702)
				)
			)
		)
	)
	(zone
		(layer "In1.Cu")
		(hatch none 0.5)
		(connect_pads
			(clearance 0)
		)
		(min_thickness 0.25)
		(keepout
			(tracks not_allowed)
			(vias allowed)
			(pads allowed)
			(copperpour not_allowed)
			(footprints allowed)
		)
		(placement
			(enabled no)
			(sheetname "")
		)
		(fill
			(thermal_gap 0.5)
			(thermal_bridge_width 0.5)
			(island_removal_mode 0)
		)
		(polygon
			(pts
				(arc
					(start 308.117494 -294.482266)
					(mid 308.113774 -294.491246)
					(end 308.104794 -294.494966)
				)
				(arc
					(start 306.631594 -294.494966)
					(mid 306.622614 -294.491246)
					(end 306.618894 -294.482266)
				)
				(arc
					(start 306.618894 -293.987728)
					(mid 306.622614 -293.978748)
					(end 306.631594 -293.975028)
				)
				(arc
					(start 308.104794 -293.975028)
					(mid 308.113774 -293.978748)
					(end 308.117494 -293.987728)
				)
			)
		)
	)
	(zone
		(layer "In1.Cu")
		(hatch none 0.5)
		(connect_pads
			(clearance 0)
		)
		(min_thickness 0.25)
		(keepout
			(tracks not_allowed)
			(vias allowed)
			(pads allowed)
			(copperpour not_allowed)
			(footprints allowed)
		)
		(placement
			(enabled no)
			(sheetname "")
		)
		(fill
			(thermal_gap 0.5)
			(thermal_bridge_width 0.5)
			(island_removal_mode 0)
		)
		(polygon
			(pts
				(arc
					(start 176.821338 -308.082442)
					(mid 176.817618 -308.091422)
					(end 176.808638 -308.095142)
				)
				(arc
					(start 175.335438 -308.095142)
					(mid 175.326458 -308.091422)
					(end 175.322738 -308.082442)
				)
				(arc
					(start 175.322738 -307.587904)
					(mid 175.326458 -307.578924)
					(end 175.335438 -307.575204)
				)
				(arc
					(start 176.808638 -307.575204)
					(mid 176.817618 -307.578924)
					(end 176.821338 -307.587904)
				)
			)
		)
	)
	(zone
		(layer "In1.Cu")
		(hatch none 0.5)
		(connect_pads
			(clearance 0)
		)
		(min_thickness 0.25)
		(keepout
			(tracks not_allowed)
			(vias allowed)
			(pads allowed)
			(copperpour not_allowed)
			(footprints allowed)
		)
		(placement
			(enabled no)
			(sheetname "")
		)
		(fill
			(thermal_gap 0.5)
			(thermal_bridge_width 0.5)
			(island_removal_mode 0)
		)
		(polygon
			(pts
				(arc
					(start 45.089318 -251.13234)
					(mid 45.085598 -251.14132)
					(end 45.076618 -251.14504)
				)
				(arc
					(start 43.603418 -251.14504)
					(mid 43.594438 -251.14132)
					(end 43.590718 -251.13234)
				)
				(arc
					(start 43.590718 -250.637802)
					(mid 43.594438 -250.628822)
					(end 43.603418 -250.625102)
				)
				(arc
					(start 45.076618 -250.625102)
					(mid 45.085598 -250.628822)
					(end 45.089318 -250.637802)
				)
			)
		)
	)
	(zone
		(layer "In1.Cu")
		(hatch none 0.5)
		(connect_pads
			(clearance 0)
		)
		(min_thickness 0.25)
		(keepout
			(tracks not_allowed)
			(vias allowed)
			(pads allowed)
			(copperpour not_allowed)
			(footprints allowed)
		)
		(placement
			(enabled no)
			(sheetname "")
		)
		(fill
			(thermal_gap 0.5)
			(thermal_bridge_width 0.5)
			(island_removal_mode 0)
		)
		(polygon
			(pts
				(arc
					(start 428.205392 -232.432098)
					(mid 428.201672 -232.441078)
					(end 428.192692 -232.444798)
				)
				(arc
					(start 426.719492 -232.444798)
					(mid 426.710512 -232.441078)
					(end 426.706792 -232.432098)
				)
				(arc
					(start 426.706792 -231.93756)
					(mid 426.710512 -231.92858)
					(end 426.719492 -231.92486)
				)
				(arc
					(start 428.192692 -231.92486)
					(mid 428.201672 -231.92858)
					(end 428.205392 -231.93756)
				)
			)
		)
	)
	(zone
		(layer "In1.Cu")
		(hatch none 0.5)
		(connect_pads
			(clearance 0)
		)
		(min_thickness 0.25)
		(keepout
			(tracks not_allowed)
			(vias allowed)
			(pads allowed)
			(copperpour not_allowed)
			(footprints allowed)
		)
		(placement
			(enabled no)
			(sheetname "")
		)
		(fill
			(thermal_gap 0.5)
			(thermal_bridge_width 0.5)
			(island_removal_mode 0)
		)
		(polygon
			(pts
				(arc
					(start 176.821338 -203.532486)
					(mid 176.817618 -203.541466)
					(end 176.808638 -203.545186)
				)
				(arc
					(start 175.335438 -203.545186)
					(mid 175.326458 -203.541466)
					(end 175.322738 -203.532486)
				)
				(arc
					(start 175.322738 -203.037948)
					(mid 175.326458 -203.028968)
					(end 175.335438 -203.025248)
				)
				(arc
					(start 176.808638 -203.025248)
					(mid 176.817618 -203.028968)
					(end 176.821338 -203.037948)
				)
			)
		)
	)
	(zone
		(layer "In1.Cu")
		(hatch none 0.5)
		(connect_pads
			(clearance 0)
		)
		(min_thickness 0.25)
		(keepout
			(tracks not_allowed)
			(vias allowed)
			(pads allowed)
			(copperpour not_allowed)
			(footprints allowed)
		)
		(placement
			(enabled no)
			(sheetname "")
		)
		(fill
			(thermal_gap 0.5)
			(thermal_bridge_width 0.5)
			(island_removal_mode 0)
		)
		(polygon
			(pts
				(arc
					(start 296.473372 -285.982156)
					(mid 296.469652 -285.991136)
					(end 296.460672 -285.994856)
				)
				(arc
					(start 294.987472 -285.994856)
					(mid 294.978492 -285.991136)
					(end 294.974772 -285.982156)
				)
				(arc
					(start 294.974772 -285.487618)
					(mid 294.978492 -285.478638)
					(end 294.987472 -285.474918)
				)
				(arc
					(start 296.460672 -285.474918)
					(mid 296.469652 -285.478638)
					(end 296.473372 -285.487618)
				)
			)
		)
	)
	(zone
		(layer "In1.Cu")
		(hatch none 0.5)
		(connect_pads
			(clearance 0)
		)
		(min_thickness 0.25)
		(keepout
			(tracks not_allowed)
			(vias allowed)
			(pads allowed)
			(copperpour not_allowed)
			(footprints allowed)
		)
		(placement
			(enabled no)
			(sheetname "")
		)
		(fill
			(thermal_gap 0.5)
			(thermal_bridge_width 0.5)
			(island_removal_mode 0)
		)
		(polygon
			(pts
				(arc
					(start 266.29741 -310.632094)
					(mid 266.29369 -310.641074)
					(end 266.28471 -310.644794)
				)
				(arc
					(start 264.81151 -310.644794)
					(mid 264.80253 -310.641074)
					(end 264.79881 -310.632094)
				)
				(arc
					(start 264.79881 -310.137556)
					(mid 264.80253 -310.128576)
					(end 264.81151 -310.124856)
				)
				(arc
					(start 266.28471 -310.124856)
					(mid 266.29369 -310.128576)
					(end 266.29741 -310.137556)
				)
			)
		)
	)
	(zone
		(layer "In1.Cu")
		(hatch none 0.5)
		(connect_pads
			(clearance 0)
		)
		(min_thickness 0.25)
		(keepout
			(tracks not_allowed)
			(vias allowed)
			(pads allowed)
			(copperpour not_allowed)
			(footprints allowed)
		)
		(placement
			(enabled no)
			(sheetname "")
		)
		(fill
			(thermal_gap 0.5)
			(thermal_bridge_width 0.5)
			(island_removal_mode 0)
		)
		(polygon
			(pts
				(arc
					(start 293.029386 -217.982292)
					(mid 293.025666 -217.991272)
					(end 293.016686 -217.994992)
				)
				(arc
					(start 291.543486 -217.994992)
					(mid 291.534506 -217.991272)
					(end 291.530786 -217.982292)
				)
				(arc
					(start 291.530786 -217.487754)
					(mid 291.534506 -217.478774)
					(end 291.543486 -217.475054)
				)
				(arc
					(start 293.016686 -217.475054)
					(mid 293.025666 -217.478774)
					(end 293.029386 -217.487754)
				)
			)
		)
	)
	(zone
		(layer "In1.Cu")
		(hatch none 0.5)
		(connect_pads
			(clearance 0)
		)
		(min_thickness 0.25)
		(keepout
			(tracks not_allowed)
			(vias allowed)
			(pads allowed)
			(copperpour not_allowed)
			(footprints allowed)
		)
		(placement
			(enabled no)
			(sheetname "")
		)
		(fill
			(thermal_gap 0.5)
			(thermal_bridge_width 0.5)
			(island_removal_mode 0)
		)
		(polygon
			(pts
				(arc
					(start 60.177426 -210.332574)
					(mid 60.173706 -210.341554)
					(end 60.164726 -210.345274)
				)
				(arc
					(start 58.691526 -210.345274)
					(mid 58.682546 -210.341554)
					(end 58.678826 -210.332574)
				)
				(arc
					(start 58.678826 -209.838036)
					(mid 58.682546 -209.829056)
					(end 58.691526 -209.825336)
				)
				(arc
					(start 60.164726 -209.825336)
					(mid 60.173706 -209.829056)
					(end 60.177426 -209.838036)
				)
			)
		)
	)
	(zone
		(layer "In1.Cu")
		(hatch none 0.5)
		(connect_pads
			(clearance 0)
		)
		(min_thickness 0.25)
		(keepout
			(tracks not_allowed)
			(vias allowed)
			(pads allowed)
			(copperpour not_allowed)
			(footprints allowed)
		)
		(placement
			(enabled no)
			(sheetname "")
		)
		(fill
			(thermal_gap 0.5)
			(thermal_bridge_width 0.5)
			(island_removal_mode 0)
		)
		(polygon
			(pts
				(arc
					(start 273.841464 -296.182288)
					(mid 273.837744 -296.191268)
					(end 273.828764 -296.194988)
				)
				(arc
					(start 272.355564 -296.194988)
					(mid 272.346584 -296.191268)
					(end 272.342864 -296.182288)
				)
				(arc
					(start 272.342864 -295.68775)
					(mid 272.346584 -295.67877)
					(end 272.355564 -295.67505)
				)
				(arc
					(start 273.828764 -295.67505)
					(mid 273.837744 -295.67877)
					(end 273.841464 -295.68775)
				)
			)
		)
	)
	(zone
		(layer "In1.Cu")
		(hatch none 0.5)
		(connect_pads
			(clearance 0)
		)
		(min_thickness 0.25)
		(keepout
			(tracks not_allowed)
			(vias allowed)
			(pads allowed)
			(copperpour not_allowed)
			(footprints allowed)
		)
		(placement
			(enabled no)
			(sheetname "")
		)
		(fill
			(thermal_gap 0.5)
			(thermal_bridge_width 0.5)
			(island_removal_mode 0)
		)
		(polygon
			(pts
				(arc
					(start 199.4535 -314.032392)
					(mid 199.44978 -314.041372)
					(end 199.4408 -314.045092)
				)
				(arc
					(start 197.9676 -314.045092)
					(mid 197.95862 -314.041372)
					(end 197.9549 -314.032392)
				)
				(arc
					(start 197.9549 -313.537854)
					(mid 197.95862 -313.528874)
					(end 197.9676 -313.525154)
				)
				(arc
					(start 199.4408 -313.525154)
					(mid 199.44978 -313.528874)
					(end 199.4535 -313.537854)
				)
			)
		)
	)
	(zone
		(layer "In1.Cu")
		(hatch none 0.5)
		(connect_pads
			(clearance 0)
		)
		(min_thickness 0.25)
		(keepout
			(tracks not_allowed)
			(vias allowed)
			(pads allowed)
			(copperpour not_allowed)
			(footprints allowed)
		)
		(placement
			(enabled no)
			(sheetname "")
		)
		(fill
			(thermal_gap 0.5)
			(thermal_bridge_width 0.5)
			(island_removal_mode 0)
		)
		(polygon
			(pts
				(arc
					(start 439.849514 -302.132238)
					(mid 439.845794 -302.141218)
					(end 439.836814 -302.144938)
				)
				(arc
					(start 438.363614 -302.144938)
					(mid 438.354634 -302.141218)
					(end 438.350914 -302.132238)
				)
				(arc
					(start 438.350914 -301.6377)
					(mid 438.354634 -301.62872)
					(end 438.363614 -301.625)
				)
				(arc
					(start 439.836814 -301.625)
					(mid 439.845794 -301.62872)
					(end 439.849514 -301.6377)
				)
			)
		)
	)
	(zone
		(layer "In1.Cu")
		(hatch none 0.5)
		(connect_pads
			(clearance 0)
		)
		(min_thickness 0.25)
		(keepout
			(tracks not_allowed)
			(vias allowed)
			(pads allowed)
			(copperpour not_allowed)
			(footprints allowed)
		)
		(placement
			(enabled no)
			(sheetname "")
		)
		(fill
			(thermal_gap 0.5)
			(thermal_bridge_width 0.5)
			(island_removal_mode 0)
		)
		(polygon
			(pts
				(arc
					(start 176.821338 -278.332438)
					(mid 176.817618 -278.341418)
					(end 176.808638 -278.345138)
				)
				(arc
					(start 175.335438 -278.345138)
					(mid 175.326458 -278.341418)
					(end 175.322738 -278.332438)
				)
				(arc
					(start 175.322738 -277.8379)
					(mid 175.326458 -277.82892)
					(end 175.335438 -277.8252)
				)
				(arc
					(start 176.808638 -277.8252)
					(mid 176.817618 -277.82892)
					(end 176.821338 -277.8379)
				)
			)
		)
	)
	(zone
		(layer "In1.Cu")
		(hatch none 0.5)
		(connect_pads
			(clearance 0)
		)
		(min_thickness 0.25)
		(keepout
			(tracks not_allowed)
			(vias allowed)
			(pads allowed)
			(copperpour not_allowed)
			(footprints allowed)
		)
		(placement
			(enabled no)
			(sheetname "")
		)
		(fill
			(thermal_gap 0.5)
			(thermal_bridge_width 0.5)
			(island_removal_mode 0)
		)
		(polygon
			(pts
				(arc
					(start 424.761406 -203.532232)
					(mid 424.757686 -203.541212)
					(end 424.748706 -203.544932)
				)
				(arc
					(start 423.275506 -203.544932)
					(mid 423.266526 -203.541212)
					(end 423.262806 -203.532232)
				)
				(arc
					(start 423.262806 -203.037694)
					(mid 423.266526 -203.028714)
					(end 423.275506 -203.024994)
				)
				(arc
					(start 424.748706 -203.024994)
					(mid 424.757686 -203.028714)
					(end 424.761406 -203.037694)
				)
			)
		)
	)
	(zone
		(layer "In1.Cu")
		(hatch none 0.5)
		(connect_pads
			(clearance 0)
		)
		(min_thickness 0.25)
		(keepout
			(tracks not_allowed)
			(vias allowed)
			(pads allowed)
			(copperpour not_allowed)
			(footprints allowed)
		)
		(placement
			(enabled no)
			(sheetname "")
		)
		(fill
			(thermal_gap 0.5)
			(thermal_bridge_width 0.5)
			(island_removal_mode 0)
		)
		(polygon
			(pts
				(arc
					(start 56.077358 -295.332404)
					(mid 56.073638 -295.341384)
					(end 56.064658 -295.345104)
				)
				(arc
					(start 54.591458 -295.345104)
					(mid 54.582478 -295.341384)
					(end 54.578758 -295.332404)
				)
				(arc
					(start 54.578758 -294.837866)
					(mid 54.582478 -294.828886)
					(end 54.591458 -294.825166)
				)
				(arc
					(start 56.064658 -294.825166)
					(mid 56.073638 -294.828886)
					(end 56.077358 -294.837866)
				)
			)
		)
	)
	(zone
		(layer "In1.Cu")
		(hatch none 0.5)
		(connect_pads
			(clearance 0)
		)
		(min_thickness 0.25)
		(keepout
			(tracks not_allowed)
			(vias allowed)
			(pads allowed)
			(copperpour not_allowed)
			(footprints allowed)
		)
		(placement
			(enabled no)
			(sheetname "")
		)
		(fill
			(thermal_gap 0.5)
			(thermal_bridge_width 0.5)
			(island_removal_mode 0)
		)
		(polygon
			(pts
				(arc
					(start 288.929318 -243.482114)
					(mid 288.925598 -243.491094)
					(end 288.916618 -243.494814)
				)
				(arc
					(start 287.443418 -243.494814)
					(mid 287.434438 -243.491094)
					(end 287.430718 -243.482114)
				)
				(arc
					(start 287.430718 -242.987576)
					(mid 287.434438 -242.978596)
					(end 287.443418 -242.974876)
				)
				(arc
					(start 288.916618 -242.974876)
					(mid 288.925598 -242.978596)
					(end 288.929318 -242.987576)
				)
			)
		)
	)
	(zone
		(layer "In1.Cu")
		(hatch none 0.5)
		(connect_pads
			(clearance 0)
		)
		(min_thickness 0.25)
		(keepout
			(tracks not_allowed)
			(vias allowed)
			(pads allowed)
			(copperpour not_allowed)
			(footprints allowed)
		)
		(placement
			(enabled no)
			(sheetname "")
		)
		(fill
			(thermal_gap 0.5)
			(thermal_bridge_width 0.5)
			(island_removal_mode 0)
		)
		(polygon
			(pts
				(arc
					(start 202.897232 -316.582552)
					(mid 202.893512 -316.591532)
					(end 202.884532 -316.595252)
				)
				(arc
					(start 201.411332 -316.595252)
					(mid 201.402352 -316.591532)
					(end 201.398632 -316.582552)
				)
				(arc
					(start 201.398632 -316.088014)
					(mid 201.402352 -316.079034)
					(end 201.411332 -316.075314)
				)
				(arc
					(start 202.884532 -316.075314)
					(mid 202.893512 -316.079034)
					(end 202.897232 -316.088014)
				)
			)
		)
	)
	(zone
		(layer "In1.Cu")
		(hatch none 0.5)
		(connect_pads
			(clearance 0)
		)
		(min_thickness 0.25)
		(keepout
			(tracks not_allowed)
			(vias allowed)
			(pads allowed)
			(copperpour not_allowed)
			(footprints allowed)
		)
		(placement
			(enabled no)
			(sheetname "")
		)
		(fill
			(thermal_gap 0.5)
			(thermal_bridge_width 0.5)
			(island_removal_mode 0)
		)
		(polygon
			(pts
				(arc
					(start 169.277284 -281.732482)
					(mid 169.273564 -281.741462)
					(end 169.264584 -281.745182)
				)
				(arc
					(start 167.791384 -281.745182)
					(mid 167.782404 -281.741462)
					(end 167.778684 -281.732482)
				)
				(arc
					(start 167.778684 -281.237944)
					(mid 167.782404 -281.228964)
					(end 167.791384 -281.225244)
				)
				(arc
					(start 169.264584 -281.225244)
					(mid 169.273564 -281.228964)
					(end 169.277284 -281.237944)
				)
			)
		)
	)
	(zone
		(layer "In1.Cu")
		(hatch none 0.5)
		(connect_pads
			(clearance 0)
		)
		(min_thickness 0.25)
		(keepout
			(tracks not_allowed)
			(vias allowed)
			(pads allowed)
			(copperpour not_allowed)
			(footprints allowed)
		)
		(placement
			(enabled no)
			(sheetname "")
		)
		(fill
			(thermal_gap 0.5)
			(thermal_bridge_width 0.5)
			(island_removal_mode 0)
		)
		(polygon
			(pts
				(arc
					(start 81.298034 -390.761474)
					(mid 80.993234 -390.761474)
					(end 81.298034 -390.761474)
				)
			)
		)
	)
	(zone
		(layer "In1.Cu")
		(hatch none 0.5)
		(connect_pads
			(clearance 0)
		)
		(min_thickness 0.25)
		(keepout
			(tracks not_allowed)
			(vias allowed)
			(pads allowed)
			(copperpour not_allowed)
			(footprints allowed)
		)
		(placement
			(enabled no)
			(sheetname "")
		)
		(fill
			(thermal_gap 0.5)
			(thermal_bridge_width 0.5)
			(island_removal_mode 0)
		)
		(polygon
			(pts
				(arc
					(start 161.888678 -386.003292)
					(mid 161.507678 -386.003292)
					(end 161.888678 -386.003292)
				)
			)
		)
	)
	(zone
		(layer "In1.Cu")
		(hatch none 0.5)
		(connect_pads
			(clearance 0)
		)
		(min_thickness 0.25)
		(keepout
			(tracks not_allowed)
			(vias allowed)
			(pads allowed)
			(copperpour not_allowed)
			(footprints allowed)
		)
		(placement
			(enabled no)
			(sheetname "")
		)
		(fill
			(thermal_gap 0.5)
			(thermal_bridge_width 0.5)
			(island_removal_mode 0)
		)
		(polygon
			(pts
				(arc
					(start 385.07035 -392.30427)
					(mid 384.76555 -392.30427)
					(end 385.07035 -392.30427)
				)
			)
		)
	)
	(zone
		(layer "In1.Cu")
		(hatch none 0.5)
		(connect_pads
			(clearance 0)
		)
		(min_thickness 0.25)
		(keepout
			(tracks not_allowed)
			(vias allowed)
			(pads allowed)
			(copperpour not_allowed)
			(footprints allowed)
		)
		(placement
			(enabled no)
			(sheetname "")
		)
		(fill
			(thermal_gap 0.5)
			(thermal_bridge_width 0.5)
			(island_removal_mode 0)
		)
		(polygon
			(pts
				(arc
					(start 336.38871 -397.849344)
					(mid 336.00771 -397.849344)
					(end 336.38871 -397.849344)
				)
			)
		)
	)
	(zone
		(layer "In1.Cu")
		(hatch none 0.5)
		(connect_pads
			(clearance 0)
		)
		(min_thickness 0.25)
		(keepout
			(tracks not_allowed)
			(vias allowed)
			(pads allowed)
			(copperpour not_allowed)
			(footprints allowed)
		)
		(placement
			(enabled no)
			(sheetname "")
		)
		(fill
			(thermal_gap 0.5)
			(thermal_bridge_width 0.5)
			(island_removal_mode 0)
		)
		(polygon
			(pts
				(arc
					(start 435.749446 -239.232186)
					(mid 435.745726 -239.241166)
					(end 435.736746 -239.244886)
				)
				(arc
					(start 434.263546 -239.244886)
					(mid 434.254566 -239.241166)
					(end 434.250846 -239.232186)
				)
				(arc
					(start 434.250846 -238.737648)
					(mid 434.254566 -238.728668)
					(end 434.263546 -238.724948)
				)
				(arc
					(start 435.736746 -238.724948)
					(mid 435.745726 -238.728668)
					(end 435.749446 -238.737648)
				)
			)
		)
	)
	(zone
		(layer "In1.Cu")
		(hatch none 0.5)
		(connect_pads
			(clearance 0)
		)
		(min_thickness 0.25)
		(keepout
			(tracks not_allowed)
			(vias allowed)
			(pads allowed)
			(copperpour not_allowed)
			(footprints allowed)
		)
		(placement
			(enabled no)
			(sheetname "")
		)
		(fill
			(thermal_gap 0.5)
			(thermal_bridge_width 0.5)
			(island_removal_mode 0)
		)
		(polygon
			(pts
				(arc
					(start 155.488894 -385.31038)
					(mid 155.107894 -385.31038)
					(end 155.488894 -385.31038)
				)
			)
		)
	)
	(zone
		(layer "In1.Cu")
		(hatch none 0.5)
		(connect_pads
			(clearance 0)
		)
		(min_thickness 0.25)
		(keepout
			(tracks not_allowed)
			(vias allowed)
			(pads allowed)
			(copperpour not_allowed)
			(footprints allowed)
		)
		(placement
			(enabled no)
			(sheetname "")
		)
		(fill
			(thermal_gap 0.5)
			(thermal_bridge_width 0.5)
			(island_removal_mode 0)
		)
		(polygon
			(pts
				(arc
					(start 199.4535 -219.682568)
					(mid 199.44978 -219.691548)
					(end 199.4408 -219.695268)
				)
				(arc
					(start 197.9676 -219.695268)
					(mid 197.95862 -219.691548)
					(end 197.9549 -219.682568)
				)
				(arc
					(start 197.9549 -219.18803)
					(mid 197.95862 -219.17905)
					(end 197.9676 -219.17533)
				)
				(arc
					(start 199.4408 -219.17533)
					(mid 199.44978 -219.17905)
					(end 199.4535 -219.18803)
				)
			)
		)
	)
	(zone
		(layer "In1.Cu")
		(hatch none 0.5)
		(connect_pads
			(clearance 0)
		)
		(min_thickness 0.25)
		(keepout
			(tracks not_allowed)
			(vias allowed)
			(pads allowed)
			(copperpour not_allowed)
			(footprints allowed)
		)
		(placement
			(enabled no)
			(sheetname "")
		)
		(fill
			(thermal_gap 0.5)
			(thermal_bridge_width 0.5)
			(island_removal_mode 0)
		)
		(polygon
			(pts
				(arc
					(start 191.909446 -261.332472)
					(mid 191.905726 -261.341452)
					(end 191.896746 -261.345172)
				)
				(arc
					(start 190.423546 -261.345172)
					(mid 190.414566 -261.341452)
					(end 190.410846 -261.332472)
				)
				(arc
					(start 190.410846 -260.837934)
					(mid 190.414566 -260.828954)
					(end 190.423546 -260.825234)
				)
				(arc
					(start 191.896746 -260.825234)
					(mid 191.905726 -260.828954)
					(end 191.909446 -260.837934)
				)
			)
		)
	)
	(zone
		(layer "In1.Cu")
		(hatch none 0.5)
		(connect_pads
			(clearance 0)
		)
		(min_thickness 0.25)
		(keepout
			(tracks not_allowed)
			(vias allowed)
			(pads allowed)
			(copperpour not_allowed)
			(footprints allowed)
		)
		(placement
			(enabled no)
			(sheetname "")
		)
		(fill
			(thermal_gap 0.5)
			(thermal_bridge_width 0.5)
			(island_removal_mode 0)
		)
		(polygon
			(pts
				(arc
					(start 22.45741 -220.532452)
					(mid 22.45369 -220.541432)
					(end 22.44471 -220.545152)
				)
				(arc
					(start 20.97151 -220.545152)
					(mid 20.96253 -220.541432)
					(end 20.95881 -220.532452)
				)
				(arc
					(start 20.95881 -220.037914)
					(mid 20.96253 -220.028934)
					(end 20.97151 -220.025214)
				)
				(arc
					(start 22.44471 -220.025214)
					(mid 22.45369 -220.028934)
					(end 22.45741 -220.037914)
				)
			)
		)
	)
	(zone
		(layer "In1.Cu")
		(hatch none 0.5)
		(connect_pads
			(clearance 0)
		)
		(min_thickness 0.25)
		(keepout
			(tracks not_allowed)
			(vias allowed)
			(pads allowed)
			(copperpour not_allowed)
			(footprints allowed)
		)
		(placement
			(enabled no)
			(sheetname "")
		)
		(fill
			(thermal_gap 0.5)
			(thermal_bridge_width 0.5)
			(island_removal_mode 0)
		)
		(polygon
			(pts
				(arc
					(start 184.365392 -278.332438)
					(mid 184.361672 -278.341418)
					(end 184.352692 -278.345138)
				)
				(arc
					(start 182.879492 -278.345138)
					(mid 182.870512 -278.341418)
					(end 182.866792 -278.332438)
				)
				(arc
					(start 182.866792 -277.8379)
					(mid 182.870512 -277.82892)
					(end 182.879492 -277.8252)
				)
				(arc
					(start 184.352692 -277.8252)
					(mid 184.361672 -277.82892)
					(end 184.365392 -277.8379)
				)
			)
		)
	)
	(zone
		(layer "In1.Cu")
		(hatch none 0.5)
		(connect_pads
			(clearance 0)
		)
		(min_thickness 0.25)
		(keepout
			(tracks not_allowed)
			(vias allowed)
			(pads allowed)
			(copperpour not_allowed)
			(footprints allowed)
		)
		(placement
			(enabled no)
			(sheetname "")
		)
		(fill
			(thermal_gap 0.5)
			(thermal_bridge_width 0.5)
			(island_removal_mode 0)
		)
		(polygon
			(pts
				(arc
					(start 176.821338 -238.382556)
					(mid 176.817618 -238.391536)
					(end 176.808638 -238.395256)
				)
				(arc
					(start 175.335438 -238.395256)
					(mid 175.326458 -238.391536)
					(end 175.322738 -238.382556)
				)
				(arc
					(start 175.322738 -237.888018)
					(mid 175.326458 -237.879038)
					(end 175.335438 -237.875318)
				)
				(arc
					(start 176.808638 -237.875318)
					(mid 176.817618 -237.879038)
					(end 176.821338 -237.888018)
				)
			)
		)
	)
	(zone
		(layer "In1.Cu")
		(hatch none 0.5)
		(connect_pads
			(clearance 0)
		)
		(min_thickness 0.25)
		(keepout
			(tracks not_allowed)
			(vias allowed)
			(pads allowed)
			(copperpour not_allowed)
			(footprints allowed)
		)
		(placement
			(enabled no)
			(sheetname "")
		)
		(fill
			(thermal_gap 0.5)
			(thermal_bridge_width 0.5)
			(island_removal_mode 0)
		)
		(polygon
			(pts
				(arc
					(start 15.034006 -106.08818)
					(mid 15.056324 -106.142062)
					(end 15.110206 -106.16438)
				)
				(arc
					(start 15.465806 -106.16438)
					(mid 15.519688 -106.142062)
					(end 15.542006 -106.08818)
				)
				(arc
					(start 15.542006 -104.18318)
					(mid 15.519688 -104.129298)
					(end 15.465806 -104.10698)
				)
				(arc
					(start 15.110206 -104.10698)
					(mid 15.056324 -104.129298)
					(end 15.034006 -104.18318)
				)
			)
		)
	)
	(zone
		(layer "In1.Cu")
		(hatch none 0.5)
		(connect_pads
			(clearance 0)
		)
		(min_thickness 0.25)
		(keepout
			(tracks not_allowed)
			(vias allowed)
			(pads allowed)
			(copperpour not_allowed)
			(footprints allowed)
		)
		(placement
			(enabled no)
			(sheetname "")
		)
		(fill
			(thermal_gap 0.5)
			(thermal_bridge_width 0.5)
			(island_removal_mode 0)
		)
		(polygon
			(pts
				(arc
					(start 169.277284 -239.23244)
					(mid 169.273564 -239.24142)
					(end 169.264584 -239.24514)
				)
				(arc
					(start 167.791384 -239.24514)
					(mid 167.782404 -239.24142)
					(end 167.778684 -239.23244)
				)
				(arc
					(start 167.778684 -238.737902)
					(mid 167.782404 -238.728922)
					(end 167.791384 -238.725202)
				)
				(arc
					(start 169.264584 -238.725202)
					(mid 169.273564 -238.728922)
					(end 169.277284 -238.737902)
				)
			)
		)
	)
	(zone
		(layer "In1.Cu")
		(hatch none 0.5)
		(connect_pads
			(clearance 0)
		)
		(min_thickness 0.25)
		(keepout
			(tracks not_allowed)
			(vias allowed)
			(pads allowed)
			(copperpour not_allowed)
			(footprints allowed)
		)
		(placement
			(enabled no)
			(sheetname "")
		)
		(fill
			(thermal_gap 0.5)
			(thermal_bridge_width 0.5)
			(island_removal_mode 0)
		)
		(polygon
			(pts
				(arc
					(start 300.57344 -219.682314)
					(mid 300.56972 -219.691294)
					(end 300.56074 -219.695014)
				)
				(arc
					(start 299.08754 -219.695014)
					(mid 299.07856 -219.691294)
					(end 299.07484 -219.682314)
				)
				(arc
					(start 299.07484 -219.187776)
					(mid 299.07856 -219.178796)
					(end 299.08754 -219.175076)
				)
				(arc
					(start 300.56074 -219.175076)
					(mid 300.56972 -219.178796)
					(end 300.57344 -219.187776)
				)
			)
		)
	)
	(zone
		(layer "In1.Cu")
		(hatch none 0.5)
		(connect_pads
			(clearance 0)
		)
		(min_thickness 0.25)
		(keepout
			(tracks not_allowed)
			(vias allowed)
			(pads allowed)
			(copperpour not_allowed)
			(footprints allowed)
		)
		(placement
			(enabled no)
			(sheetname "")
		)
		(fill
			(thermal_gap 0.5)
			(thermal_bridge_width 0.5)
			(island_removal_mode 0)
		)
		(polygon
			(pts
				(arc
					(start 202.897232 -229.882446)
					(mid 202.893512 -229.891426)
					(end 202.884532 -229.895146)
				)
				(arc
					(start 201.411332 -229.895146)
					(mid 201.402352 -229.891426)
					(end 201.398632 -229.882446)
				)
				(arc
					(start 201.398632 -229.387908)
					(mid 201.402352 -229.378928)
					(end 201.411332 -229.375208)
				)
				(arc
					(start 202.884532 -229.375208)
					(mid 202.893512 -229.378928)
					(end 202.897232 -229.387908)
				)
			)
		)
	)
	(zone
		(layer "In1.Cu")
		(hatch none 0.5)
		(connect_pads
			(clearance 0)
		)
		(min_thickness 0.25)
		(keepout
			(tracks not_allowed)
			(vias allowed)
			(pads allowed)
			(copperpour not_allowed)
			(footprints allowed)
		)
		(placement
			(enabled no)
			(sheetname "")
		)
		(fill
			(thermal_gap 0.5)
			(thermal_bridge_width 0.5)
			(island_removal_mode 0)
		)
		(polygon
			(pts
				(arc
					(start 57.46115 -389.467344)
					(mid 57.08015 -389.467344)
					(end 57.46115 -389.467344)
				)
			)
		)
	)
	(zone
		(layer "In1.Cu")
		(hatch none 0.5)
		(connect_pads
			(clearance 0)
		)
		(min_thickness 0.25)
		(keepout
			(tracks not_allowed)
			(vias allowed)
			(pads allowed)
			(copperpour not_allowed)
			(footprints allowed)
		)
		(placement
			(enabled no)
			(sheetname "")
		)
		(fill
			(thermal_gap 0.5)
			(thermal_bridge_width 0.5)
			(island_removal_mode 0)
		)
		(polygon
			(pts
				(arc
					(start 202.897232 -285.98241)
					(mid 202.893512 -285.99139)
					(end 202.884532 -285.99511)
				)
				(arc
					(start 201.411332 -285.99511)
					(mid 201.402352 -285.99139)
					(end 201.398632 -285.98241)
				)
				(arc
					(start 201.398632 -285.487872)
					(mid 201.402352 -285.478892)
					(end 201.411332 -285.475172)
				)
				(arc
					(start 202.884532 -285.475172)
					(mid 202.893512 -285.478892)
					(end 202.897232 -285.487872)
				)
			)
		)
	)
	(zone
		(layer "In1.Cu")
		(hatch none 0.5)
		(connect_pads
			(clearance 0)
		)
		(min_thickness 0.25)
		(keepout
			(tracks not_allowed)
			(vias allowed)
			(pads allowed)
			(copperpour not_allowed)
			(footprints allowed)
		)
		(placement
			(enabled no)
			(sheetname "")
		)
		(fill
			(thermal_gap 0.5)
			(thermal_bridge_width 0.5)
			(island_removal_mode 0)
		)
		(polygon
			(pts
				(arc
					(start 277.941532 -231.582214)
					(mid 277.937812 -231.591194)
					(end 277.928832 -231.594914)
				)
				(arc
					(start 276.455632 -231.594914)
					(mid 276.446652 -231.591194)
					(end 276.442932 -231.582214)
				)
				(arc
					(start 276.442932 -231.087676)
					(mid 276.446652 -231.078696)
					(end 276.455632 -231.074976)
				)
				(arc
					(start 277.928832 -231.074976)
					(mid 277.937812 -231.078696)
					(end 277.941532 -231.087676)
				)
			)
		)
	)
	(zone
		(layer "In1.Cu")
		(hatch none 0.5)
		(connect_pads
			(clearance 0)
		)
		(min_thickness 0.25)
		(keepout
			(tracks not_allowed)
			(vias allowed)
			(pads allowed)
			(copperpour not_allowed)
			(footprints allowed)
		)
		(placement
			(enabled no)
			(sheetname "")
		)
		(fill
			(thermal_gap 0.5)
			(thermal_bridge_width 0.5)
			(island_removal_mode 0)
		)
		(polygon
			(pts
				(arc
					(start 60.177426 -222.232474)
					(mid 60.173706 -222.241454)
					(end 60.164726 -222.245174)
				)
				(arc
					(start 58.691526 -222.245174)
					(mid 58.682546 -222.241454)
					(end 58.678826 -222.232474)
				)
				(arc
					(start 58.678826 -221.737936)
					(mid 58.682546 -221.728956)
					(end 58.691526 -221.725236)
				)
				(arc
					(start 60.164726 -221.725236)
					(mid 60.173706 -221.728956)
					(end 60.177426 -221.737936)
				)
			)
		)
	)
	(zone
		(layer "In1.Cu")
		(hatch none 0.5)
		(connect_pads
			(clearance 0)
		)
		(min_thickness 0.25)
		(keepout
			(tracks not_allowed)
			(vias allowed)
			(pads allowed)
			(copperpour not_allowed)
			(footprints allowed)
		)
		(placement
			(enabled no)
			(sheetname "")
		)
		(fill
			(thermal_gap 0.5)
			(thermal_bridge_width 0.5)
			(island_removal_mode 0)
		)
		(polygon
			(pts
				(arc
					(start 206.5782 -204.985366)
					(mid 205.9178 -204.985366)
					(end 206.5782 -204.985366)
				)
			)
		)
	)
	(zone
		(layer "In1.Cu")
		(hatch none 0.5)
		(connect_pads
			(clearance 0)
		)
		(min_thickness 0.25)
		(keepout
			(tracks not_allowed)
			(vias allowed)
			(pads allowed)
			(copperpour not_allowed)
			(footprints allowed)
		)
		(placement
			(enabled no)
			(sheetname "")
		)
		(fill
			(thermal_gap 0.5)
			(thermal_bridge_width 0.5)
			(island_removal_mode 0)
		)
		(polygon
			(pts
				(arc
					(start 454.937368 -306.382166)
					(mid 454.933648 -306.391146)
					(end 454.924668 -306.394866)
				)
				(arc
					(start 453.451468 -306.394866)
					(mid 453.442488 -306.391146)
					(end 453.438768 -306.382166)
				)
				(arc
					(start 453.438768 -305.887628)
					(mid 453.442488 -305.878648)
					(end 453.451468 -305.874928)
				)
				(arc
					(start 454.924668 -305.874928)
					(mid 454.933648 -305.878648)
					(end 454.937368 -305.887628)
				)
			)
		)
	)
	(zone
		(layer "In1.Cu")
		(hatch none 0.5)
		(connect_pads
			(clearance 0)
		)
		(min_thickness 0.25)
		(keepout
			(tracks not_allowed)
			(vias allowed)
			(pads allowed)
			(copperpour not_allowed)
			(footprints allowed)
		)
		(placement
			(enabled no)
			(sheetname "")
		)
		(fill
			(thermal_gap 0.5)
			(thermal_bridge_width 0.5)
			(island_removal_mode 0)
		)
		(polygon
			(pts
				(arc
					(start 277.941532 -217.982292)
					(mid 277.937812 -217.991272)
					(end 277.928832 -217.994992)
				)
				(arc
					(start 276.455632 -217.994992)
					(mid 276.446652 -217.991272)
					(end 276.442932 -217.982292)
				)
				(arc
					(start 276.442932 -217.487754)
					(mid 276.446652 -217.478774)
					(end 276.455632 -217.475054)
				)
				(arc
					(start 277.928832 -217.475054)
					(mid 277.937812 -217.478774)
					(end 277.941532 -217.487754)
				)
			)
		)
	)
	(zone
		(layer "In1.Cu")
		(hatch none 0.5)
		(connect_pads
			(clearance 0)
		)
		(min_thickness 0.25)
		(keepout
			(tracks not_allowed)
			(vias allowed)
			(pads allowed)
			(copperpour not_allowed)
			(footprints allowed)
		)
		(placement
			(enabled no)
			(sheetname "")
		)
		(fill
			(thermal_gap 0.5)
			(thermal_bridge_width 0.5)
			(island_removal_mode 0)
		)
		(polygon
			(pts
				(arc
					(start 33.445196 -273.232372)
					(mid 33.441476 -273.241352)
					(end 33.432496 -273.245072)
				)
				(arc
					(start 31.959296 -273.245072)
					(mid 31.950316 -273.241352)
					(end 31.946596 -273.232372)
				)
				(arc
					(start 31.946596 -272.737834)
					(mid 31.950316 -272.728854)
					(end 31.959296 -272.725134)
				)
				(arc
					(start 33.432496 -272.725134)
					(mid 33.441476 -272.728854)
					(end 33.445196 -272.737834)
				)
			)
		)
	)
	(zone
		(layer "In1.Cu")
		(hatch none 0.5)
		(connect_pads
			(clearance 0)
		)
		(min_thickness 0.25)
		(keepout
			(tracks not_allowed)
			(vias allowed)
			(pads allowed)
			(copperpour not_allowed)
			(footprints allowed)
		)
		(placement
			(enabled no)
			(sheetname "")
		)
		(fill
			(thermal_gap 0.5)
			(thermal_bridge_width 0.5)
			(island_removal_mode 0)
		)
		(polygon
			(pts
				(arc
					(start 165.089078 -388.774432)
					(mid 164.708078 -388.774432)
					(end 165.089078 -388.774432)
				)
			)
		)
	)
	(zone
		(layer "In1.Cu")
		(hatch none 0.5)
		(connect_pads
			(clearance 0)
		)
		(min_thickness 0.25)
		(keepout
			(tracks not_allowed)
			(vias allowed)
			(pads allowed)
			(copperpour not_allowed)
			(footprints allowed)
		)
		(placement
			(enabled no)
			(sheetname "")
		)
		(fill
			(thermal_gap 0.5)
			(thermal_bridge_width 0.5)
			(island_removal_mode 0)
		)
		(polygon
			(pts
				(arc
					(start 281.385264 -280.88209)
					(mid 281.381544 -280.89107)
					(end 281.372564 -280.89479)
				)
				(arc
					(start 279.899364 -280.89479)
					(mid 279.890384 -280.89107)
					(end 279.886664 -280.88209)
				)
				(arc
					(start 279.886664 -280.387552)
					(mid 279.890384 -280.378572)
					(end 279.899364 -280.374852)
				)
				(arc
					(start 281.372564 -280.374852)
					(mid 281.381544 -280.378572)
					(end 281.385264 -280.387552)
				)
			)
		)
	)
	(zone
		(layer "In1.Cu")
		(hatch none 0.5)
		(connect_pads
			(clearance 0)
		)
		(min_thickness 0.25)
		(keepout
			(tracks not_allowed)
			(vias allowed)
			(pads allowed)
			(copperpour not_allowed)
			(footprints allowed)
		)
		(placement
			(enabled no)
			(sheetname "")
		)
		(fill
			(thermal_gap 0.5)
			(thermal_bridge_width 0.5)
			(island_removal_mode 0)
		)
		(polygon
			(pts
				(arc
					(start 37.545264 -229.882446)
					(mid 37.541544 -229.891426)
					(end 37.532564 -229.895146)
				)
				(arc
					(start 36.059364 -229.895146)
					(mid 36.050384 -229.891426)
					(end 36.046664 -229.882446)
				)
				(arc
					(start 36.046664 -229.387908)
					(mid 36.050384 -229.378928)
					(end 36.059364 -229.375208)
				)
				(arc
					(start 37.532564 -229.375208)
					(mid 37.541544 -229.378928)
					(end 37.545264 -229.387908)
				)
			)
		)
	)
	(zone
		(layer "In1.Cu")
		(hatch none 0.5)
		(connect_pads
			(clearance 0)
		)
		(min_thickness 0.25)
		(keepout
			(tracks not_allowed)
			(vias allowed)
			(pads allowed)
			(copperpour not_allowed)
			(footprints allowed)
		)
		(placement
			(enabled no)
			(sheetname "")
		)
		(fill
			(thermal_gap 0.5)
			(thermal_bridge_width 0.5)
			(island_removal_mode 0)
		)
		(polygon
			(pts
				(arc
					(start 176.821338 -251.13234)
					(mid 176.817618 -251.14132)
					(end 176.808638 -251.14504)
				)
				(arc
					(start 175.335438 -251.14504)
					(mid 175.326458 -251.14132)
					(end 175.322738 -251.13234)
				)
				(arc
					(start 175.322738 -250.637802)
					(mid 175.326458 -250.628822)
					(end 175.335438 -250.625102)
				)
				(arc
					(start 176.808638 -250.625102)
					(mid 176.817618 -250.628822)
					(end 176.821338 -250.637802)
				)
			)
		)
	)
	(zone
		(layer "In1.Cu")
		(hatch none 0.5)
		(connect_pads
			(clearance 0)
		)
		(min_thickness 0.25)
		(keepout
			(tracks not_allowed)
			(vias allowed)
			(pads allowed)
			(copperpour not_allowed)
			(footprints allowed)
		)
		(placement
			(enabled no)
			(sheetname "")
		)
		(fill
			(thermal_gap 0.5)
			(thermal_bridge_width 0.5)
			(island_removal_mode 0)
		)
		(polygon
			(pts
				(arc
					(start 305.060858 -397.849344)
					(mid 304.679858 -397.849344)
					(end 305.060858 -397.849344)
				)
			)
		)
	)
	(zone
		(layer "In1.Cu")
		(hatch none 0.5)
		(connect_pads
			(clearance 0)
		)
		(min_thickness 0.25)
		(keepout
			(tracks not_allowed)
			(vias allowed)
			(pads allowed)
			(copperpour not_allowed)
			(footprints allowed)
		)
		(placement
			(enabled no)
			(sheetname "")
		)
		(fill
			(thermal_gap 0.5)
			(thermal_bridge_width 0.5)
			(island_removal_mode 0)
		)
		(polygon
			(pts
				(arc
					(start 48.533304 -288.53257)
					(mid 48.529584 -288.54155)
					(end 48.520604 -288.54527)
				)
				(arc
					(start 47.047404 -288.54527)
					(mid 47.038424 -288.54155)
					(end 47.034704 -288.53257)
				)
				(arc
					(start 47.034704 -288.038032)
					(mid 47.038424 -288.029052)
					(end 47.047404 -288.025332)
				)
				(arc
					(start 48.520604 -288.025332)
					(mid 48.529584 -288.029052)
					(end 48.533304 -288.038032)
				)
			)
		)
	)
	(zone
		(layer "In1.Cu")
		(hatch none 0.5)
		(connect_pads
			(clearance 0)
		)
		(min_thickness 0.25)
		(keepout
			(tracks not_allowed)
			(vias allowed)
			(pads allowed)
			(copperpour not_allowed)
			(footprints allowed)
		)
		(placement
			(enabled no)
			(sheetname "")
		)
		(fill
			(thermal_gap 0.5)
			(thermal_bridge_width 0.5)
			(island_removal_mode 0)
		)
		(polygon
			(pts
				(arc
					(start 25.901396 -232.432352)
					(mid 25.897676 -232.441332)
					(end 25.888696 -232.445052)
				)
				(arc
					(start 24.415496 -232.445052)
					(mid 24.406516 -232.441332)
					(end 24.402796 -232.432352)
				)
				(arc
					(start 24.402796 -231.937814)
					(mid 24.406516 -231.928834)
					(end 24.415496 -231.925114)
				)
				(arc
					(start 25.888696 -231.925114)
					(mid 25.897676 -231.928834)
					(end 25.901396 -231.937814)
				)
			)
		)
	)
	(zone
		(layer "In1.Cu")
		(hatch none 0.5)
		(connect_pads
			(clearance 0)
		)
		(min_thickness 0.25)
		(keepout
			(tracks not_allowed)
			(vias allowed)
			(pads allowed)
			(copperpour not_allowed)
			(footprints allowed)
		)
		(placement
			(enabled no)
			(sheetname "")
		)
		(fill
			(thermal_gap 0.5)
			(thermal_bridge_width 0.5)
			(island_removal_mode 0)
		)
		(polygon
			(pts
				(arc
					(start 293.029386 -227.332286)
					(mid 293.025666 -227.341266)
					(end 293.016686 -227.344986)
				)
				(arc
					(start 291.543486 -227.344986)
					(mid 291.534506 -227.341266)
					(end 291.530786 -227.332286)
				)
				(arc
					(start 291.530786 -226.837748)
					(mid 291.534506 -226.828768)
					(end 291.543486 -226.825048)
				)
				(arc
					(start 293.016686 -226.825048)
					(mid 293.025666 -226.828768)
					(end 293.029386 -226.837748)
				)
			)
		)
	)
	(zone
		(layer "In1.Cu")
		(hatch none 0.5)
		(connect_pads
			(clearance 0)
		)
		(min_thickness 0.25)
		(keepout
			(tracks not_allowed)
			(vias allowed)
			(pads allowed)
			(copperpour not_allowed)
			(footprints allowed)
		)
		(placement
			(enabled no)
			(sheetname "")
		)
		(fill
			(thermal_gap 0.5)
			(thermal_bridge_width 0.5)
			(island_removal_mode 0)
		)
		(polygon
			(pts
				(arc
					(start 417.217352 -199.282304)
					(mid 417.213632 -199.291284)
					(end 417.204652 -199.295004)
				)
				(arc
					(start 415.731452 -199.295004)
					(mid 415.722472 -199.291284)
					(end 415.718752 -199.282304)
				)
				(arc
					(start 415.718752 -198.787766)
					(mid 415.722472 -198.778786)
					(end 415.731452 -198.775066)
				)
				(arc
					(start 417.204652 -198.775066)
					(mid 417.213632 -198.778786)
					(end 417.217352 -198.787766)
				)
			)
		)
	)
	(zone
		(layer "In1.Cu")
		(hatch none 0.5)
		(connect_pads
			(clearance 0)
		)
		(min_thickness 0.25)
		(keepout
			(tracks not_allowed)
			(vias allowed)
			(pads allowed)
			(copperpour not_allowed)
			(footprints allowed)
		)
		(placement
			(enabled no)
			(sheetname "")
		)
		(fill
			(thermal_gap 0.5)
			(thermal_bridge_width 0.5)
			(island_removal_mode 0)
		)
		(polygon
			(pts
				(arc
					(start 319.17005 -392.30427)
					(mid 318.86525 -392.30427)
					(end 319.17005 -392.30427)
				)
			)
		)
	)
	(zone
		(layer "In1.Cu")
		(hatch none 0.5)
		(connect_pads
			(clearance 0)
		)
		(min_thickness 0.25)
		(keepout
			(tracks not_allowed)
			(vias allowed)
			(pads allowed)
			(copperpour not_allowed)
			(footprints allowed)
		)
		(placement
			(enabled no)
			(sheetname "")
		)
		(fill
			(thermal_gap 0.5)
			(thermal_bridge_width 0.5)
			(island_removal_mode 0)
		)
		(polygon
			(pts
				(arc
					(start 195.353432 -201.832464)
					(mid 195.349712 -201.841444)
					(end 195.340732 -201.845164)
				)
				(arc
					(start 193.867532 -201.845164)
					(mid 193.858552 -201.841444)
					(end 193.854832 -201.832464)
				)
				(arc
					(start 193.854832 -201.337926)
					(mid 193.858552 -201.328946)
					(end 193.867532 -201.325226)
				)
				(arc
					(start 195.340732 -201.325226)
					(mid 195.349712 -201.328946)
					(end 195.353432 -201.337926)
				)
			)
		)
	)
	(zone
		(layer "In1.Cu")
		(hatch none 0.5)
		(connect_pads
			(clearance 0)
		)
		(min_thickness 0.25)
		(keepout
			(tracks not_allowed)
			(vias allowed)
			(pads allowed)
			(copperpour not_allowed)
			(footprints allowed)
		)
		(placement
			(enabled no)
			(sheetname "")
		)
		(fill
			(thermal_gap 0.5)
			(thermal_bridge_width 0.5)
			(island_removal_mode 0)
		)
		(polygon
			(pts
				(arc
					(start 417.217352 -306.382166)
					(mid 417.213632 -306.391146)
					(end 417.204652 -306.394866)
				)
				(arc
					(start 415.731452 -306.394866)
					(mid 415.722472 -306.391146)
					(end 415.718752 -306.382166)
				)
				(arc
					(start 415.718752 -305.887628)
					(mid 415.722472 -305.878648)
					(end 415.731452 -305.874928)
				)
				(arc
					(start 417.204652 -305.874928)
					(mid 417.213632 -305.878648)
					(end 417.217352 -305.887628)
				)
			)
		)
	)
	(zone
		(layer "In1.Cu")
		(hatch none 0.5)
		(connect_pads
			(clearance 0)
		)
		(min_thickness 0.25)
		(keepout
			(tracks not_allowed)
			(vias allowed)
			(pads allowed)
			(copperpour not_allowed)
			(footprints allowed)
		)
		(placement
			(enabled no)
			(sheetname "")
		)
		(fill
			(thermal_gap 0.5)
			(thermal_bridge_width 0.5)
			(island_removal_mode 0)
		)
		(polygon
			(pts
				(arc
					(start 33.445196 -280.882344)
					(mid 33.441476 -280.891324)
					(end 33.432496 -280.895044)
				)
				(arc
					(start 31.959296 -280.895044)
					(mid 31.950316 -280.891324)
					(end 31.946596 -280.882344)
				)
				(arc
					(start 31.946596 -280.387806)
					(mid 31.950316 -280.378826)
					(end 31.959296 -280.375106)
				)
				(arc
					(start 33.432496 -280.375106)
					(mid 33.441476 -280.378826)
					(end 33.445196 -280.387806)
				)
			)
		)
	)
	(zone
		(layer "In1.Cu")
		(hatch none 0.5)
		(connect_pads
			(clearance 0)
		)
		(min_thickness 0.25)
		(keepout
			(tracks not_allowed)
			(vias allowed)
			(pads allowed)
			(copperpour not_allowed)
			(footprints allowed)
		)
		(placement
			(enabled no)
			(sheetname "")
		)
		(fill
			(thermal_gap 0.5)
			(thermal_bridge_width 0.5)
			(island_removal_mode 0)
		)
		(polygon
			(pts
				(arc
					(start 382.670304 -392.30427)
					(mid 382.365504 -392.30427)
					(end 382.670304 -392.30427)
				)
			)
		)
	)
	(zone
		(layer "In1.Cu")
		(hatch none 0.5)
		(connect_pads
			(clearance 0)
		)
		(min_thickness 0.25)
		(keepout
			(tracks not_allowed)
			(vias allowed)
			(pads allowed)
			(copperpour not_allowed)
			(footprints allowed)
		)
		(placement
			(enabled no)
			(sheetname "")
		)
		(fill
			(thermal_gap 0.5)
			(thermal_bridge_width 0.5)
			(island_removal_mode 0)
		)
		(polygon
			(pts
				(arc
					(start 285.485332 -314.032138)
					(mid 285.481612 -314.041118)
					(end 285.472632 -314.044838)
				)
				(arc
					(start 283.999432 -314.044838)
					(mid 283.990452 -314.041118)
					(end 283.986732 -314.032138)
				)
				(arc
					(start 283.986732 -313.5376)
					(mid 283.990452 -313.52862)
					(end 283.999432 -313.5249)
				)
				(arc
					(start 285.472632 -313.5249)
					(mid 285.481612 -313.52862)
					(end 285.485332 -313.5376)
				)
			)
		)
	)
	(zone
		(layer "In1.Cu")
		(hatch none 0.5)
		(connect_pads
			(clearance 0)
		)
		(min_thickness 0.25)
		(keepout
			(tracks not_allowed)
			(vias allowed)
			(pads allowed)
			(copperpour not_allowed)
			(footprints allowed)
		)
		(placement
			(enabled no)
			(sheetname "")
		)
		(fill
			(thermal_gap 0.5)
			(thermal_bridge_width 0.5)
			(island_removal_mode 0)
		)
		(polygon
			(pts
				(arc
					(start 296.473372 -211.182204)
					(mid 296.469652 -211.191184)
					(end 296.460672 -211.194904)
				)
				(arc
					(start 294.987472 -211.194904)
					(mid 294.978492 -211.191184)
					(end 294.974772 -211.182204)
				)
				(arc
					(start 294.974772 -210.687666)
					(mid 294.978492 -210.678686)
					(end 294.987472 -210.674966)
				)
				(arc
					(start 296.460672 -210.674966)
					(mid 296.469652 -210.678686)
					(end 296.473372 -210.687666)
				)
			)
		)
	)
	(zone
		(layer "In1.Cu")
		(hatch none 0.5)
		(connect_pads
			(clearance 0)
		)
		(min_thickness 0.25)
		(keepout
			(tracks not_allowed)
			(vias allowed)
			(pads allowed)
			(copperpour not_allowed)
			(footprints allowed)
		)
		(placement
			(enabled no)
			(sheetname "")
		)
		(fill
			(thermal_gap 0.5)
			(thermal_bridge_width 0.5)
			(island_removal_mode 0)
		)
		(polygon
			(pts
				(arc
					(start 83.589114 -388.774432)
					(mid 83.208114 -388.774432)
					(end 83.589114 -388.774432)
				)
			)
		)
	)
	(zone
		(layer "In1.Cu")
		(hatch none 0.5)
		(connect_pads
			(clearance 0)
		)
		(min_thickness 0.25)
		(keepout
			(tracks not_allowed)
			(vias allowed)
			(pads allowed)
			(copperpour not_allowed)
			(footprints allowed)
		)
		(placement
			(enabled no)
			(sheetname "")
		)
		(fill
			(thermal_gap 0.5)
			(thermal_bridge_width 0.5)
			(island_removal_mode 0)
		)
		(polygon
			(pts
				(arc
					(start 273.841464 -248.58218)
					(mid 273.837744 -248.59116)
					(end 273.828764 -248.59488)
				)
				(arc
					(start 272.355564 -248.59488)
					(mid 272.346584 -248.59116)
					(end 272.342864 -248.58218)
				)
				(arc
					(start 272.342864 -248.087642)
					(mid 272.346584 -248.078662)
					(end 272.355564 -248.074942)
				)
				(arc
					(start 273.828764 -248.074942)
					(mid 273.837744 -248.078662)
					(end 273.841464 -248.087642)
				)
			)
		)
	)
	(zone
		(layer "In1.Cu")
		(hatch none 0.5)
		(connect_pads
			(clearance 0)
		)
		(min_thickness 0.25)
		(keepout
			(tracks not_allowed)
			(vias allowed)
			(pads allowed)
			(copperpour not_allowed)
			(footprints allowed)
		)
		(placement
			(enabled no)
			(sheetname "")
		)
		(fill
			(thermal_gap 0.5)
			(thermal_bridge_width 0.5)
			(island_removal_mode 0)
		)
		(polygon
			(pts
				(arc
					(start 339.697822 -399.143474)
					(mid 339.393022 -399.143474)
					(end 339.697822 -399.143474)
				)
			)
		)
	)
	(zone
		(layer "In1.Cu")
		(hatch none 0.5)
		(connect_pads
			(clearance 0)
		)
		(min_thickness 0.25)
		(keepout
			(tracks not_allowed)
			(vias allowed)
			(pads allowed)
			(copperpour not_allowed)
			(footprints allowed)
		)
		(placement
			(enabled no)
			(sheetname "")
		)
		(fill
			(thermal_gap 0.5)
			(thermal_bridge_width 0.5)
			(island_removal_mode 0)
		)
		(polygon
			(pts
				(arc
					(start 206.9973 -203.532486)
					(mid 206.99358 -203.541466)
					(end 206.9846 -203.545186)
				)
				(arc
					(start 205.5114 -203.545186)
					(mid 205.50242 -203.541466)
					(end 205.4987 -203.532486)
				)
				(arc
					(start 205.4987 -203.037948)
					(mid 205.50242 -203.028968)
					(end 205.5114 -203.025248)
				)
				(arc
					(start 206.9846 -203.025248)
					(mid 206.99358 -203.028968)
					(end 206.9973 -203.037948)
				)
			)
		)
	)
	(zone
		(layer "In1.Cu")
		(hatch none 0.5)
		(connect_pads
			(clearance 0)
		)
		(min_thickness 0.25)
		(keepout
			(tracks not_allowed)
			(vias allowed)
			(pads allowed)
			(copperpour not_allowed)
			(footprints allowed)
		)
		(placement
			(enabled no)
			(sheetname "")
		)
		(fill
			(thermal_gap 0.5)
			(thermal_bridge_width 0.5)
			(island_removal_mode 0)
		)
		(polygon
			(pts
				(arc
					(start 206.9973 -274.08251)
					(mid 206.99358 -274.09149)
					(end 206.9846 -274.09521)
				)
				(arc
					(start 205.5114 -274.09521)
					(mid 205.50242 -274.09149)
					(end 205.4987 -274.08251)
				)
				(arc
					(start 205.4987 -273.587972)
					(mid 205.50242 -273.578992)
					(end 205.5114 -273.575272)
				)
				(arc
					(start 206.9846 -273.575272)
					(mid 206.99358 -273.578992)
					(end 206.9973 -273.587972)
				)
			)
		)
	)
	(zone
		(layer "In1.Cu")
		(hatch none 0.5)
		(connect_pads
			(clearance 0)
		)
		(min_thickness 0.25)
		(keepout
			(tracks not_allowed)
			(vias allowed)
			(pads allowed)
			(copperpour not_allowed)
			(footprints allowed)
		)
		(placement
			(enabled no)
			(sheetname "")
		)
		(fill
			(thermal_gap 0.5)
			(thermal_bridge_width 0.5)
			(island_removal_mode 0)
		)
		(polygon
			(pts
				(arc
					(start 277.941532 -306.382166)
					(mid 277.937812 -306.391146)
					(end 277.928832 -306.394866)
				)
				(arc
					(start 276.455632 -306.394866)
					(mid 276.446652 -306.391146)
					(end 276.442932 -306.382166)
				)
				(arc
					(start 276.442932 -305.887628)
					(mid 276.446652 -305.878648)
					(end 276.455632 -305.874928)
				)
				(arc
					(start 277.928832 -305.874928)
					(mid 277.937812 -305.878648)
					(end 277.941532 -305.887628)
				)
			)
		)
	)
	(zone
		(layer "In1.Cu")
		(hatch none 0.5)
		(connect_pads
			(clearance 0)
		)
		(min_thickness 0.25)
		(keepout
			(tracks not_allowed)
			(vias allowed)
			(pads allowed)
			(copperpour not_allowed)
			(footprints allowed)
		)
		(placement
			(enabled no)
			(sheetname "")
		)
		(fill
			(thermal_gap 0.5)
			(thermal_bridge_width 0.5)
			(island_removal_mode 0)
		)
		(polygon
			(pts
				(arc
					(start 266.29741 -251.982224)
					(mid 266.29369 -251.991204)
					(end 266.28471 -251.994924)
				)
				(arc
					(start 264.81151 -251.994924)
					(mid 264.80253 -251.991204)
					(end 264.79881 -251.982224)
				)
				(arc
					(start 264.79881 -251.487686)
					(mid 264.80253 -251.478706)
					(end 264.81151 -251.474986)
				)
				(arc
					(start 266.28471 -251.474986)
					(mid 266.29369 -251.478706)
					(end 266.29741 -251.487686)
				)
			)
		)
	)
	(zone
		(layer "In1.Cu")
		(hatch none 0.5)
		(connect_pads
			(clearance 0)
		)
		(min_thickness 0.25)
		(keepout
			(tracks not_allowed)
			(vias allowed)
			(pads allowed)
			(copperpour not_allowed)
			(footprints allowed)
		)
		(placement
			(enabled no)
			(sheetname "")
		)
		(fill
			(thermal_gap 0.5)
			(thermal_bridge_width 0.5)
			(island_removal_mode 0)
		)
		(polygon
			(pts
				(arc
					(start 48.533304 -234.132374)
					(mid 48.529584 -234.141354)
					(end 48.520604 -234.145074)
				)
				(arc
					(start 47.047404 -234.145074)
					(mid 47.038424 -234.141354)
					(end 47.034704 -234.132374)
				)
				(arc
					(start 47.034704 -233.637836)
					(mid 47.038424 -233.628856)
					(end 47.047404 -233.625136)
				)
				(arc
					(start 48.520604 -233.625136)
					(mid 48.529584 -233.628856)
					(end 48.533304 -233.637836)
				)
			)
		)
	)
	(zone
		(layer "In1.Cu")
		(hatch none 0.5)
		(connect_pads
			(clearance 0)
		)
		(min_thickness 0.25)
		(keepout
			(tracks not_allowed)
			(vias allowed)
			(pads allowed)
			(copperpour not_allowed)
			(footprints allowed)
		)
		(placement
			(enabled no)
			(sheetname "")
		)
		(fill
			(thermal_gap 0.5)
			(thermal_bridge_width 0.5)
			(island_removal_mode 0)
		)
		(polygon
			(pts
				(arc
					(start 447.393568 -200.982326)
					(mid 447.389848 -200.991306)
					(end 447.380868 -200.995026)
				)
				(arc
					(start 445.907668 -200.995026)
					(mid 445.898688 -200.991306)
					(end 445.894968 -200.982326)
				)
				(arc
					(start 445.894968 -200.487788)
					(mid 445.898688 -200.478808)
					(end 445.907668 -200.475088)
				)
				(arc
					(start 447.380868 -200.475088)
					(mid 447.389848 -200.478808)
					(end 447.393568 -200.487788)
				)
			)
		)
	)
	(zone
		(layer "In1.Cu")
		(hatch none 0.5)
		(connect_pads
			(clearance 0)
		)
		(min_thickness 0.25)
		(keepout
			(tracks not_allowed)
			(vias allowed)
			(pads allowed)
			(copperpour not_allowed)
			(footprints allowed)
		)
		(placement
			(enabled no)
			(sheetname "")
		)
		(fill
			(thermal_gap 0.5)
			(thermal_bridge_width 0.5)
			(island_removal_mode 0)
		)
		(polygon
			(pts
				(arc
					(start 435.749446 -198.432166)
					(mid 435.745726 -198.441146)
					(end 435.736746 -198.444866)
				)
				(arc
					(start 434.263546 -198.444866)
					(mid 434.254566 -198.441146)
					(end 434.250846 -198.432166)
				)
				(arc
					(start 434.250846 -197.937628)
					(mid 434.254566 -197.928648)
					(end 434.263546 -197.924928)
				)
				(arc
					(start 435.736746 -197.924928)
					(mid 435.745726 -197.928648)
					(end 435.749446 -197.937628)
				)
			)
		)
	)
	(zone
		(layer "In1.Cu")
		(hatch none 0.5)
		(connect_pads
			(clearance 0)
		)
		(min_thickness 0.25)
		(keepout
			(tracks not_allowed)
			(vias allowed)
			(pads allowed)
			(copperpour not_allowed)
			(footprints allowed)
		)
		(placement
			(enabled no)
			(sheetname "")
		)
		(fill
			(thermal_gap 0.5)
			(thermal_bridge_width 0.5)
			(island_removal_mode 0)
		)
		(polygon
			(pts
				(arc
					(start 305.390804 -391.822686)
					(mid 305.517804 -391.949686)
					(end 305.644804 -391.822686)
				)
				(arc
					(start 305.644804 -391.746486)
					(mid 305.517804 -391.619486)
					(end 305.390804 -391.746486)
				)
			)
		)
	)
	(zone
		(layer "In1.Cu")
		(hatch none 0.5)
		(connect_pads
			(clearance 0)
		)
		(min_thickness 0.25)
		(keepout
			(tracks not_allowed)
			(vias allowed)
			(pads allowed)
			(copperpour not_allowed)
			(footprints allowed)
		)
		(placement
			(enabled no)
			(sheetname "")
		)
		(fill
			(thermal_gap 0.5)
			(thermal_bridge_width 0.5)
			(island_removal_mode 0)
		)
		(polygon
			(pts
				(arc
					(start 51.791108 -391.319258)
					(mid 51.918108 -391.446258)
					(end 52.045108 -391.319258)
				)
				(arc
					(start 52.045108 -391.243058)
					(mid 51.918108 -391.116058)
					(end 51.791108 -391.243058)
				)
			)
		)
	)
	(zone
		(layer "In1.Cu")
		(hatch none 0.5)
		(connect_pads
			(clearance 0)
		)
		(min_thickness 0.25)
		(keepout
			(tracks not_allowed)
			(vias allowed)
			(pads allowed)
			(copperpour not_allowed)
			(footprints allowed)
		)
		(placement
			(enabled no)
			(sheetname "")
		)
		(fill
			(thermal_gap 0.5)
			(thermal_bridge_width 0.5)
			(island_removal_mode 0)
		)
		(polygon
			(pts
				(arc
					(start 345.118436 -391.822686)
					(mid 345.245436 -391.949686)
					(end 345.372436 -391.822686)
				)
				(arc
					(start 345.372436 -391.746486)
					(mid 345.245436 -391.619486)
					(end 345.118436 -391.746486)
				)
			)
		)
	)
	(zone
		(layer "In1.Cu")
		(hatch none 0.5)
		(connect_pads
			(clearance 0)
		)
		(min_thickness 0.25)
		(keepout
			(tracks not_allowed)
			(vias allowed)
			(pads allowed)
			(copperpour not_allowed)
			(footprints allowed)
		)
		(placement
			(enabled no)
			(sheetname "")
		)
		(fill
			(thermal_gap 0.5)
			(thermal_bridge_width 0.5)
			(island_removal_mode 0)
		)
		(polygon
			(pts
				(arc
					(start 187.809378 -267.282422)
					(mid 187.805658 -267.291402)
					(end 187.796678 -267.295122)
				)
				(arc
					(start 186.323478 -267.295122)
					(mid 186.314498 -267.291402)
					(end 186.310778 -267.282422)
				)
				(arc
					(start 186.310778 -266.787884)
					(mid 186.314498 -266.778904)
					(end 186.323478 -266.775184)
				)
				(arc
					(start 187.796678 -266.775184)
					(mid 187.805658 -266.778904)
					(end 187.809378 -266.787884)
				)
			)
		)
	)
	(zone
		(layer "In1.Cu")
		(hatch none 0.5)
		(connect_pads
			(clearance 0)
		)
		(min_thickness 0.25)
		(keepout
			(tracks not_allowed)
			(vias allowed)
			(pads allowed)
			(copperpour not_allowed)
			(footprints allowed)
		)
		(placement
			(enabled no)
			(sheetname "")
		)
		(fill
			(thermal_gap 0.5)
			(thermal_bridge_width 0.5)
			(island_removal_mode 0)
		)
		(polygon
			(pts
				(arc
					(start 424.761406 -197.582282)
					(mid 424.757686 -197.591262)
					(end 424.748706 -197.594982)
				)
				(arc
					(start 423.275506 -197.594982)
					(mid 423.266526 -197.591262)
					(end 423.262806 -197.582282)
				)
				(arc
					(start 423.262806 -197.087744)
					(mid 423.266526 -197.078764)
					(end 423.275506 -197.075044)
				)
				(arc
					(start 424.748706 -197.075044)
					(mid 424.757686 -197.078764)
					(end 424.761406 -197.087744)
				)
			)
		)
	)
	(zone
		(layer "In1.Cu")
		(hatch none 0.5)
		(connect_pads
			(clearance 0)
		)
		(min_thickness 0.25)
		(keepout
			(tracks not_allowed)
			(vias allowed)
			(pads allowed)
			(copperpour not_allowed)
			(footprints allowed)
		)
		(placement
			(enabled no)
			(sheetname "")
		)
		(fill
			(thermal_gap 0.5)
			(thermal_bridge_width 0.5)
			(island_removal_mode 0)
		)
		(polygon
			(pts
				(arc
					(start 265.87831 -285.735014)
					(mid 265.21791 -285.735014)
					(end 265.87831 -285.735014)
				)
			)
		)
	)
	(zone
		(layer "In1.Cu")
		(hatch none 0.5)
		(connect_pads
			(clearance 0)
		)
		(min_thickness 0.25)
		(keepout
			(tracks not_allowed)
			(vias allowed)
			(pads allowed)
			(copperpour not_allowed)
			(footprints allowed)
		)
		(placement
			(enabled no)
			(sheetname "")
		)
		(fill
			(thermal_gap 0.5)
			(thermal_bridge_width 0.5)
			(island_removal_mode 0)
		)
		(polygon
			(pts
				(arc
					(start 265.87831 -221.13494)
					(mid 265.21791 -221.13494)
					(end 265.87831 -221.13494)
				)
			)
		)
	)
	(zone
		(layer "In1.Cu")
		(hatch none 0.5)
		(connect_pads
			(clearance 0)
		)
		(min_thickness 0.25)
		(keepout
			(tracks not_allowed)
			(vias allowed)
			(pads allowed)
			(copperpour not_allowed)
			(footprints allowed)
		)
		(placement
			(enabled no)
			(sheetname "")
		)
		(fill
			(thermal_gap 0.5)
			(thermal_bridge_width 0.5)
			(island_removal_mode 0)
		)
		(polygon
			(pts
				(arc
					(start 47.576994 -408.860244)
					(mid 47.599312 -408.914126)
					(end 47.653194 -408.936444)
				)
				(arc
					(start 47.848774 -408.936444)
					(mid 47.87065 -408.933312)
					(end 47.890684 -408.923998)
				)
				(arc
					(start 48.184308 -408.731466)
					(mid 48.225964 -408.719064)
					(end 48.26762 -408.731466)
				)
				(arc
					(start 48.562514 -408.923998)
					(mid 48.582438 -408.933234)
					(end 48.60417 -408.936444)
				)
				(arc
					(start 48.798734 -408.936444)
					(mid 48.852616 -408.914126)
					(end 48.874934 -408.860244)
				)
				(arc
					(start 48.874934 -408.174444)
					(mid 48.852616 -408.120562)
					(end 48.798734 -408.098244)
				)
				(arc
					(start 48.60417 -408.098244)
					(mid 48.582426 -408.101412)
					(end 48.562514 -408.11069)
				)
				(arc
					(start 48.26635 -408.303476)
					(mid 48.224666 -408.315698)
					(end 48.183038 -408.303222)
				)
				(arc
					(start 47.889414 -408.11069)
					(mid 47.86949 -408.101454)
					(end 47.847758 -408.098244)
				)
				(arc
					(start 47.653194 -408.098244)
					(mid 47.599312 -408.120562)
					(end 47.576994 -408.174444)
				)
			)
		)
	)
	(zone
		(layer "In1.Cu")
		(hatch none 0.5)
		(connect_pads
			(clearance 0)
		)
		(min_thickness 0.25)
		(keepout
			(tracks not_allowed)
			(vias allowed)
			(pads allowed)
			(copperpour not_allowed)
			(footprints allowed)
		)
		(placement
			(enabled no)
			(sheetname "")
		)
		(fill
			(thermal_gap 0.5)
			(thermal_bridge_width 0.5)
			(island_removal_mode 0)
		)
		(polygon
			(pts
				(arc
					(start 439.849514 -281.732228)
					(mid 439.845794 -281.741208)
					(end 439.836814 -281.744928)
				)
				(arc
					(start 438.363614 -281.744928)
					(mid 438.354634 -281.741208)
					(end 438.350914 -281.732228)
				)
				(arc
					(start 438.350914 -281.23769)
					(mid 438.354634 -281.22871)
					(end 438.363614 -281.22499)
				)
				(arc
					(start 439.836814 -281.22499)
					(mid 439.845794 -281.22871)
					(end 439.849514 -281.23769)
				)
			)
		)
	)
	(zone
		(layer "In1.Cu")
		(hatch none 0.5)
		(connect_pads
			(clearance 0)
		)
		(min_thickness 0.25)
		(keepout
			(tracks not_allowed)
			(vias allowed)
			(pads allowed)
			(copperpour not_allowed)
			(footprints allowed)
		)
		(placement
			(enabled no)
			(sheetname "")
		)
		(fill
			(thermal_gap 0.5)
			(thermal_bridge_width 0.5)
			(island_removal_mode 0)
		)
		(polygon
			(pts
				(arc
					(start 25.901396 -274.932394)
					(mid 25.897676 -274.941374)
					(end 25.888696 -274.945094)
				)
				(arc
					(start 24.415496 -274.945094)
					(mid 24.406516 -274.941374)
					(end 24.402796 -274.932394)
				)
				(arc
					(start 24.402796 -274.437856)
					(mid 24.406516 -274.428876)
					(end 24.415496 -274.425156)
				)
				(arc
					(start 25.888696 -274.425156)
					(mid 25.897676 -274.428876)
					(end 25.901396 -274.437856)
				)
			)
		)
	)
	(zone
		(layer "In1.Cu")
		(hatch none 0.5)
		(connect_pads
			(clearance 0)
		)
		(min_thickness 0.25)
		(keepout
			(tracks not_allowed)
			(vias allowed)
			(pads allowed)
			(copperpour not_allowed)
			(footprints allowed)
		)
		(placement
			(enabled no)
			(sheetname "")
		)
		(fill
			(thermal_gap 0.5)
			(thermal_bridge_width 0.5)
			(island_removal_mode 0)
		)
		(polygon
			(pts
				(arc
					(start 191.909446 -292.782498)
					(mid 191.905726 -292.791478)
					(end 191.896746 -292.795198)
				)
				(arc
					(start 190.423546 -292.795198)
					(mid 190.414566 -292.791478)
					(end 190.410846 -292.782498)
				)
				(arc
					(start 190.410846 -292.28796)
					(mid 190.414566 -292.27898)
					(end 190.423546 -292.27526)
				)
				(arc
					(start 191.896746 -292.27526)
					(mid 191.905726 -292.27898)
					(end 191.909446 -292.28796)
				)
			)
		)
	)
	(zone
		(layer "In1.Cu")
		(hatch none 0.5)
		(connect_pads
			(clearance 0)
		)
		(min_thickness 0.25)
		(keepout
			(tracks not_allowed)
			(vias allowed)
			(pads allowed)
			(copperpour not_allowed)
			(footprints allowed)
		)
		(placement
			(enabled no)
			(sheetname "")
		)
		(fill
			(thermal_gap 0.5)
			(thermal_bridge_width 0.5)
			(island_removal_mode 0)
		)
		(polygon
			(pts
				(arc
					(start 176.821338 -280.03246)
					(mid 176.817618 -280.04144)
					(end 176.808638 -280.04516)
				)
				(arc
					(start 175.335438 -280.04516)
					(mid 175.326458 -280.04144)
					(end 175.322738 -280.03246)
				)
				(arc
					(start 175.322738 -279.537922)
					(mid 175.326458 -279.528942)
					(end 175.335438 -279.525222)
				)
				(arc
					(start 176.808638 -279.525222)
					(mid 176.817618 -279.528942)
					(end 176.821338 -279.537922)
				)
			)
		)
	)
	(zone
		(layer "In1.Cu")
		(hatch none 0.5)
		(connect_pads
			(clearance 0)
		)
		(min_thickness 0.25)
		(keepout
			(tracks not_allowed)
			(vias allowed)
			(pads allowed)
			(copperpour not_allowed)
			(footprints allowed)
		)
		(placement
			(enabled no)
			(sheetname "")
		)
		(fill
			(thermal_gap 0.5)
			(thermal_bridge_width 0.5)
			(island_removal_mode 0)
		)
		(polygon
			(pts
				(arc
					(start 281.385264 -209.482182)
					(mid 281.381544 -209.491162)
					(end 281.372564 -209.494882)
				)
				(arc
					(start 279.899364 -209.494882)
					(mid 279.890384 -209.491162)
					(end 279.886664 -209.482182)
				)
				(arc
					(start 279.886664 -208.987644)
					(mid 279.890384 -208.978664)
					(end 279.899364 -208.974944)
				)
				(arc
					(start 281.372564 -208.974944)
					(mid 281.381544 -208.978664)
					(end 281.385264 -208.987644)
				)
			)
		)
	)
	(zone
		(layer "In1.Cu")
		(hatch none 0.5)
		(connect_pads
			(clearance 0)
		)
		(min_thickness 0.25)
		(keepout
			(tracks not_allowed)
			(vias allowed)
			(pads allowed)
			(copperpour not_allowed)
			(footprints allowed)
		)
		(placement
			(enabled no)
			(sheetname "")
		)
		(fill
			(thermal_gap 0.5)
			(thermal_bridge_width 0.5)
			(island_removal_mode 0)
		)
		(polygon
			(pts
				(arc
					(start 169.277284 -295.332404)
					(mid 169.273564 -295.341384)
					(end 169.264584 -295.345104)
				)
				(arc
					(start 167.791384 -295.345104)
					(mid 167.782404 -295.341384)
					(end 167.778684 -295.332404)
				)
				(arc
					(start 167.778684 -294.837866)
					(mid 167.782404 -294.828886)
					(end 167.791384 -294.825166)
				)
				(arc
					(start 169.264584 -294.825166)
					(mid 169.273564 -294.828886)
					(end 169.277284 -294.837866)
				)
			)
		)
	)
	(zone
		(layer "In1.Cu")
		(hatch none 0.5)
		(connect_pads
			(clearance 0)
		)
		(min_thickness 0.25)
		(keepout
			(tracks not_allowed)
			(vias allowed)
			(pads allowed)
			(copperpour not_allowed)
			(footprints allowed)
		)
		(placement
			(enabled no)
			(sheetname "")
		)
		(fill
			(thermal_gap 0.5)
			(thermal_bridge_width 0.5)
			(island_removal_mode 0)
		)
		(polygon
			(pts
				(arc
					(start 293.029386 -275.782278)
					(mid 293.025666 -275.791258)
					(end 293.016686 -275.794978)
				)
				(arc
					(start 291.543486 -275.794978)
					(mid 291.534506 -275.791258)
					(end 291.530786 -275.782278)
				)
				(arc
					(start 291.530786 -275.28774)
					(mid 291.534506 -275.27876)
					(end 291.543486 -275.27504)
				)
				(arc
					(start 293.016686 -275.27504)
					(mid 293.025666 -275.27876)
					(end 293.029386 -275.28774)
				)
			)
		)
	)
	(zone
		(layer "In1.Cu")
		(hatch none 0.5)
		(connect_pads
			(clearance 0)
		)
		(min_thickness 0.25)
		(keepout
			(tracks not_allowed)
			(vias allowed)
			(pads allowed)
			(copperpour not_allowed)
			(footprints allowed)
		)
		(placement
			(enabled no)
			(sheetname "")
		)
		(fill
			(thermal_gap 0.5)
			(thermal_bridge_width 0.5)
			(island_removal_mode 0)
		)
		(polygon
			(pts
				(arc
					(start 418.797994 -392.30427)
					(mid 418.493194 -392.30427)
					(end 418.797994 -392.30427)
				)
			)
		)
	)
	(zone
		(layer "In1.Cu")
		(hatch none 0.5)
		(connect_pads
			(clearance 0)
		)
		(min_thickness 0.25)
		(keepout
			(tracks not_allowed)
			(vias allowed)
			(pads allowed)
			(copperpour not_allowed)
			(footprints allowed)
		)
		(placement
			(enabled no)
			(sheetname "")
		)
		(fill
			(thermal_gap 0.5)
			(thermal_bridge_width 0.5)
			(island_removal_mode 0)
		)
		(polygon
			(pts
				(arc
					(start 443.2935 -310.632094)
					(mid 443.28978 -310.641074)
					(end 443.2808 -310.644794)
				)
				(arc
					(start 441.8076 -310.644794)
					(mid 441.79862 -310.641074)
					(end 441.7949 -310.632094)
				)
				(arc
					(start 441.7949 -310.137556)
					(mid 441.79862 -310.128576)
					(end 441.8076 -310.124856)
				)
				(arc
					(start 443.2808 -310.124856)
					(mid 443.28978 -310.128576)
					(end 443.2935 -310.137556)
				)
			)
		)
	)
	(zone
		(layer "In1.Cu")
		(hatch none 0.5)
		(connect_pads
			(clearance 0)
		)
		(min_thickness 0.25)
		(keepout
			(tracks not_allowed)
			(vias allowed)
			(pads allowed)
			(copperpour not_allowed)
			(footprints allowed)
		)
		(placement
			(enabled no)
			(sheetname "")
		)
		(fill
			(thermal_gap 0.5)
			(thermal_bridge_width 0.5)
			(island_removal_mode 0)
		)
		(polygon
			(pts
				(arc
					(start 30.001464 -240.932462)
					(mid 29.997744 -240.941442)
					(end 29.988764 -240.945162)
				)
				(arc
					(start 28.515564 -240.945162)
					(mid 28.506584 -240.941442)
					(end 28.502864 -240.932462)
				)
				(arc
					(start 28.502864 -240.437924)
					(mid 28.506584 -240.428944)
					(end 28.515564 -240.425224)
				)
				(arc
					(start 29.988764 -240.425224)
					(mid 29.997744 -240.428944)
					(end 30.001464 -240.437924)
				)
			)
		)
	)
	(zone
		(layer "In1.Cu")
		(hatch none 0.5)
		(connect_pads
			(clearance 0)
		)
		(min_thickness 0.25)
		(keepout
			(tracks not_allowed)
			(vias allowed)
			(pads allowed)
			(copperpour not_allowed)
			(footprints allowed)
		)
		(placement
			(enabled no)
			(sheetname "")
		)
		(fill
			(thermal_gap 0.5)
			(thermal_bridge_width 0.5)
			(island_removal_mode 0)
		)
		(polygon
			(pts
				(arc
					(start 199.4535 -275.782532)
					(mid 199.44978 -275.791512)
					(end 199.4408 -275.795232)
				)
				(arc
					(start 197.9676 -275.795232)
					(mid 197.95862 -275.791512)
					(end 197.9549 -275.782532)
				)
				(arc
					(start 197.9549 -275.287994)
					(mid 197.95862 -275.279014)
					(end 197.9676 -275.275294)
				)
				(arc
					(start 199.4408 -275.275294)
					(mid 199.44978 -275.279014)
					(end 199.4535 -275.287994)
				)
			)
		)
	)
	(zone
		(layer "In1.Cu")
		(hatch none 0.5)
		(connect_pads
			(clearance 0)
		)
		(min_thickness 0.25)
		(keepout
			(tracks not_allowed)
			(vias allowed)
			(pads allowed)
			(copperpour not_allowed)
			(footprints allowed)
		)
		(placement
			(enabled no)
			(sheetname "")
		)
		(fill
			(thermal_gap 0.5)
			(thermal_bridge_width 0.5)
			(island_removal_mode 0)
		)
		(polygon
			(pts
				(arc
					(start 435.749446 -223.082104)
					(mid 435.745726 -223.091084)
					(end 435.736746 -223.094804)
				)
				(arc
					(start 434.263546 -223.094804)
					(mid 434.254566 -223.091084)
					(end 434.250846 -223.082104)
				)
				(arc
					(start 434.250846 -222.587566)
					(mid 434.254566 -222.578586)
					(end 434.263546 -222.574866)
				)
				(arc
					(start 435.736746 -222.574866)
					(mid 435.745726 -222.578586)
					(end 435.749446 -222.587566)
				)
			)
		)
	)
	(zone
		(layer "In1.Cu")
		(hatch none 0.5)
		(connect_pads
			(clearance 0)
		)
		(min_thickness 0.25)
		(keepout
			(tracks not_allowed)
			(vias allowed)
			(pads allowed)
			(copperpour not_allowed)
			(footprints allowed)
		)
		(placement
			(enabled no)
			(sheetname "")
		)
		(fill
			(thermal_gap 0.5)
			(thermal_bridge_width 0.5)
			(island_removal_mode 0)
		)
		(polygon
			(pts
				(arc
					(start 265.87831 -229.63505)
					(mid 265.21791 -229.63505)
					(end 265.87831 -229.63505)
				)
			)
		)
	)
	(zone
		(layer "In1.Cu")
		(hatch none 0.5)
		(connect_pads
			(clearance 0)
		)
		(min_thickness 0.25)
		(keepout
			(tracks not_allowed)
			(vias allowed)
			(pads allowed)
			(copperpour not_allowed)
			(footprints allowed)
		)
		(placement
			(enabled no)
			(sheetname "")
		)
		(fill
			(thermal_gap 0.5)
			(thermal_bridge_width 0.5)
			(island_removal_mode 0)
		)
		(polygon
			(pts
				(arc
					(start 404.397972 -392.30427)
					(mid 404.093172 -392.30427)
					(end 404.397972 -392.30427)
				)
			)
		)
	)
	(zone
		(layer "In1.Cu")
		(hatch none 0.5)
		(connect_pads
			(clearance 0)
		)
		(min_thickness 0.25)
		(keepout
			(tracks not_allowed)
			(vias allowed)
			(pads allowed)
			(copperpour not_allowed)
			(footprints allowed)
		)
		(placement
			(enabled no)
			(sheetname "")
		)
		(fill
			(thermal_gap 0.5)
			(thermal_bridge_width 0.5)
			(island_removal_mode 0)
		)
		(polygon
			(pts
				(arc
					(start 148.397976 -390.761474)
					(mid 148.093176 -390.761474)
					(end 148.397976 -390.761474)
				)
			)
		)
	)
	(zone
		(layer "In1.Cu")
		(hatch none 0.5)
		(connect_pads
			(clearance 0)
		)
		(min_thickness 0.25)
		(keepout
			(tracks not_allowed)
			(vias allowed)
			(pads allowed)
			(copperpour not_allowed)
			(footprints allowed)
		)
		(placement
			(enabled no)
			(sheetname "")
		)
		(fill
			(thermal_gap 0.5)
			(thermal_bridge_width 0.5)
			(island_removal_mode 0)
		)
		(polygon
			(pts
				(arc
					(start 191.909446 -274.08251)
					(mid 191.905726 -274.09149)
					(end 191.896746 -274.09521)
				)
				(arc
					(start 190.423546 -274.09521)
					(mid 190.414566 -274.09149)
					(end 190.410846 -274.08251)
				)
				(arc
					(start 190.410846 -273.587972)
					(mid 190.414566 -273.578992)
					(end 190.423546 -273.575272)
				)
				(arc
					(start 191.896746 -273.575272)
					(mid 191.905726 -273.578992)
					(end 191.909446 -273.587972)
				)
			)
		)
	)
	(zone
		(layer "In1.Cu")
		(hatch none 0.5)
		(connect_pads
			(clearance 0)
		)
		(min_thickness 0.25)
		(keepout
			(tracks not_allowed)
			(vias allowed)
			(pads allowed)
			(copperpour not_allowed)
			(footprints allowed)
		)
		(placement
			(enabled no)
			(sheetname "")
		)
		(fill
			(thermal_gap 0.5)
			(thermal_bridge_width 0.5)
			(island_removal_mode 0)
		)
		(polygon
			(pts
				(arc
					(start 285.485332 -311.482232)
					(mid 285.481612 -311.491212)
					(end 285.472632 -311.494932)
				)
				(arc
					(start 283.999432 -311.494932)
					(mid 283.990452 -311.491212)
					(end 283.986732 -311.482232)
				)
				(arc
					(start 283.986732 -310.987694)
					(mid 283.990452 -310.978714)
					(end 283.999432 -310.974994)
				)
				(arc
					(start 285.472632 -310.974994)
					(mid 285.481612 -310.978714)
					(end 285.485332 -310.987694)
				)
			)
		)
	)
	(zone
		(layer "In1.Cu")
		(hatch none 0.5)
		(connect_pads
			(clearance 0)
		)
		(min_thickness 0.25)
		(keepout
			(tracks not_allowed)
			(vias allowed)
			(pads allowed)
			(copperpour not_allowed)
			(footprints allowed)
		)
		(placement
			(enabled no)
			(sheetname "")
		)
		(fill
			(thermal_gap 0.5)
			(thermal_bridge_width 0.5)
			(island_removal_mode 0)
		)
		(polygon
			(pts
				(arc
					(start 63.061342 -388.774432)
					(mid 62.680342 -388.774432)
					(end 63.061342 -388.774432)
				)
			)
		)
	)
	(zone
		(layer "In1.Cu")
		(hatch none 0.5)
		(connect_pads
			(clearance 0)
		)
		(min_thickness 0.25)
		(keepout
			(tracks not_allowed)
			(vias allowed)
			(pads allowed)
			(copperpour not_allowed)
			(footprints allowed)
		)
		(placement
			(enabled no)
			(sheetname "")
		)
		(fill
			(thermal_gap 0.5)
			(thermal_bridge_width 0.5)
			(island_removal_mode 0)
		)
		(polygon
			(pts
				(arc
					(start 206.5782 -252.58522)
					(mid 205.9178 -252.58522)
					(end 206.5782 -252.58522)
				)
			)
		)
	)
	(zone
		(layer "In1.Cu")
		(hatch none 0.5)
		(connect_pads
			(clearance 0)
		)
		(min_thickness 0.25)
		(keepout
			(tracks not_allowed)
			(vias allowed)
			(pads allowed)
			(copperpour not_allowed)
			(footprints allowed)
		)
		(placement
			(enabled no)
			(sheetname "")
		)
		(fill
			(thermal_gap 0.5)
			(thermal_bridge_width 0.5)
			(island_removal_mode 0)
		)
		(polygon
			(pts
				(arc
					(start 454.937368 -287.682178)
					(mid 454.933648 -287.691158)
					(end 454.924668 -287.694878)
				)
				(arc
					(start 453.451468 -287.694878)
					(mid 453.442488 -287.691158)
					(end 453.438768 -287.682178)
				)
				(arc
					(start 453.438768 -287.18764)
					(mid 453.442488 -287.17866)
					(end 453.451468 -287.17494)
				)
				(arc
					(start 454.924668 -287.17494)
					(mid 454.933648 -287.17866)
					(end 454.937368 -287.18764)
				)
			)
		)
	)
	(zone
		(layer "In1.Cu")
		(hatch none 0.5)
		(connect_pads
			(clearance 0)
		)
		(min_thickness 0.25)
		(keepout
			(tracks not_allowed)
			(vias allowed)
			(pads allowed)
			(copperpour not_allowed)
			(footprints allowed)
		)
		(placement
			(enabled no)
			(sheetname "")
		)
		(fill
			(thermal_gap 0.5)
			(thermal_bridge_width 0.5)
			(island_removal_mode 0)
		)
		(polygon
			(pts
				(arc
					(start 172.72127 -200.132442)
					(mid 172.71755 -200.141422)
					(end 172.70857 -200.145142)
				)
				(arc
					(start 171.23537 -200.145142)
					(mid 171.22639 -200.141422)
					(end 171.22267 -200.132442)
				)
				(arc
					(start 171.22267 -199.637904)
					(mid 171.22639 -199.628924)
					(end 171.23537 -199.625204)
				)
				(arc
					(start 172.70857 -199.625204)
					(mid 172.71755 -199.628924)
					(end 172.72127 -199.637904)
				)
			)
		)
	)
	(zone
		(layer "In1.Cu")
		(hatch none 0.5)
		(connect_pads
			(clearance 0)
		)
		(min_thickness 0.25)
		(keepout
			(tracks not_allowed)
			(vias allowed)
			(pads allowed)
			(copperpour not_allowed)
			(footprints allowed)
		)
		(placement
			(enabled no)
			(sheetname "")
		)
		(fill
			(thermal_gap 0.5)
			(thermal_bridge_width 0.5)
			(island_removal_mode 0)
		)
		(polygon
			(pts
				(arc
					(start 52.633372 -238.382556)
					(mid 52.629652 -238.391536)
					(end 52.620672 -238.395256)
				)
				(arc
					(start 51.147472 -238.395256)
					(mid 51.138492 -238.391536)
					(end 51.134772 -238.382556)
				)
				(arc
					(start 51.134772 -237.888018)
					(mid 51.138492 -237.879038)
					(end 51.147472 -237.875318)
				)
				(arc
					(start 52.620672 -237.875318)
					(mid 52.629652 -237.879038)
					(end 52.633372 -237.888018)
				)
			)
		)
	)
	(zone
		(layer "In1.Cu")
		(hatch none 0.5)
		(connect_pads
			(clearance 0)
		)
		(min_thickness 0.25)
		(keepout
			(tracks not_allowed)
			(vias allowed)
			(pads allowed)
			(copperpour not_allowed)
			(footprints allowed)
		)
		(placement
			(enabled no)
			(sheetname "")
		)
		(fill
			(thermal_gap 0.5)
			(thermal_bridge_width 0.5)
			(island_removal_mode 0)
		)
		(polygon
			(pts
				(arc
					(start 281.385264 -267.282168)
					(mid 281.381544 -267.291148)
					(end 281.372564 -267.294868)
				)
				(arc
					(start 279.899364 -267.294868)
					(mid 279.890384 -267.291148)
					(end 279.886664 -267.282168)
				)
				(arc
					(start 279.886664 -266.78763)
					(mid 279.890384 -266.77865)
					(end 279.899364 -266.77493)
				)
				(arc
					(start 281.372564 -266.77493)
					(mid 281.381544 -266.77865)
					(end 281.385264 -266.78763)
				)
			)
		)
	)
	(zone
		(layer "In1.Cu")
		(hatch none 0.5)
		(connect_pads
			(clearance 0)
		)
		(min_thickness 0.25)
		(keepout
			(tracks not_allowed)
			(vias allowed)
			(pads allowed)
			(copperpour not_allowed)
			(footprints allowed)
		)
		(placement
			(enabled no)
			(sheetname "")
		)
		(fill
			(thermal_gap 0.5)
			(thermal_bridge_width 0.5)
			(island_removal_mode 0)
		)
		(polygon
			(pts
				(arc
					(start 165.177216 -215.432386)
					(mid 165.173496 -215.441366)
					(end 165.164516 -215.445086)
				)
				(arc
					(start 163.691316 -215.445086)
					(mid 163.682336 -215.441366)
					(end 163.678616 -215.432386)
				)
				(arc
					(start 163.678616 -214.937848)
					(mid 163.682336 -214.928868)
					(end 163.691316 -214.925148)
				)
				(arc
					(start 165.164516 -214.925148)
					(mid 165.173496 -214.928868)
					(end 165.177216 -214.937848)
				)
			)
		)
	)
	(zone
		(layer "In1.Cu")
		(hatch none 0.5)
		(connect_pads
			(clearance 0)
		)
		(min_thickness 0.25)
		(keepout
			(tracks not_allowed)
			(vias allowed)
			(pads allowed)
			(copperpour not_allowed)
			(footprints allowed)
		)
		(placement
			(enabled no)
			(sheetname "")
		)
		(fill
			(thermal_gap 0.5)
			(thermal_bridge_width 0.5)
			(island_removal_mode 0)
		)
		(polygon
			(pts
				(arc
					(start 123.690888 -383.440686)
					(mid 123.817888 -383.567686)
					(end 123.944888 -383.440686)
				)
				(arc
					(start 123.944888 -383.364486)
					(mid 123.817888 -383.237486)
					(end 123.690888 -383.364486)
				)
			)
		)
	)
	(zone
		(layer "In1.Cu")
		(hatch none 0.5)
		(connect_pads
			(clearance 0)
		)
		(min_thickness 0.25)
		(keepout
			(tracks not_allowed)
			(vias allowed)
			(pads allowed)
			(copperpour not_allowed)
			(footprints allowed)
		)
		(placement
			(enabled no)
			(sheetname "")
		)
		(fill
			(thermal_gap 0.5)
			(thermal_bridge_width 0.5)
			(island_removal_mode 0)
		)
		(polygon
			(pts
				(arc
					(start 33.445196 -277.482554)
					(mid 33.441476 -277.491534)
					(end 33.432496 -277.495254)
				)
				(arc
					(start 31.959296 -277.495254)
					(mid 31.950316 -277.491534)
					(end 31.946596 -277.482554)
				)
				(arc
					(start 31.946596 -276.988016)
					(mid 31.950316 -276.979036)
					(end 31.959296 -276.975316)
				)
				(arc
					(start 33.432496 -276.975316)
					(mid 33.441476 -276.979036)
					(end 33.445196 -276.988016)
				)
			)
		)
	)
	(zone
		(layer "In1.Cu")
		(hatch none 0.5)
		(connect_pads
			(clearance 0)
		)
		(min_thickness 0.25)
		(keepout
			(tracks not_allowed)
			(vias allowed)
			(pads allowed)
			(copperpour not_allowed)
			(footprints allowed)
		)
		(placement
			(enabled no)
			(sheetname "")
		)
		(fill
			(thermal_gap 0.5)
			(thermal_bridge_width 0.5)
			(island_removal_mode 0)
		)
		(polygon
			(pts
				(arc
					(start 18.357342 -246.882412)
					(mid 18.353622 -246.891392)
					(end 18.344642 -246.895112)
				)
				(arc
					(start 16.871442 -246.895112)
					(mid 16.862462 -246.891392)
					(end 16.858742 -246.882412)
				)
				(arc
					(start 16.858742 -246.387874)
					(mid 16.862462 -246.378894)
					(end 16.871442 -246.375174)
				)
				(arc
					(start 18.344642 -246.375174)
					(mid 18.353622 -246.378894)
					(end 18.357342 -246.387874)
				)
			)
		)
	)
	(zone
		(layer "In1.Cu")
		(hatch none 0.5)
		(connect_pads
			(clearance 0)
		)
		(min_thickness 0.25)
		(keepout
			(tracks not_allowed)
			(vias allowed)
			(pads allowed)
			(copperpour not_allowed)
			(footprints allowed)
		)
		(placement
			(enabled no)
			(sheetname "")
		)
		(fill
			(thermal_gap 0.5)
			(thermal_bridge_width 0.5)
			(island_removal_mode 0)
		)
		(polygon
			(pts
				(arc
					(start 206.9973 -302.132492)
					(mid 206.99358 -302.141472)
					(end 206.9846 -302.145192)
				)
				(arc
					(start 205.5114 -302.145192)
					(mid 205.50242 -302.141472)
					(end 205.4987 -302.132492)
				)
				(arc
					(start 205.4987 -301.637954)
					(mid 205.50242 -301.628974)
					(end 205.5114 -301.625254)
				)
				(arc
					(start 206.9846 -301.625254)
					(mid 206.99358 -301.628974)
					(end 206.9973 -301.637954)
				)
			)
		)
	)
	(zone
		(layer "In1.Cu")
		(hatch none 0.5)
		(connect_pads
			(clearance 0)
		)
		(min_thickness 0.25)
		(keepout
			(tracks not_allowed)
			(vias allowed)
			(pads allowed)
			(copperpour not_allowed)
			(footprints allowed)
		)
		(placement
			(enabled no)
			(sheetname "")
		)
		(fill
			(thermal_gap 0.5)
			(thermal_bridge_width 0.5)
			(island_removal_mode 0)
		)
		(polygon
			(pts
				(arc
					(start 176.821338 -269.832582)
					(mid 176.817618 -269.841562)
					(end 176.808638 -269.845282)
				)
				(arc
					(start 175.335438 -269.845282)
					(mid 175.326458 -269.841562)
					(end 175.322738 -269.832582)
				)
				(arc
					(start 175.322738 -269.338044)
					(mid 175.326458 -269.329064)
					(end 175.335438 -269.325344)
				)
				(arc
					(start 176.808638 -269.325344)
					(mid 176.817618 -269.329064)
					(end 176.821338 -269.338044)
				)
			)
		)
	)
	(zone
		(layer "In1.Cu")
		(hatch none 0.5)
		(connect_pads
			(clearance 0)
		)
		(min_thickness 0.25)
		(keepout
			(tracks not_allowed)
			(vias allowed)
			(pads allowed)
			(copperpour not_allowed)
			(footprints allowed)
		)
		(placement
			(enabled no)
			(sheetname "")
		)
		(fill
			(thermal_gap 0.5)
			(thermal_bridge_width 0.5)
			(island_removal_mode 0)
		)
		(polygon
			(pts
				(arc
					(start 376.670316 -392.30427)
					(mid 376.365516 -392.30427)
					(end 376.670316 -392.30427)
				)
			)
		)
	)
	(zone
		(layer "In1.Cu")
		(hatch none 0.5)
		(connect_pads
			(clearance 0)
		)
		(min_thickness 0.25)
		(keepout
			(tracks not_allowed)
			(vias allowed)
			(pads allowed)
			(copperpour not_allowed)
			(footprints allowed)
		)
		(placement
			(enabled no)
			(sheetname "")
		)
		(fill
			(thermal_gap 0.5)
			(thermal_bridge_width 0.5)
			(island_removal_mode 0)
		)
		(polygon
			(pts
				(arc
					(start 403.08911 -397.156432)
					(mid 402.70811 -397.156432)
					(end 403.08911 -397.156432)
				)
			)
		)
	)
	(zone
		(layer "In1.Cu")
		(hatch none 0.5)
		(connect_pads
			(clearance 0)
		)
		(min_thickness 0.25)
		(keepout
			(tracks not_allowed)
			(vias allowed)
			(pads allowed)
			(copperpour not_allowed)
			(footprints allowed)
		)
		(placement
			(enabled no)
			(sheetname "")
		)
		(fill
			(thermal_gap 0.5)
			(thermal_bridge_width 0.5)
			(island_removal_mode 0)
		)
		(polygon
			(pts
				(arc
					(start 447.393568 -294.482266)
					(mid 447.389848 -294.491246)
					(end 447.380868 -294.494966)
				)
				(arc
					(start 445.907668 -294.494966)
					(mid 445.898688 -294.491246)
					(end 445.894968 -294.482266)
				)
				(arc
					(start 445.894968 -293.987728)
					(mid 445.898688 -293.978748)
					(end 445.907668 -293.975028)
				)
				(arc
					(start 447.380868 -293.975028)
					(mid 447.389848 -293.978748)
					(end 447.393568 -293.987728)
				)
			)
		)
	)
	(zone
		(layer "In1.Cu")
		(hatch none 0.5)
		(connect_pads
			(clearance 0)
		)
		(min_thickness 0.25)
		(keepout
			(tracks not_allowed)
			(vias allowed)
			(pads allowed)
			(copperpour not_allowed)
			(footprints allowed)
		)
		(placement
			(enabled no)
			(sheetname "")
		)
		(fill
			(thermal_gap 0.5)
			(thermal_bridge_width 0.5)
			(island_removal_mode 0)
		)
		(polygon
			(pts
				(arc
					(start 40.98925 -246.882412)
					(mid 40.98553 -246.891392)
					(end 40.97655 -246.895112)
				)
				(arc
					(start 39.50335 -246.895112)
					(mid 39.49437 -246.891392)
					(end 39.49065 -246.882412)
				)
				(arc
					(start 39.49065 -246.387874)
					(mid 39.49437 -246.378894)
					(end 39.50335 -246.375174)
				)
				(arc
					(start 40.97655 -246.375174)
					(mid 40.98553 -246.378894)
					(end 40.98925 -246.387874)
				)
			)
		)
	)
	(zone
		(layer "In1.Cu")
		(hatch none 0.5)
		(connect_pads
			(clearance 0)
		)
		(min_thickness 0.25)
		(keepout
			(tracks not_allowed)
			(vias allowed)
			(pads allowed)
			(copperpour not_allowed)
			(footprints allowed)
		)
		(placement
			(enabled no)
			(sheetname "")
		)
		(fill
			(thermal_gap 0.5)
			(thermal_bridge_width 0.5)
			(island_removal_mode 0)
		)
		(polygon
			(pts
				(arc
					(start 115.870228 -390.761474)
					(mid 115.565428 -390.761474)
					(end 115.870228 -390.761474)
				)
			)
		)
	)
	(zone
		(layer "In1.Cu")
		(hatch none 0.5)
		(connect_pads
			(clearance 0)
		)
		(min_thickness 0.25)
		(keepout
			(tracks not_allowed)
			(vias allowed)
			(pads allowed)
			(copperpour not_allowed)
			(footprints allowed)
		)
		(placement
			(enabled no)
			(sheetname "")
		)
		(fill
			(thermal_gap 0.5)
			(thermal_bridge_width 0.5)
			(island_removal_mode 0)
		)
		(polygon
			(pts
				(arc
					(start 432.30546 -289.3822)
					(mid 432.30174 -289.39118)
					(end 432.29276 -289.3949)
				)
				(arc
					(start 430.81956 -289.3949)
					(mid 430.81058 -289.39118)
					(end 430.80686 -289.3822)
				)
				(arc
					(start 430.80686 -288.887662)
					(mid 430.81058 -288.878682)
					(end 430.81956 -288.874962)
				)
				(arc
					(start 432.29276 -288.874962)
					(mid 432.30174 -288.878682)
					(end 432.30546 -288.887662)
				)
			)
		)
	)
	(zone
		(layer "In1.Cu")
		(hatch none 0.5)
		(connect_pads
			(clearance 0)
		)
		(min_thickness 0.25)
		(keepout
			(tracks not_allowed)
			(vias allowed)
			(pads allowed)
			(copperpour not_allowed)
			(footprints allowed)
		)
		(placement
			(enabled no)
			(sheetname "")
		)
		(fill
			(thermal_gap 0.5)
			(thermal_bridge_width 0.5)
			(island_removal_mode 0)
		)
		(polygon
			(pts
				(arc
					(start 52.633372 -247.73255)
					(mid 52.629652 -247.74153)
					(end 52.620672 -247.74525)
				)
				(arc
					(start 51.147472 -247.74525)
					(mid 51.138492 -247.74153)
					(end 51.134772 -247.73255)
				)
				(arc
					(start 51.134772 -247.238012)
					(mid 51.138492 -247.229032)
					(end 51.147472 -247.225312)
				)
				(arc
					(start 52.620672 -247.225312)
					(mid 52.629652 -247.229032)
					(end 52.633372 -247.238012)
				)
			)
		)
	)
	(zone
		(layer "In1.Cu")
		(hatch none 0.5)
		(connect_pads
			(clearance 0)
		)
		(min_thickness 0.25)
		(keepout
			(tracks not_allowed)
			(vias allowed)
			(pads allowed)
			(copperpour not_allowed)
			(footprints allowed)
		)
		(placement
			(enabled no)
			(sheetname "")
		)
		(fill
			(thermal_gap 0.5)
			(thermal_bridge_width 0.5)
			(island_removal_mode 0)
		)
		(polygon
			(pts
				(arc
					(start 54.661308 -385.31038)
					(mid 54.280308 -385.31038)
					(end 54.661308 -385.31038)
				)
			)
		)
	)
	(zone
		(layer "In1.Cu")
		(hatch none 0.5)
		(connect_pads
			(clearance 0)
		)
		(min_thickness 0.25)
		(keepout
			(tracks not_allowed)
			(vias allowed)
			(pads allowed)
			(copperpour not_allowed)
			(footprints allowed)
		)
		(placement
			(enabled no)
			(sheetname "")
		)
		(fill
			(thermal_gap 0.5)
			(thermal_bridge_width 0.5)
			(island_removal_mode 0)
		)
		(polygon
			(pts
				(arc
					(start 308.117494 -242.63223)
					(mid 308.113774 -242.64121)
					(end 308.104794 -242.64493)
				)
				(arc
					(start 306.631594 -242.64493)
					(mid 306.622614 -242.64121)
					(end 306.618894 -242.63223)
				)
				(arc
					(start 306.618894 -242.137692)
					(mid 306.622614 -242.128712)
					(end 306.631594 -242.124992)
				)
				(arc
					(start 308.104794 -242.124992)
					(mid 308.113774 -242.128712)
					(end 308.117494 -242.137692)
				)
			)
		)
	)
	(zone
		(layer "In1.Cu")
		(hatch none 0.5)
		(connect_pads
			(clearance 0)
		)
		(min_thickness 0.25)
		(keepout
			(tracks not_allowed)
			(vias allowed)
			(pads allowed)
			(copperpour not_allowed)
			(footprints allowed)
		)
		(placement
			(enabled no)
			(sheetname "")
		)
		(fill
			(thermal_gap 0.5)
			(thermal_bridge_width 0.5)
			(island_removal_mode 0)
		)
		(polygon
			(pts
				(arc
					(start 454.937368 -283.43225)
					(mid 454.933648 -283.44123)
					(end 454.924668 -283.44495)
				)
				(arc
					(start 453.451468 -283.44495)
					(mid 453.442488 -283.44123)
					(end 453.438768 -283.43225)
				)
				(arc
					(start 453.438768 -282.937712)
					(mid 453.442488 -282.928732)
					(end 453.451468 -282.925012)
				)
				(arc
					(start 454.924668 -282.925012)
					(mid 454.933648 -282.928732)
					(end 454.937368 -282.937712)
				)
			)
		)
	)
	(zone
		(layer "In1.Cu")
		(hatch none 0.5)
		(connect_pads
			(clearance 0)
		)
		(min_thickness 0.25)
		(keepout
			(tracks not_allowed)
			(vias allowed)
			(pads allowed)
			(copperpour not_allowed)
			(footprints allowed)
		)
		(placement
			(enabled no)
			(sheetname "")
		)
		(fill
			(thermal_gap 0.5)
			(thermal_bridge_width 0.5)
			(island_removal_mode 0)
		)
		(polygon
			(pts
				(arc
					(start 22.45741 -233.28249)
					(mid 22.45369 -233.29147)
					(end 22.44471 -233.29519)
				)
				(arc
					(start 20.97151 -233.29519)
					(mid 20.96253 -233.29147)
					(end 20.95881 -233.28249)
				)
				(arc
					(start 20.95881 -232.787952)
					(mid 20.96253 -232.778972)
					(end 20.97151 -232.775252)
				)
				(arc
					(start 22.44471 -232.775252)
					(mid 22.45369 -232.778972)
					(end 22.45741 -232.787952)
				)
			)
		)
	)
	(zone
		(layer "In1.Cu")
		(hatch none 0.5)
		(connect_pads
			(clearance 0)
		)
		(min_thickness 0.25)
		(keepout
			(tracks not_allowed)
			(vias allowed)
			(pads allowed)
			(copperpour not_allowed)
			(footprints allowed)
		)
		(placement
			(enabled no)
			(sheetname "")
		)
		(fill
			(thermal_gap 0.5)
			(thermal_bridge_width 0.5)
			(island_removal_mode 0)
		)
		(polygon
			(pts
				(arc
					(start 160.288986 -385.31038)
					(mid 159.907986 -385.31038)
					(end 160.288986 -385.31038)
				)
			)
		)
	)
	(zone
		(layer "In1.Cu")
		(hatch none 0.5)
		(connect_pads
			(clearance 0)
		)
		(min_thickness 0.25)
		(keepout
			(tracks not_allowed)
			(vias allowed)
			(pads allowed)
			(copperpour not_allowed)
			(footprints allowed)
		)
		(placement
			(enabled no)
			(sheetname "")
		)
		(fill
			(thermal_gap 0.5)
			(thermal_bridge_width 0.5)
			(island_removal_mode 0)
		)
		(polygon
			(pts
				(arc
					(start 443.2935 -246.882158)
					(mid 443.28978 -246.891138)
					(end 443.2808 -246.894858)
				)
				(arc
					(start 441.8076 -246.894858)
					(mid 441.79862 -246.891138)
					(end 441.7949 -246.882158)
				)
				(arc
					(start 441.7949 -246.38762)
					(mid 441.79862 -246.37864)
					(end 441.8076 -246.37492)
				)
				(arc
					(start 443.2808 -246.37492)
					(mid 443.28978 -246.37864)
					(end 443.2935 -246.38762)
				)
			)
		)
	)
	(zone
		(layer "In1.Cu")
		(hatch none 0.5)
		(connect_pads
			(clearance 0)
		)
		(min_thickness 0.25)
		(keepout
			(tracks not_allowed)
			(vias allowed)
			(pads allowed)
			(copperpour not_allowed)
			(footprints allowed)
		)
		(placement
			(enabled no)
			(sheetname "")
		)
		(fill
			(thermal_gap 0.5)
			(thermal_bridge_width 0.5)
			(island_removal_mode 0)
		)
		(polygon
			(pts
				(arc
					(start 206.5782 -270.435324)
					(mid 205.9178 -270.435324)
					(end 206.5782 -270.435324)
				)
			)
		)
	)
	(zone
		(layer "In1.Cu")
		(hatch none 0.5)
		(connect_pads
			(clearance 0)
		)
		(min_thickness 0.25)
		(keepout
			(tracks not_allowed)
			(vias allowed)
			(pads allowed)
			(copperpour not_allowed)
			(footprints allowed)
		)
		(placement
			(enabled no)
			(sheetname "")
		)
		(fill
			(thermal_gap 0.5)
			(thermal_bridge_width 0.5)
			(island_removal_mode 0)
		)
		(polygon
			(pts
				(arc
					(start 180.265324 -202.682348)
					(mid 180.261604 -202.691328)
					(end 180.252624 -202.695048)
				)
				(arc
					(start 178.779424 -202.695048)
					(mid 178.770444 -202.691328)
					(end 178.766724 -202.682348)
				)
				(arc
					(start 178.766724 -202.18781)
					(mid 178.770444 -202.17883)
					(end 178.779424 -202.17511)
				)
				(arc
					(start 180.252624 -202.17511)
					(mid 180.261604 -202.17883)
					(end 180.265324 -202.18781)
				)
			)
		)
	)
	(zone
		(layer "In1.Cu")
		(hatch none 0.5)
		(connect_pads
			(clearance 0)
		)
		(min_thickness 0.25)
		(keepout
			(tracks not_allowed)
			(vias allowed)
			(pads allowed)
			(copperpour not_allowed)
			(footprints allowed)
		)
		(placement
			(enabled no)
			(sheetname "")
		)
		(fill
			(thermal_gap 0.5)
			(thermal_bridge_width 0.5)
			(island_removal_mode 0)
		)
		(polygon
			(pts
				(arc
					(start 184.365392 -275.782532)
					(mid 184.361672 -275.791512)
					(end 184.352692 -275.795232)
				)
				(arc
					(start 182.879492 -275.795232)
					(mid 182.870512 -275.791512)
					(end 182.866792 -275.782532)
				)
				(arc
					(start 182.866792 -275.287994)
					(mid 182.870512 -275.279014)
					(end 182.879492 -275.275294)
				)
				(arc
					(start 184.352692 -275.275294)
					(mid 184.361672 -275.279014)
					(end 184.365392 -275.287994)
				)
			)
		)
	)
	(zone
		(layer "In1.Cu")
		(hatch none 0.5)
		(connect_pads
			(clearance 0)
		)
		(min_thickness 0.25)
		(keepout
			(tracks not_allowed)
			(vias allowed)
			(pads allowed)
			(copperpour not_allowed)
			(footprints allowed)
		)
		(placement
			(enabled no)
			(sheetname "")
		)
		(fill
			(thermal_gap 0.5)
			(thermal_bridge_width 0.5)
			(island_removal_mode 0)
		)
		(polygon
			(pts
				(arc
					(start 293.029386 -212.882226)
					(mid 293.025666 -212.891206)
					(end 293.016686 -212.894926)
				)
				(arc
					(start 291.543486 -212.894926)
					(mid 291.534506 -212.891206)
					(end 291.530786 -212.882226)
				)
				(arc
					(start 291.530786 -212.387688)
					(mid 291.534506 -212.378708)
					(end 291.543486 -212.374988)
				)
				(arc
					(start 293.016686 -212.374988)
					(mid 293.025666 -212.378708)
					(end 293.029386 -212.387688)
				)
			)
		)
	)
	(zone
		(layer "In1.Cu")
		(hatch none 0.5)
		(connect_pads
			(clearance 0)
		)
		(min_thickness 0.25)
		(keepout
			(tracks not_allowed)
			(vias allowed)
			(pads allowed)
			(copperpour not_allowed)
			(footprints allowed)
		)
		(placement
			(enabled no)
			(sheetname "")
		)
		(fill
			(thermal_gap 0.5)
			(thermal_bridge_width 0.5)
			(island_removal_mode 0)
		)
		(polygon
			(pts
				(arc
					(start 56.077358 -314.88253)
					(mid 56.073638 -314.89151)
					(end 56.064658 -314.89523)
				)
				(arc
					(start 54.591458 -314.89523)
					(mid 54.582478 -314.89151)
					(end 54.578758 -314.88253)
				)
				(arc
					(start 54.578758 -314.387992)
					(mid 54.582478 -314.379012)
					(end 54.591458 -314.375292)
				)
				(arc
					(start 56.064658 -314.375292)
					(mid 56.073638 -314.379012)
					(end 56.077358 -314.387992)
				)
			)
		)
	)
	(zone
		(layer "In1.Cu")
		(hatch none 0.5)
		(connect_pads
			(clearance 0)
		)
		(min_thickness 0.25)
		(keepout
			(tracks not_allowed)
			(vias allowed)
			(pads allowed)
			(copperpour not_allowed)
			(footprints allowed)
		)
		(placement
			(enabled no)
			(sheetname "")
		)
		(fill
			(thermal_gap 0.5)
			(thermal_bridge_width 0.5)
			(island_removal_mode 0)
		)
		(polygon
			(pts
				(arc
					(start 199.4535 -304.682398)
					(mid 199.44978 -304.691378)
					(end 199.4408 -304.695098)
				)
				(arc
					(start 197.9676 -304.695098)
					(mid 197.95862 -304.691378)
					(end 197.9549 -304.682398)
				)
				(arc
					(start 197.9549 -304.18786)
					(mid 197.95862 -304.17888)
					(end 197.9676 -304.17516)
				)
				(arc
					(start 199.4408 -304.17516)
					(mid 199.44978 -304.17888)
					(end 199.4535 -304.18786)
				)
			)
		)
	)
	(zone
		(layer "In1.Cu")
		(hatch none 0.5)
		(connect_pads
			(clearance 0)
		)
		(min_thickness 0.25)
		(keepout
			(tracks not_allowed)
			(vias allowed)
			(pads allowed)
			(copperpour not_allowed)
			(footprints allowed)
		)
		(placement
			(enabled no)
			(sheetname "")
		)
		(fill
			(thermal_gap 0.5)
			(thermal_bridge_width 0.5)
			(island_removal_mode 0)
		)
		(polygon
			(pts
				(arc
					(start 187.809378 -268.982444)
					(mid 187.805658 -268.991424)
					(end 187.796678 -268.995144)
				)
				(arc
					(start 186.323478 -268.995144)
					(mid 186.314498 -268.991424)
					(end 186.310778 -268.982444)
				)
				(arc
					(start 186.310778 -268.487906)
					(mid 186.314498 -268.478926)
					(end 186.323478 -268.475206)
				)
				(arc
					(start 187.796678 -268.475206)
					(mid 187.805658 -268.478926)
					(end 187.809378 -268.487906)
				)
			)
		)
	)
	(zone
		(layer "In1.Cu")
		(hatch none 0.5)
		(connect_pads
			(clearance 0)
		)
		(min_thickness 0.25)
		(keepout
			(tracks not_allowed)
			(vias allowed)
			(pads allowed)
			(copperpour not_allowed)
			(footprints allowed)
		)
		(placement
			(enabled no)
			(sheetname "")
		)
		(fill
			(thermal_gap 0.5)
			(thermal_bridge_width 0.5)
			(island_removal_mode 0)
		)
		(polygon
			(pts
				(arc
					(start 52.96154 -11.91768)
					(mid 52.939222 -11.971562)
					(end 52.88534 -11.99388)
				)
				(arc
					(start 51.848766 -11.99388)
					(mid 51.794884 -11.971562)
					(end 51.772566 -11.91768)
				)
				(arc
					(start 51.772566 -10.51814)
					(mid 51.794884 -10.464258)
					(end 51.848766 -10.44194)
				)
				(arc
					(start 52.88534 -10.44194)
					(mid 52.939222 -10.464258)
					(end 52.96154 -10.51814)
				)
			)
		)
	)
	(zone
		(layer "In1.Cu")
		(hatch none 0.5)
		(connect_pads
			(clearance 0)
		)
		(min_thickness 0.25)
		(keepout
			(tracks not_allowed)
			(vias allowed)
			(pads allowed)
			(copperpour not_allowed)
			(footprints allowed)
		)
		(placement
			(enabled no)
			(sheetname "")
		)
		(fill
			(thermal_gap 0.5)
			(thermal_bridge_width 0.5)
			(island_removal_mode 0)
		)
		(polygon
			(pts
				(arc
					(start 195.353432 -207.782414)
					(mid 195.349712 -207.791394)
					(end 195.340732 -207.795114)
				)
				(arc
					(start 193.867532 -207.795114)
					(mid 193.858552 -207.791394)
					(end 193.854832 -207.782414)
				)
				(arc
					(start 193.854832 -207.287876)
					(mid 193.858552 -207.278896)
					(end 193.867532 -207.275176)
				)
				(arc
					(start 195.340732 -207.275176)
					(mid 195.349712 -207.278896)
					(end 195.353432 -207.287876)
				)
			)
		)
	)
	(zone
		(layer "In1.Cu")
		(hatch none 0.5)
		(connect_pads
			(clearance 0)
		)
		(min_thickness 0.25)
		(keepout
			(tracks not_allowed)
			(vias allowed)
			(pads allowed)
			(copperpour not_allowed)
			(footprints allowed)
		)
		(placement
			(enabled no)
			(sheetname "")
		)
		(fill
			(thermal_gap 0.5)
			(thermal_bridge_width 0.5)
			(island_removal_mode 0)
		)
		(polygon
			(pts
				(arc
					(start 300.57344 -252.832108)
					(mid 300.56972 -252.841088)
					(end 300.56074 -252.844808)
				)
				(arc
					(start 299.08754 -252.844808)
					(mid 299.07856 -252.841088)
					(end 299.07484 -252.832108)
				)
				(arc
					(start 299.07484 -252.33757)
					(mid 299.07856 -252.32859)
					(end 299.08754 -252.32487)
				)
				(arc
					(start 300.56074 -252.32487)
					(mid 300.56972 -252.32859)
					(end 300.57344 -252.33757)
				)
			)
		)
	)
	(zone
		(layer "In1.Cu")
		(hatch none 0.5)
		(connect_pads
			(clearance 0)
		)
		(min_thickness 0.25)
		(keepout
			(tracks not_allowed)
			(vias allowed)
			(pads allowed)
			(copperpour not_allowed)
			(footprints allowed)
		)
		(placement
			(enabled no)
			(sheetname "")
		)
		(fill
			(thermal_gap 0.5)
			(thermal_bridge_width 0.5)
			(island_removal_mode 0)
		)
		(polygon
			(pts
				(arc
					(start 281.385264 -250.282202)
					(mid 281.381544 -250.291182)
					(end 281.372564 -250.294902)
				)
				(arc
					(start 279.899364 -250.294902)
					(mid 279.890384 -250.291182)
					(end 279.886664 -250.282202)
				)
				(arc
					(start 279.886664 -249.787664)
					(mid 279.890384 -249.778684)
					(end 279.899364 -249.774964)
				)
				(arc
					(start 281.372564 -249.774964)
					(mid 281.381544 -249.778684)
					(end 281.385264 -249.787664)
				)
			)
		)
	)
	(zone
		(layer "In1.Cu")
		(hatch none 0.5)
		(connect_pads
			(clearance 0)
		)
		(min_thickness 0.25)
		(keepout
			(tracks not_allowed)
			(vias allowed)
			(pads allowed)
			(copperpour not_allowed)
			(footprints allowed)
		)
		(placement
			(enabled no)
			(sheetname "")
		)
		(fill
			(thermal_gap 0.5)
			(thermal_bridge_width 0.5)
			(island_removal_mode 0)
		)
		(polygon
			(pts
				(arc
					(start 450.8373 -246.882158)
					(mid 450.83358 -246.891138)
					(end 450.8246 -246.894858)
				)
				(arc
					(start 449.3514 -246.894858)
					(mid 449.34242 -246.891138)
					(end 449.3387 -246.882158)
				)
				(arc
					(start 449.3387 -246.38762)
					(mid 449.34242 -246.37864)
					(end 449.3514 -246.37492)
				)
				(arc
					(start 450.8246 -246.37492)
					(mid 450.83358 -246.37864)
					(end 450.8373 -246.38762)
				)
			)
		)
	)
	(zone
		(layer "In1.Cu")
		(hatch none 0.5)
		(connect_pads
			(clearance 0)
		)
		(min_thickness 0.25)
		(keepout
			(tracks not_allowed)
			(vias allowed)
			(pads allowed)
			(copperpour not_allowed)
			(footprints allowed)
		)
		(placement
			(enabled no)
			(sheetname "")
		)
		(fill
			(thermal_gap 0.5)
			(thermal_bridge_width 0.5)
			(island_removal_mode 0)
		)
		(polygon
			(pts
				(arc
					(start 450.8373 -202.682094)
					(mid 450.83358 -202.691074)
					(end 450.8246 -202.694794)
				)
				(arc
					(start 449.3514 -202.694794)
					(mid 449.34242 -202.691074)
					(end 449.3387 -202.682094)
				)
				(arc
					(start 449.3387 -202.187556)
					(mid 449.34242 -202.178576)
					(end 449.3514 -202.174856)
				)
				(arc
					(start 450.8246 -202.174856)
					(mid 450.83358 -202.178576)
					(end 450.8373 -202.187556)
				)
			)
		)
	)
	(zone
		(layer "In1.Cu")
		(hatch none 0.5)
		(connect_pads
			(clearance 0)
		)
		(min_thickness 0.25)
		(keepout
			(tracks not_allowed)
			(vias allowed)
			(pads allowed)
			(copperpour not_allowed)
			(footprints allowed)
		)
		(placement
			(enabled no)
			(sheetname "")
		)
		(fill
			(thermal_gap 0.5)
			(thermal_bridge_width 0.5)
			(island_removal_mode 0)
		)
		(polygon
			(pts
				(arc
					(start 51.170332 -390.761474)
					(mid 50.865532 -390.761474)
					(end 51.170332 -390.761474)
				)
			)
		)
	)
	(zone
		(layer "In1.Cu")
		(hatch none 0.5)
		(connect_pads
			(clearance 0)
		)
		(min_thickness 0.25)
		(keepout
			(tracks not_allowed)
			(vias allowed)
			(pads allowed)
			(copperpour not_allowed)
			(footprints allowed)
		)
		(placement
			(enabled no)
			(sheetname "")
		)
		(fill
			(thermal_gap 0.5)
			(thermal_bridge_width 0.5)
			(island_removal_mode 0)
		)
		(polygon
			(pts
				(arc
					(start 270.397478 -211.182204)
					(mid 270.393758 -211.191184)
					(end 270.384778 -211.194904)
				)
				(arc
					(start 268.911578 -211.194904)
					(mid 268.902598 -211.191184)
					(end 268.898878 -211.182204)
				)
				(arc
					(start 268.898878 -210.687666)
					(mid 268.902598 -210.678686)
					(end 268.911578 -210.674966)
				)
				(arc
					(start 270.384778 -210.674966)
					(mid 270.393758 -210.678686)
					(end 270.397478 -210.687666)
				)
			)
		)
	)
	(zone
		(layer "In1.Cu")
		(hatch none 0.5)
		(connect_pads
			(clearance 0)
		)
		(min_thickness 0.25)
		(keepout
			(tracks not_allowed)
			(vias allowed)
			(pads allowed)
			(copperpour not_allowed)
			(footprints allowed)
		)
		(placement
			(enabled no)
			(sheetname "")
		)
		(fill
			(thermal_gap 0.5)
			(thermal_bridge_width 0.5)
			(island_removal_mode 0)
		)
		(polygon
			(pts
				(arc
					(start 169.277284 -287.682432)
					(mid 169.273564 -287.691412)
					(end 169.264584 -287.695132)
				)
				(arc
					(start 167.791384 -287.695132)
					(mid 167.782404 -287.691412)
					(end 167.778684 -287.682432)
				)
				(arc
					(start 167.778684 -287.187894)
					(mid 167.782404 -287.178914)
					(end 167.791384 -287.175194)
				)
				(arc
					(start 169.264584 -287.175194)
					(mid 169.273564 -287.178914)
					(end 169.277284 -287.187894)
				)
			)
		)
	)
	(zone
		(layer "In1.Cu")
		(hatch none 0.5)
		(connect_pads
			(clearance 0)
		)
		(min_thickness 0.25)
		(keepout
			(tracks not_allowed)
			(vias allowed)
			(pads allowed)
			(copperpour not_allowed)
			(footprints allowed)
		)
		(placement
			(enabled no)
			(sheetname "")
		)
		(fill
			(thermal_gap 0.5)
			(thermal_bridge_width 0.5)
			(island_removal_mode 0)
		)
		(polygon
			(pts
				(arc
					(start 270.397478 -314.032138)
					(mid 270.393758 -314.041118)
					(end 270.384778 -314.044838)
				)
				(arc
					(start 268.911578 -314.044838)
					(mid 268.902598 -314.041118)
					(end 268.898878 -314.032138)
				)
				(arc
					(start 268.898878 -313.5376)
					(mid 268.902598 -313.52862)
					(end 268.911578 -313.5249)
				)
				(arc
					(start 270.384778 -313.5249)
					(mid 270.393758 -313.52862)
					(end 270.397478 -313.5376)
				)
			)
		)
	)
	(zone
		(layer "In1.Cu")
		(hatch none 0.5)
		(connect_pads
			(clearance 0)
		)
		(min_thickness 0.25)
		(keepout
			(tracks not_allowed)
			(vias allowed)
			(pads allowed)
			(copperpour not_allowed)
			(footprints allowed)
		)
		(placement
			(enabled no)
			(sheetname "")
		)
		(fill
			(thermal_gap 0.5)
			(thermal_bridge_width 0.5)
			(island_removal_mode 0)
		)
		(polygon
			(pts
				(arc
					(start 265.87831 -201.585068)
					(mid 265.21791 -201.585068)
					(end 265.87831 -201.585068)
				)
			)
		)
	)
	(zone
		(layer "In1.Cu")
		(hatch none 0.5)
		(connect_pads
			(clearance 0)
		)
		(min_thickness 0.25)
		(keepout
			(tracks not_allowed)
			(vias allowed)
			(pads allowed)
			(copperpour not_allowed)
			(footprints allowed)
		)
		(placement
			(enabled no)
			(sheetname "")
		)
		(fill
			(thermal_gap 0.5)
			(thermal_bridge_width 0.5)
			(island_removal_mode 0)
		)
		(polygon
			(pts
				(arc
					(start 336.718402 -391.822686)
					(mid 336.845402 -391.949686)
					(end 336.972402 -391.822686)
				)
				(arc
					(start 336.972402 -391.746486)
					(mid 336.845402 -391.619486)
					(end 336.718402 -391.746486)
				)
			)
		)
	)
	(zone
		(layer "In1.Cu")
		(hatch none 0.5)
		(connect_pads
			(clearance 0)
		)
		(min_thickness 0.25)
		(keepout
			(tracks not_allowed)
			(vias allowed)
			(pads allowed)
			(copperpour not_allowed)
			(footprints allowed)
		)
		(placement
			(enabled no)
			(sheetname "")
		)
		(fill
			(thermal_gap 0.5)
			(thermal_bridge_width 0.5)
			(island_removal_mode 0)
		)
		(polygon
			(pts
				(arc
					(start 180.265324 -207.782414)
					(mid 180.261604 -207.791394)
					(end 180.252624 -207.795114)
				)
				(arc
					(start 178.779424 -207.795114)
					(mid 178.770444 -207.791394)
					(end 178.766724 -207.782414)
				)
				(arc
					(start 178.766724 -207.287876)
					(mid 178.770444 -207.278896)
					(end 178.779424 -207.275176)
				)
				(arc
					(start 180.252624 -207.275176)
					(mid 180.261604 -207.278896)
					(end 180.265324 -207.287876)
				)
			)
		)
	)
	(zone
		(layer "In1.Cu")
		(hatch none 0.5)
		(connect_pads
			(clearance 0)
		)
		(min_thickness 0.25)
		(keepout
			(tracks not_allowed)
			(vias allowed)
			(pads allowed)
			(copperpour not_allowed)
			(footprints allowed)
		)
		(placement
			(enabled no)
			(sheetname "")
		)
		(fill
			(thermal_gap 0.5)
			(thermal_bridge_width 0.5)
			(island_removal_mode 0)
		)
		(polygon
			(pts
				(arc
					(start 308.117494 -247.732296)
					(mid 308.113774 -247.741276)
					(end 308.104794 -247.744996)
				)
				(arc
					(start 306.631594 -247.744996)
					(mid 306.622614 -247.741276)
					(end 306.618894 -247.732296)
				)
				(arc
					(start 306.618894 -247.237758)
					(mid 306.622614 -247.228778)
					(end 306.631594 -247.225058)
				)
				(arc
					(start 308.104794 -247.225058)
					(mid 308.113774 -247.228778)
					(end 308.117494 -247.237758)
				)
			)
		)
	)
	(zone
		(layer "In1.Cu")
		(hatch none 0.5)
		(connect_pads
			(clearance 0)
		)
		(min_thickness 0.25)
		(keepout
			(tracks not_allowed)
			(vias allowed)
			(pads allowed)
			(copperpour not_allowed)
			(footprints allowed)
		)
		(placement
			(enabled no)
			(sheetname "")
		)
		(fill
			(thermal_gap 0.5)
			(thermal_bridge_width 0.5)
			(island_removal_mode 0)
		)
		(polygon
			(pts
				(arc
					(start 180.265324 -232.432352)
					(mid 180.261604 -232.441332)
					(end 180.252624 -232.445052)
				)
				(arc
					(start 178.779424 -232.445052)
					(mid 178.770444 -232.441332)
					(end 178.766724 -232.432352)
				)
				(arc
					(start 178.766724 -231.937814)
					(mid 178.770444 -231.928834)
					(end 178.779424 -231.925114)
				)
				(arc
					(start 180.252624 -231.925114)
					(mid 180.261604 -231.928834)
					(end 180.265324 -231.937814)
				)
			)
		)
	)
	(zone
		(layer "In1.Cu")
		(hatch none 0.5)
		(connect_pads
			(clearance 0)
		)
		(min_thickness 0.25)
		(keepout
			(tracks not_allowed)
			(vias allowed)
			(pads allowed)
			(copperpour not_allowed)
			(footprints allowed)
		)
		(placement
			(enabled no)
			(sheetname "")
		)
		(fill
			(thermal_gap 0.5)
			(thermal_bridge_width 0.5)
			(island_removal_mode 0)
		)
		(polygon
			(pts
				(arc
					(start 206.9973 -261.332472)
					(mid 206.99358 -261.341452)
					(end 206.9846 -261.345172)
				)
				(arc
					(start 205.5114 -261.345172)
					(mid 205.50242 -261.341452)
					(end 205.4987 -261.332472)
				)
				(arc
					(start 205.4987 -260.837934)
					(mid 205.50242 -260.828954)
					(end 205.5114 -260.825234)
				)
				(arc
					(start 206.9846 -260.825234)
					(mid 206.99358 -260.828954)
					(end 206.9973 -260.837934)
				)
			)
		)
	)
	(zone
		(layer "In1.Cu")
		(hatch none 0.5)
		(connect_pads
			(clearance 0)
		)
		(min_thickness 0.25)
		(keepout
			(tracks not_allowed)
			(vias allowed)
			(pads allowed)
			(copperpour not_allowed)
			(footprints allowed)
		)
		(placement
			(enabled no)
			(sheetname "")
		)
		(fill
			(thermal_gap 0.5)
			(thermal_bridge_width 0.5)
			(island_removal_mode 0)
		)
		(polygon
			(pts
				(arc
					(start 49.970436 -383.92227)
					(mid 49.665636 -383.92227)
					(end 49.970436 -383.92227)
				)
			)
		)
	)
	(zone
		(layer "In1.Cu")
		(hatch none 0.5)
		(connect_pads
			(clearance 0)
		)
		(min_thickness 0.25)
		(keepout
			(tracks not_allowed)
			(vias allowed)
			(pads allowed)
			(copperpour not_allowed)
			(footprints allowed)
		)
		(placement
			(enabled no)
			(sheetname "")
		)
		(fill
			(thermal_gap 0.5)
			(thermal_bridge_width 0.5)
			(island_removal_mode 0)
		)
		(polygon
			(pts
				(arc
					(start 454.937368 -264.732262)
					(mid 454.933648 -264.741242)
					(end 454.924668 -264.744962)
				)
				(arc
					(start 453.451468 -264.744962)
					(mid 453.442488 -264.741242)
					(end 453.438768 -264.732262)
				)
				(arc
					(start 453.438768 -264.237724)
					(mid 453.442488 -264.228744)
					(end 453.451468 -264.225024)
				)
				(arc
					(start 454.924668 -264.225024)
					(mid 454.933648 -264.228744)
					(end 454.937368 -264.237724)
				)
			)
		)
	)
	(zone
		(layer "In1.Cu")
		(hatch none 0.5)
		(connect_pads
			(clearance 0)
		)
		(min_thickness 0.25)
		(keepout
			(tracks not_allowed)
			(vias allowed)
			(pads allowed)
			(copperpour not_allowed)
			(footprints allowed)
		)
		(placement
			(enabled no)
			(sheetname "")
		)
		(fill
			(thermal_gap 0.5)
			(thermal_bridge_width 0.5)
			(island_removal_mode 0)
		)
		(polygon
			(pts
				(arc
					(start 285.485332 -249.432318)
					(mid 285.481612 -249.441298)
					(end 285.472632 -249.445018)
				)
				(arc
					(start 283.999432 -249.445018)
					(mid 283.990452 -249.441298)
					(end 283.986732 -249.432318)
				)
				(arc
					(start 283.986732 -248.93778)
					(mid 283.990452 -248.9288)
					(end 283.999432 -248.92508)
				)
				(arc
					(start 285.472632 -248.92508)
					(mid 285.481612 -248.9288)
					(end 285.485332 -248.93778)
				)
			)
		)
	)
	(zone
		(layer "In1.Cu")
		(hatch none 0.5)
		(connect_pads
			(clearance 0)
		)
		(min_thickness 0.25)
		(keepout
			(tracks not_allowed)
			(vias allowed)
			(pads allowed)
			(copperpour not_allowed)
			(footprints allowed)
		)
		(placement
			(enabled no)
			(sheetname "")
		)
		(fill
			(thermal_gap 0.5)
			(thermal_bridge_width 0.5)
			(island_removal_mode 0)
		)
		(polygon
			(pts
				(arc
					(start 33.445196 -299.582586)
					(mid 33.441476 -299.591566)
					(end 33.432496 -299.595286)
				)
				(arc
					(start 31.959296 -299.595286)
					(mid 31.950316 -299.591566)
					(end 31.946596 -299.582586)
				)
				(arc
					(start 31.946596 -299.088048)
					(mid 31.950316 -299.079068)
					(end 31.959296 -299.075348)
				)
				(arc
					(start 33.432496 -299.075348)
					(mid 33.441476 -299.079068)
					(end 33.445196 -299.088048)
				)
			)
		)
	)
	(zone
		(layer "In1.Cu")
		(hatch none 0.5)
		(connect_pads
			(clearance 0)
		)
		(min_thickness 0.25)
		(keepout
			(tracks not_allowed)
			(vias allowed)
			(pads allowed)
			(copperpour not_allowed)
			(footprints allowed)
		)
		(placement
			(enabled no)
			(sheetname "")
		)
		(fill
			(thermal_gap 0.5)
			(thermal_bridge_width 0.5)
			(island_removal_mode 0)
		)
		(polygon
			(pts
				(arc
					(start 48.533304 -305.532536)
					(mid 48.529584 -305.541516)
					(end 48.520604 -305.545236)
				)
				(arc
					(start 47.047404 -305.545236)
					(mid 47.038424 -305.541516)
					(end 47.034704 -305.532536)
				)
				(arc
					(start 47.034704 -305.037998)
					(mid 47.038424 -305.029018)
					(end 47.047404 -305.025298)
				)
				(arc
					(start 48.520604 -305.025298)
					(mid 48.529584 -305.029018)
					(end 48.533304 -305.037998)
				)
			)
		)
	)
	(zone
		(layer "In1.Cu")
		(hatch none 0.5)
		(connect_pads
			(clearance 0)
		)
		(min_thickness 0.25)
		(keepout
			(tracks not_allowed)
			(vias allowed)
			(pads allowed)
			(copperpour not_allowed)
			(footprints allowed)
		)
		(placement
			(enabled no)
			(sheetname "")
		)
		(fill
			(thermal_gap 0.5)
			(thermal_bridge_width 0.5)
			(island_removal_mode 0)
		)
		(polygon
			(pts
				(arc
					(start 300.57344 -309.78221)
					(mid 300.56972 -309.79119)
					(end 300.56074 -309.79491)
				)
				(arc
					(start 299.08754 -309.79491)
					(mid 299.07856 -309.79119)
					(end 299.07484 -309.78221)
				)
				(arc
					(start 299.07484 -309.287672)
					(mid 299.07856 -309.278692)
					(end 299.08754 -309.274972)
				)
				(arc
					(start 300.56074 -309.274972)
					(mid 300.56972 -309.278692)
					(end 300.57344 -309.287672)
				)
			)
		)
	)
	(zone
		(layer "In1.Cu")
		(hatch none 0.5)
		(connect_pads
			(clearance 0)
		)
		(min_thickness 0.25)
		(keepout
			(tracks not_allowed)
			(vias allowed)
			(pads allowed)
			(copperpour not_allowed)
			(footprints allowed)
		)
		(placement
			(enabled no)
			(sheetname "")
		)
		(fill
			(thermal_gap 0.5)
			(thermal_bridge_width 0.5)
			(island_removal_mode 0)
		)
		(polygon
			(pts
				(arc
					(start 427.461426 -11.91768)
					(mid 427.439108 -11.971562)
					(end 427.385226 -11.99388)
				)
				(arc
					(start 426.348652 -11.99388)
					(mid 426.29477 -11.971562)
					(end 426.272452 -11.91768)
				)
				(arc
					(start 426.272452 -10.51814)
					(mid 426.29477 -10.464258)
					(end 426.348652 -10.44194)
				)
				(arc
					(start 427.385226 -10.44194)
					(mid 427.439108 -10.464258)
					(end 427.461426 -10.51814)
				)
			)
		)
	)
	(zone
		(layer "In1.Cu")
		(hatch none 0.5)
		(connect_pads
			(clearance 0)
		)
		(min_thickness 0.25)
		(keepout
			(tracks not_allowed)
			(vias allowed)
			(pads allowed)
			(copperpour not_allowed)
			(footprints allowed)
		)
		(placement
			(enabled no)
			(sheetname "")
		)
		(fill
			(thermal_gap 0.5)
			(thermal_bridge_width 0.5)
			(island_removal_mode 0)
		)
		(polygon
			(pts
				(arc
					(start 265.87831 -278.93518)
					(mid 265.21791 -278.93518)
					(end 265.87831 -278.93518)
				)
			)
		)
	)
	(zone
		(layer "In1.Cu")
		(hatch none 0.5)
		(connect_pads
			(clearance 0)
		)
		(min_thickness 0.25)
		(keepout
			(tracks not_allowed)
			(vias allowed)
			(pads allowed)
			(copperpour not_allowed)
			(footprints allowed)
		)
		(placement
			(enabled no)
			(sheetname "")
		)
		(fill
			(thermal_gap 0.5)
			(thermal_bridge_width 0.5)
			(island_removal_mode 0)
		)
		(polygon
			(pts
				(arc
					(start 89.118694 -383.440686)
					(mid 89.245694 -383.567686)
					(end 89.372694 -383.440686)
				)
				(arc
					(start 89.372694 -383.364486)
					(mid 89.245694 -383.237486)
					(end 89.118694 -383.364486)
				)
			)
		)
	)
	(zone
		(layer "In1.Cu")
		(hatch none 0.5)
		(connect_pads
			(clearance 0)
		)
		(min_thickness 0.25)
		(keepout
			(tracks not_allowed)
			(vias allowed)
			(pads allowed)
			(copperpour not_allowed)
			(footprints allowed)
		)
		(placement
			(enabled no)
			(sheetname "")
		)
		(fill
			(thermal_gap 0.5)
			(thermal_bridge_width 0.5)
			(island_removal_mode 0)
		)
		(polygon
			(pts
				(arc
					(start 424.761406 -309.78221)
					(mid 424.757686 -309.79119)
					(end 424.748706 -309.79491)
				)
				(arc
					(start 423.275506 -309.79491)
					(mid 423.266526 -309.79119)
					(end 423.262806 -309.78221)
				)
				(arc
					(start 423.262806 -309.287672)
					(mid 423.266526 -309.278692)
					(end 423.275506 -309.274972)
				)
				(arc
					(start 424.748706 -309.274972)
					(mid 424.757686 -309.278692)
					(end 424.761406 -309.287672)
				)
			)
		)
	)
	(zone
		(layer "In1.Cu")
		(hatch none 0.5)
		(connect_pads
			(clearance 0)
		)
		(min_thickness 0.25)
		(keepout
			(tracks not_allowed)
			(vias allowed)
			(pads allowed)
			(copperpour not_allowed)
			(footprints allowed)
		)
		(placement
			(enabled no)
			(sheetname "")
		)
		(fill
			(thermal_gap 0.5)
			(thermal_bridge_width 0.5)
			(island_removal_mode 0)
		)
		(polygon
			(pts
				(arc
					(start 184.365392 -303.832514)
					(mid 184.361672 -303.841494)
					(end 184.352692 -303.845214)
				)
				(arc
					(start 182.879492 -303.845214)
					(mid 182.870512 -303.841494)
					(end 182.866792 -303.832514)
				)
				(arc
					(start 182.866792 -303.337976)
					(mid 182.870512 -303.328996)
					(end 182.879492 -303.325276)
				)
				(arc
					(start 184.352692 -303.325276)
					(mid 184.361672 -303.328996)
					(end 184.365392 -303.337976)
				)
			)
		)
	)
	(zone
		(layer "In1.Cu")
		(hatch none 0.5)
		(connect_pads
			(clearance 0)
		)
		(min_thickness 0.25)
		(keepout
			(tracks not_allowed)
			(vias allowed)
			(pads allowed)
			(copperpour not_allowed)
			(footprints allowed)
		)
		(placement
			(enabled no)
			(sheetname "")
		)
		(fill
			(thermal_gap 0.5)
			(thermal_bridge_width 0.5)
			(island_removal_mode 0)
		)
		(polygon
			(pts
				(arc
					(start 121.76125 -385.31038)
					(mid 121.38025 -385.31038)
					(end 121.76125 -385.31038)
				)
			)
		)
	)
	(zone
		(layer "In1.Cu")
		(hatch none 0.5)
		(connect_pads
			(clearance 0)
		)
		(min_thickness 0.25)
		(keepout
			(tracks not_allowed)
			(vias allowed)
			(pads allowed)
			(copperpour not_allowed)
			(footprints allowed)
		)
		(placement
			(enabled no)
			(sheetname "")
		)
		(fill
			(thermal_gap 0.5)
			(thermal_bridge_width 0.5)
			(island_removal_mode 0)
		)
		(polygon
			(pts
				(arc
					(start 48.533304 -308.93258)
					(mid 48.529584 -308.94156)
					(end 48.520604 -308.94528)
				)
				(arc
					(start 47.047404 -308.94528)
					(mid 47.038424 -308.94156)
					(end 47.034704 -308.93258)
				)
				(arc
					(start 47.034704 -308.438042)
					(mid 47.038424 -308.429062)
					(end 47.047404 -308.425342)
				)
				(arc
					(start 48.520604 -308.425342)
					(mid 48.529584 -308.429062)
					(end 48.533304 -308.438042)
				)
			)
		)
	)
	(zone
		(layer "In1.Cu")
		(hatch none 0.5)
		(connect_pads
			(clearance 0)
		)
		(min_thickness 0.25)
		(keepout
			(tracks not_allowed)
			(vias allowed)
			(pads allowed)
			(copperpour not_allowed)
			(footprints allowed)
		)
		(placement
			(enabled no)
			(sheetname "")
		)
		(fill
			(thermal_gap 0.5)
			(thermal_bridge_width 0.5)
			(island_removal_mode 0)
		)
		(polygon
			(pts
				(arc
					(start 385.07035 -399.143474)
					(mid 384.76555 -399.143474)
					(end 385.07035 -399.143474)
				)
			)
		)
	)
	(zone
		(layer "In1.Cu")
		(hatch none 0.5)
		(connect_pads
			(clearance 0)
		)
		(min_thickness 0.25)
		(keepout
			(tracks not_allowed)
			(vias allowed)
			(pads allowed)
			(copperpour not_allowed)
			(footprints allowed)
		)
		(placement
			(enabled no)
			(sheetname "")
		)
		(fill
			(thermal_gap 0.5)
			(thermal_bridge_width 0.5)
			(island_removal_mode 0)
		)
		(polygon
			(pts
				(arc
					(start 354.388674 -397.849344)
					(mid 354.007674 -397.849344)
					(end 354.388674 -397.849344)
				)
			)
		)
	)
	(zone
		(layer "In1.Cu")
		(hatch none 0.5)
		(connect_pads
			(clearance 0)
		)
		(min_thickness 0.25)
		(keepout
			(tracks not_allowed)
			(vias allowed)
			(pads allowed)
			(copperpour not_allowed)
			(footprints allowed)
		)
		(placement
			(enabled no)
			(sheetname "")
		)
		(fill
			(thermal_gap 0.5)
			(thermal_bridge_width 0.5)
			(island_removal_mode 0)
		)
		(polygon
			(pts
				(arc
					(start 428.205392 -235.832142)
					(mid 428.201672 -235.841122)
					(end 428.192692 -235.844842)
				)
				(arc
					(start 426.719492 -235.844842)
					(mid 426.710512 -235.841122)
					(end 426.706792 -235.832142)
				)
				(arc
					(start 426.706792 -235.337604)
					(mid 426.710512 -235.328624)
					(end 426.719492 -235.324904)
				)
				(arc
					(start 428.192692 -235.324904)
					(mid 428.201672 -235.328624)
					(end 428.205392 -235.337604)
				)
			)
		)
	)
	(zone
		(layer "In1.Cu")
		(hatch none 0.5)
		(connect_pads
			(clearance 0)
		)
		(min_thickness 0.25)
		(keepout
			(tracks not_allowed)
			(vias allowed)
			(pads allowed)
			(copperpour not_allowed)
			(footprints allowed)
		)
		(placement
			(enabled no)
			(sheetname "")
		)
		(fill
			(thermal_gap 0.5)
			(thermal_bridge_width 0.5)
			(island_removal_mode 0)
		)
		(polygon
			(pts
				(arc
					(start 296.473372 -243.482114)
					(mid 296.469652 -243.491094)
					(end 296.460672 -243.494814)
				)
				(arc
					(start 294.987472 -243.494814)
					(mid 294.978492 -243.491094)
					(end 294.974772 -243.482114)
				)
				(arc
					(start 294.974772 -242.987576)
					(mid 294.978492 -242.978596)
					(end 294.987472 -242.974876)
				)
				(arc
					(start 296.460672 -242.974876)
					(mid 296.469652 -242.978596)
					(end 296.473372 -242.987576)
				)
			)
		)
	)
	(zone
		(layer "In1.Cu")
		(hatch none 0.5)
		(connect_pads
			(clearance 0)
		)
		(min_thickness 0.25)
		(keepout
			(tracks not_allowed)
			(vias allowed)
			(pads allowed)
			(copperpour not_allowed)
			(footprints allowed)
		)
		(placement
			(enabled no)
			(sheetname "")
		)
		(fill
			(thermal_gap 0.5)
			(thermal_bridge_width 0.5)
			(island_removal_mode 0)
		)
		(polygon
			(pts
				(arc
					(start 336.38871 -394.385292)
					(mid 336.00771 -394.385292)
					(end 336.38871 -394.385292)
				)
			)
		)
	)
	(zone
		(layer "In1.Cu")
		(hatch none 0.5)
		(connect_pads
			(clearance 0)
		)
		(min_thickness 0.25)
		(keepout
			(tracks not_allowed)
			(vias allowed)
			(pads allowed)
			(copperpour not_allowed)
			(footprints allowed)
		)
		(placement
			(enabled no)
			(sheetname "")
		)
		(fill
			(thermal_gap 0.5)
			(thermal_bridge_width 0.5)
			(island_removal_mode 0)
		)
		(polygon
			(pts
				(arc
					(start 300.57344 -222.23222)
					(mid 300.56972 -222.2412)
					(end 300.56074 -222.24492)
				)
				(arc
					(start 299.08754 -222.24492)
					(mid 299.07856 -222.2412)
					(end 299.07484 -222.23222)
				)
				(arc
					(start 299.07484 -221.737682)
					(mid 299.07856 -221.728702)
					(end 299.08754 -221.724982)
				)
				(arc
					(start 300.56074 -221.724982)
					(mid 300.56972 -221.728702)
					(end 300.57344 -221.737682)
				)
			)
		)
	)
	(zone
		(layer "In1.Cu")
		(hatch none 0.5)
		(connect_pads
			(clearance 0)
		)
		(min_thickness 0.25)
		(keepout
			(tracks not_allowed)
			(vias allowed)
			(pads allowed)
			(copperpour not_allowed)
			(footprints allowed)
		)
		(placement
			(enabled no)
			(sheetname "")
		)
		(fill
			(thermal_gap 0.5)
			(thermal_bridge_width 0.5)
			(island_removal_mode 0)
		)
		(polygon
			(pts
				(arc
					(start 435.749446 -314.882276)
					(mid 435.745726 -314.891256)
					(end 435.736746 -314.894976)
				)
				(arc
					(start 434.263546 -314.894976)
					(mid 434.254566 -314.891256)
					(end 434.250846 -314.882276)
				)
				(arc
					(start 434.250846 -314.387738)
					(mid 434.254566 -314.378758)
					(end 434.263546 -314.375038)
				)
				(arc
					(start 435.736746 -314.375038)
					(mid 435.745726 -314.378758)
					(end 435.749446 -314.387738)
				)
			)
		)
	)
	(zone
		(layer "In1.Cu")
		(hatch none 0.5)
		(connect_pads
			(clearance 0)
		)
		(min_thickness 0.25)
		(keepout
			(tracks not_allowed)
			(vias allowed)
			(pads allowed)
			(copperpour not_allowed)
			(footprints allowed)
		)
		(placement
			(enabled no)
			(sheetname "")
		)
		(fill
			(thermal_gap 0.5)
			(thermal_bridge_width 0.5)
			(island_removal_mode 0)
		)
		(polygon
			(pts
				(arc
					(start 432.30546 -236.68228)
					(mid 432.30174 -236.69126)
					(end 432.29276 -236.69498)
				)
				(arc
					(start 430.81956 -236.69498)
					(mid 430.81058 -236.69126)
					(end 430.80686 -236.68228)
				)
				(arc
					(start 430.80686 -236.187742)
					(mid 430.81058 -236.178762)
					(end 430.81956 -236.175042)
				)
				(arc
					(start 432.29276 -236.175042)
					(mid 432.30174 -236.178762)
					(end 432.30546 -236.187742)
				)
			)
		)
	)
	(zone
		(layer "In1.Cu")
		(hatch none 0.5)
		(connect_pads
			(clearance 0)
		)
		(min_thickness 0.25)
		(keepout
			(tracks not_allowed)
			(vias allowed)
			(pads allowed)
			(copperpour not_allowed)
			(footprints allowed)
		)
		(placement
			(enabled no)
			(sheetname "")
		)
		(fill
			(thermal_gap 0.5)
			(thermal_bridge_width 0.5)
			(island_removal_mode 0)
		)
		(polygon
			(pts
				(arc
					(start 114.670332 -383.92227)
					(mid 114.365532 -383.92227)
					(end 114.670332 -383.92227)
				)
			)
		)
	)
	(zone
		(layer "In1.Cu")
		(hatch none 0.5)
		(connect_pads
			(clearance 0)
		)
		(min_thickness 0.25)
		(keepout
			(tracks not_allowed)
			(vias allowed)
			(pads allowed)
			(copperpour not_allowed)
			(footprints allowed)
		)
		(placement
			(enabled no)
			(sheetname "")
		)
		(fill
			(thermal_gap 0.5)
			(thermal_bridge_width 0.5)
			(island_removal_mode 0)
		)
		(polygon
			(pts
				(arc
					(start 312.590688 -391.822686)
					(mid 312.717688 -391.949686)
					(end 312.844688 -391.822686)
				)
				(arc
					(start 312.844688 -391.746486)
					(mid 312.717688 -391.619486)
					(end 312.590688 -391.746486)
				)
			)
		)
	)
	(zone
		(layer "In1.Cu")
		(hatch none 0.5)
		(connect_pads
			(clearance 0)
		)
		(min_thickness 0.25)
		(keepout
			(tracks not_allowed)
			(vias allowed)
			(pads allowed)
			(copperpour not_allowed)
			(footprints allowed)
		)
		(placement
			(enabled no)
			(sheetname "")
		)
		(fill
			(thermal_gap 0.5)
			(thermal_bridge_width 0.5)
			(island_removal_mode 0)
		)
		(polygon
			(pts
				(arc
					(start 184.365392 -264.732516)
					(mid 184.361672 -264.741496)
					(end 184.352692 -264.745216)
				)
				(arc
					(start 182.879492 -264.745216)
					(mid 182.870512 -264.741496)
					(end 182.866792 -264.732516)
				)
				(arc
					(start 182.866792 -264.237978)
					(mid 182.870512 -264.228998)
					(end 182.879492 -264.225278)
				)
				(arc
					(start 184.352692 -264.225278)
					(mid 184.361672 -264.228998)
					(end 184.365392 -264.237978)
				)
			)
		)
	)
	(zone
		(layer "In1.Cu")
		(hatch none 0.5)
		(connect_pads
			(clearance 0)
		)
		(min_thickness 0.25)
		(keepout
			(tracks not_allowed)
			(vias allowed)
			(pads allowed)
			(copperpour not_allowed)
			(footprints allowed)
		)
		(placement
			(enabled no)
			(sheetname "")
		)
		(fill
			(thermal_gap 0.5)
			(thermal_bridge_width 0.5)
			(island_removal_mode 0)
		)
		(polygon
			(pts
				(arc
					(start 176.821338 -225.632518)
					(mid 176.817618 -225.641498)
					(end 176.808638 -225.645218)
				)
				(arc
					(start 175.335438 -225.645218)
					(mid 175.326458 -225.641498)
					(end 175.322738 -225.632518)
				)
				(arc
					(start 175.322738 -225.13798)
					(mid 175.326458 -225.129)
					(end 175.335438 -225.12528)
				)
				(arc
					(start 176.808638 -225.12528)
					(mid 176.817618 -225.129)
					(end 176.821338 -225.13798)
				)
			)
		)
	)
	(zone
		(layer "In1.Cu")
		(hatch none 0.5)
		(connect_pads
			(clearance 0)
		)
		(min_thickness 0.25)
		(keepout
			(tracks not_allowed)
			(vias allowed)
			(pads allowed)
			(copperpour not_allowed)
			(footprints allowed)
		)
		(placement
			(enabled no)
			(sheetname "")
		)
		(fill
			(thermal_gap 0.5)
			(thermal_bridge_width 0.5)
			(island_removal_mode 0)
		)
		(polygon
			(pts
				(arc
					(start 22.45741 -225.632518)
					(mid 22.45369 -225.641498)
					(end 22.44471 -225.645218)
				)
				(arc
					(start 20.97151 -225.645218)
					(mid 20.96253 -225.641498)
					(end 20.95881 -225.632518)
				)
				(arc
					(start 20.95881 -225.13798)
					(mid 20.96253 -225.129)
					(end 20.97151 -225.12528)
				)
				(arc
					(start 22.44471 -225.12528)
					(mid 22.45369 -225.129)
					(end 22.45741 -225.13798)
				)
			)
		)
	)
	(zone
		(layer "In1.Cu")
		(hatch none 0.5)
		(connect_pads
			(clearance 0)
		)
		(min_thickness 0.25)
		(keepout
			(tracks not_allowed)
			(vias allowed)
			(pads allowed)
			(copperpour not_allowed)
			(footprints allowed)
		)
		(placement
			(enabled no)
			(sheetname "")
		)
		(fill
			(thermal_gap 0.5)
			(thermal_bridge_width 0.5)
			(island_removal_mode 0)
		)
		(polygon
			(pts
				(arc
					(start 443.2935 -288.532316)
					(mid 443.28978 -288.541296)
					(end 443.2808 -288.545016)
				)
				(arc
					(start 441.8076 -288.545016)
					(mid 441.79862 -288.541296)
					(end 441.7949 -288.532316)
				)
				(arc
					(start 441.7949 -288.037778)
					(mid 441.79862 -288.028798)
					(end 441.8076 -288.025078)
				)
				(arc
					(start 443.2808 -288.025078)
					(mid 443.28978 -288.028798)
					(end 443.2935 -288.037778)
				)
			)
		)
	)
	(zone
		(layer "In1.Cu")
		(hatch none 0.5)
		(connect_pads
			(clearance 0)
		)
		(min_thickness 0.25)
		(keepout
			(tracks not_allowed)
			(vias allowed)
			(pads allowed)
			(copperpour not_allowed)
			(footprints allowed)
		)
		(placement
			(enabled no)
			(sheetname "")
		)
		(fill
			(thermal_gap 0.5)
			(thermal_bridge_width 0.5)
			(island_removal_mode 0)
		)
		(polygon
			(pts
				(arc
					(start 408.288744 -394.385292)
					(mid 407.907744 -394.385292)
					(end 408.288744 -394.385292)
				)
			)
		)
	)
	(zone
		(layer "In1.Cu")
		(hatch none 0.5)
		(connect_pads
			(clearance 0)
		)
		(min_thickness 0.25)
		(keepout
			(tracks not_allowed)
			(vias allowed)
			(pads allowed)
			(copperpour not_allowed)
			(footprints allowed)
		)
		(placement
			(enabled no)
			(sheetname "")
		)
		(fill
			(thermal_gap 0.5)
			(thermal_bridge_width 0.5)
			(island_removal_mode 0)
		)
		(polygon
			(pts
				(arc
					(start 410.288994 -393.69238)
					(mid 409.907994 -393.69238)
					(end 410.288994 -393.69238)
				)
			)
		)
	)
	(zone
		(layer "In1.Cu")
		(hatch none 0.5)
		(connect_pads
			(clearance 0)
		)
		(min_thickness 0.25)
		(keepout
			(tracks not_allowed)
			(vias allowed)
			(pads allowed)
			(copperpour not_allowed)
			(footprints allowed)
		)
		(placement
			(enabled no)
			(sheetname "")
		)
		(fill
			(thermal_gap 0.5)
			(thermal_bridge_width 0.5)
			(island_removal_mode 0)
		)
		(polygon
			(pts
				(arc
					(start 409.198064 -399.143474)
					(mid 408.893264 -399.143474)
					(end 409.198064 -399.143474)
				)
			)
		)
	)
	(zone
		(layer "In1.Cu")
		(hatch none 0.5)
		(connect_pads
			(clearance 0)
		)
		(min_thickness 0.25)
		(keepout
			(tracks not_allowed)
			(vias allowed)
			(pads allowed)
			(copperpour not_allowed)
			(footprints allowed)
		)
		(placement
			(enabled no)
			(sheetname "")
		)
		(fill
			(thermal_gap 0.5)
			(thermal_bridge_width 0.5)
			(island_removal_mode 0)
		)
		(polygon
			(pts
				(arc
					(start 33.445196 -248.582434)
					(mid 33.441476 -248.591414)
					(end 33.432496 -248.595134)
				)
				(arc
					(start 31.959296 -248.595134)
					(mid 31.950316 -248.591414)
					(end 31.946596 -248.582434)
				)
				(arc
					(start 31.946596 -248.087896)
					(mid 31.950316 -248.078916)
					(end 31.959296 -248.075196)
				)
				(arc
					(start 33.432496 -248.075196)
					(mid 33.441476 -248.078916)
					(end 33.445196 -248.087896)
				)
			)
		)
	)
	(zone
		(layer "In1.Cu")
		(hatch none 0.5)
		(connect_pads
			(clearance 0)
		)
		(min_thickness 0.25)
		(keepout
			(tracks not_allowed)
			(vias allowed)
			(pads allowed)
			(copperpour not_allowed)
			(footprints allowed)
		)
		(placement
			(enabled no)
			(sheetname "")
		)
		(fill
			(thermal_gap 0.5)
			(thermal_bridge_width 0.5)
			(island_removal_mode 0)
		)
		(polygon
			(pts
				(arc
					(start 450.8373 -312.332116)
					(mid 450.83358 -312.341096)
					(end 450.8246 -312.344816)
				)
				(arc
					(start 449.3514 -312.344816)
					(mid 449.34242 -312.341096)
					(end 449.3387 -312.332116)
				)
				(arc
					(start 449.3387 -311.837578)
					(mid 449.34242 -311.828598)
					(end 449.3514 -311.824878)
				)
				(arc
					(start 450.8246 -311.824878)
					(mid 450.83358 -311.828598)
					(end 450.8373 -311.837578)
				)
			)
		)
	)
	(zone
		(layer "In1.Cu")
		(hatch none 0.5)
		(connect_pads
			(clearance 0)
		)
		(min_thickness 0.25)
		(keepout
			(tracks not_allowed)
			(vias allowed)
			(pads allowed)
			(copperpour not_allowed)
			(footprints allowed)
		)
		(placement
			(enabled no)
			(sheetname "")
		)
		(fill
			(thermal_gap 0.5)
			(thermal_bridge_width 0.5)
			(island_removal_mode 0)
		)
		(polygon
			(pts
				(arc
					(start 54.770528 -390.761474)
					(mid 54.465728 -390.761474)
					(end 54.770528 -390.761474)
				)
			)
		)
	)
	(zone
		(layer "In1.Cu")
		(hatch none 0.5)
		(connect_pads
			(clearance 0)
		)
		(min_thickness 0.25)
		(keepout
			(tracks not_allowed)
			(vias allowed)
			(pads allowed)
			(copperpour not_allowed)
			(footprints allowed)
		)
		(placement
			(enabled no)
			(sheetname "")
		)
		(fill
			(thermal_gap 0.5)
			(thermal_bridge_width 0.5)
			(island_removal_mode 0)
		)
		(polygon
			(pts
				(arc
					(start 48.533304 -268.982444)
					(mid 48.529584 -268.991424)
					(end 48.520604 -268.995144)
				)
				(arc
					(start 47.047404 -268.995144)
					(mid 47.038424 -268.991424)
					(end 47.034704 -268.982444)
				)
				(arc
					(start 47.034704 -268.487906)
					(mid 47.038424 -268.478926)
					(end 47.047404 -268.475206)
				)
				(arc
					(start 48.520604 -268.475206)
					(mid 48.529584 -268.478926)
					(end 48.533304 -268.487906)
				)
			)
		)
	)
	(zone
		(layer "In1.Cu")
		(hatch none 0.5)
		(connect_pads
			(clearance 0)
		)
		(min_thickness 0.25)
		(keepout
			(tracks not_allowed)
			(vias allowed)
			(pads allowed)
			(copperpour not_allowed)
			(footprints allowed)
		)
		(placement
			(enabled no)
			(sheetname "")
		)
		(fill
			(thermal_gap 0.5)
			(thermal_bridge_width 0.5)
			(island_removal_mode 0)
		)
		(polygon
			(pts
				(arc
					(start 390.257792 -23.50389)
					(mid 390.20391 -23.481572)
					(end 390.181592 -23.42769)
				)
				(arc
					(start 390.181592 -22.153372)
					(mid 390.20391 -22.09949)
					(end 390.257792 -22.077172)
				)
				(arc
					(start 390.766046 -22.077172)
					(mid 390.819928 -22.09949)
					(end 390.842246 -22.153372)
				)
				(arc
					(start 390.842246 -23.42769)
					(mid 390.819928 -23.481572)
					(end 390.766046 -23.50389)
				)
			)
		)
	)
	(zone
		(layer "In1.Cu")
		(hatch none 0.5)
		(connect_pads
			(clearance 0)
		)
		(min_thickness 0.25)
		(keepout
			(tracks not_allowed)
			(vias allowed)
			(pads allowed)
			(copperpour not_allowed)
			(footprints allowed)
		)
		(placement
			(enabled no)
			(sheetname "")
		)
		(fill
			(thermal_gap 0.5)
			(thermal_bridge_width 0.5)
			(island_removal_mode 0)
		)
		(polygon
			(pts
				(arc
					(start 432.30546 -246.032274)
					(mid 432.30174 -246.041254)
					(end 432.29276 -246.044974)
				)
				(arc
					(start 430.81956 -246.044974)
					(mid 430.81058 -246.041254)
					(end 430.80686 -246.032274)
				)
				(arc
					(start 430.80686 -245.537736)
					(mid 430.81058 -245.528756)
					(end 430.81956 -245.525036)
				)
				(arc
					(start 432.29276 -245.525036)
					(mid 432.30174 -245.528756)
					(end 432.30546 -245.537736)
				)
			)
		)
	)
	(zone
		(layer "In1.Cu")
		(hatch none 0.5)
		(connect_pads
			(clearance 0)
		)
		(min_thickness 0.25)
		(keepout
			(tracks not_allowed)
			(vias allowed)
			(pads allowed)
			(copperpour not_allowed)
			(footprints allowed)
		)
		(placement
			(enabled no)
			(sheetname "")
		)
		(fill
			(thermal_gap 0.5)
			(thermal_bridge_width 0.5)
			(island_removal_mode 0)
		)
		(polygon
			(pts
				(arc
					(start 277.941532 -206.932276)
					(mid 277.937812 -206.941256)
					(end 277.928832 -206.944976)
				)
				(arc
					(start 276.455632 -206.944976)
					(mid 276.446652 -206.941256)
					(end 276.442932 -206.932276)
				)
				(arc
					(start 276.442932 -206.437738)
					(mid 276.446652 -206.428758)
					(end 276.455632 -206.425038)
				)
				(arc
					(start 277.928832 -206.425038)
					(mid 277.937812 -206.428758)
					(end 277.941532 -206.437738)
				)
			)
		)
	)
	(zone
		(layer "In1.Cu")
		(hatch none 0.5)
		(connect_pads
			(clearance 0)
		)
		(min_thickness 0.25)
		(keepout
			(tracks not_allowed)
			(vias allowed)
			(pads allowed)
			(copperpour not_allowed)
			(footprints allowed)
		)
		(placement
			(enabled no)
			(sheetname "")
		)
		(fill
			(thermal_gap 0.5)
			(thermal_bridge_width 0.5)
			(island_removal_mode 0)
		)
		(polygon
			(pts
				(arc
					(start 22.45741 -313.182508)
					(mid 22.45369 -313.191488)
					(end 22.44471 -313.195208)
				)
				(arc
					(start 20.97151 -313.195208)
					(mid 20.96253 -313.191488)
					(end 20.95881 -313.182508)
				)
				(arc
					(start 20.95881 -312.68797)
					(mid 20.96253 -312.67899)
					(end 20.97151 -312.67527)
				)
				(arc
					(start 22.44471 -312.67527)
					(mid 22.45369 -312.67899)
					(end 22.45741 -312.68797)
				)
			)
		)
	)
	(zone
		(layer "In1.Cu")
		(hatch none 0.5)
		(connect_pads
			(clearance 0)
		)
		(min_thickness 0.25)
		(keepout
			(tracks not_allowed)
			(vias allowed)
			(pads allowed)
			(copperpour not_allowed)
			(footprints allowed)
		)
		(placement
			(enabled no)
			(sheetname "")
		)
		(fill
			(thermal_gap 0.5)
			(thermal_bridge_width 0.5)
			(island_removal_mode 0)
		)
		(polygon
			(pts
				(arc
					(start 45.089318 -266.432538)
					(mid 45.085598 -266.441518)
					(end 45.076618 -266.445238)
				)
				(arc
					(start 43.603418 -266.445238)
					(mid 43.594438 -266.441518)
					(end 43.590718 -266.432538)
				)
				(arc
					(start 43.590718 -265.938)
					(mid 43.594438 -265.92902)
					(end 43.603418 -265.9253)
				)
				(arc
					(start 45.076618 -265.9253)
					(mid 45.085598 -265.92902)
					(end 45.089318 -265.938)
				)
			)
		)
	)
	(zone
		(layer "In1.Cu")
		(hatch none 0.5)
		(connect_pads
			(clearance 0)
		)
		(min_thickness 0.25)
		(keepout
			(tracks not_allowed)
			(vias allowed)
			(pads allowed)
			(copperpour not_allowed)
			(footprints allowed)
		)
		(placement
			(enabled no)
			(sheetname "")
		)
		(fill
			(thermal_gap 0.5)
			(thermal_bridge_width 0.5)
			(island_removal_mode 0)
		)
		(polygon
			(pts
				(arc
					(start 413.117284 -297.88231)
					(mid 413.113564 -297.89129)
					(end 413.104584 -297.89501)
				)
				(arc
					(start 411.631384 -297.89501)
					(mid 411.622404 -297.89129)
					(end 411.618684 -297.88231)
				)
				(arc
					(start 411.618684 -297.387772)
					(mid 411.622404 -297.378792)
					(end 411.631384 -297.375072)
				)
				(arc
					(start 413.104584 -297.375072)
					(mid 413.113564 -297.378792)
					(end 413.117284 -297.387772)
				)
			)
		)
	)
	(zone
		(layer "In1.Cu")
		(hatch none 0.5)
		(connect_pads
			(clearance 0)
		)
		(min_thickness 0.25)
		(keepout
			(tracks not_allowed)
			(vias allowed)
			(pads allowed)
			(copperpour not_allowed)
			(footprints allowed)
		)
		(placement
			(enabled no)
			(sheetname "")
		)
		(fill
			(thermal_gap 0.5)
			(thermal_bridge_width 0.5)
			(island_removal_mode 0)
		)
		(polygon
			(pts
				(arc
					(start 165.177216 -273.232372)
					(mid 165.173496 -273.241352)
					(end 165.164516 -273.245072)
				)
				(arc
					(start 163.691316 -273.245072)
					(mid 163.682336 -273.241352)
					(end 163.678616 -273.232372)
				)
				(arc
					(start 163.678616 -272.737834)
					(mid 163.682336 -272.728854)
					(end 163.691316 -272.725134)
				)
				(arc
					(start 165.164516 -272.725134)
					(mid 165.173496 -272.728854)
					(end 165.177216 -272.737834)
				)
			)
		)
	)
	(zone
		(layer "In1.Cu")
		(hatch none 0.5)
		(connect_pads
			(clearance 0)
		)
		(min_thickness 0.25)
		(keepout
			(tracks not_allowed)
			(vias allowed)
			(pads allowed)
			(copperpour not_allowed)
			(footprints allowed)
		)
		(placement
			(enabled no)
			(sheetname "")
		)
		(fill
			(thermal_gap 0.5)
			(thermal_bridge_width 0.5)
			(island_removal_mode 0)
		)
		(polygon
			(pts
				(arc
					(start 432.30546 -239.232186)
					(mid 432.30174 -239.241166)
					(end 432.29276 -239.244886)
				)
				(arc
					(start 430.81956 -239.244886)
					(mid 430.81058 -239.241166)
					(end 430.80686 -239.232186)
				)
				(arc
					(start 430.80686 -238.737648)
					(mid 430.81058 -238.728668)
					(end 430.81956 -238.724948)
				)
				(arc
					(start 432.29276 -238.724948)
					(mid 432.30174 -238.728668)
					(end 432.30546 -238.737648)
				)
			)
		)
	)
	(zone
		(layer "In1.Cu")
		(hatch none 0.5)
		(connect_pads
			(clearance 0)
		)
		(min_thickness 0.25)
		(keepout
			(tracks not_allowed)
			(vias allowed)
			(pads allowed)
			(copperpour not_allowed)
			(footprints allowed)
		)
		(placement
			(enabled no)
			(sheetname "")
		)
		(fill
			(thermal_gap 0.5)
			(thermal_bridge_width 0.5)
			(island_removal_mode 0)
		)
		(polygon
			(pts
				(arc
					(start 22.45741 -291.082476)
					(mid 22.45369 -291.091456)
					(end 22.44471 -291.095176)
				)
				(arc
					(start 20.97151 -291.095176)
					(mid 20.96253 -291.091456)
					(end 20.95881 -291.082476)
				)
				(arc
					(start 20.95881 -290.587938)
					(mid 20.96253 -290.578958)
					(end 20.97151 -290.575238)
				)
				(arc
					(start 22.44471 -290.575238)
					(mid 22.45369 -290.578958)
					(end 22.45741 -290.587938)
				)
			)
		)
	)
	(zone
		(layer "In1.Cu")
		(hatch none 0.5)
		(connect_pads
			(clearance 0)
		)
		(min_thickness 0.25)
		(keepout
			(tracks not_allowed)
			(vias allowed)
			(pads allowed)
			(copperpour not_allowed)
			(footprints allowed)
		)
		(placement
			(enabled no)
			(sheetname "")
		)
		(fill
			(thermal_gap 0.5)
			(thermal_bridge_width 0.5)
			(island_removal_mode 0)
		)
		(polygon
			(pts
				(arc
					(start 37.545264 -264.732516)
					(mid 37.541544 -264.741496)
					(end 37.532564 -264.745216)
				)
				(arc
					(start 36.059364 -264.745216)
					(mid 36.050384 -264.741496)
					(end 36.046664 -264.732516)
				)
				(arc
					(start 36.046664 -264.237978)
					(mid 36.050384 -264.228998)
					(end 36.059364 -264.225278)
				)
				(arc
					(start 37.532564 -264.225278)
					(mid 37.541544 -264.228998)
					(end 37.545264 -264.237978)
				)
			)
		)
	)
	(zone
		(layer "In1.Cu")
		(hatch none 0.5)
		(connect_pads
			(clearance 0)
		)
		(min_thickness 0.25)
		(keepout
			(tracks not_allowed)
			(vias allowed)
			(pads allowed)
			(copperpour not_allowed)
			(footprints allowed)
		)
		(placement
			(enabled no)
			(sheetname "")
		)
		(fill
			(thermal_gap 0.5)
			(thermal_bridge_width 0.5)
			(island_removal_mode 0)
		)
		(polygon
			(pts
				(arc
					(start 172.72127 -268.982444)
					(mid 172.71755 -268.991424)
					(end 172.70857 -268.995144)
				)
				(arc
					(start 171.23537 -268.995144)
					(mid 171.22639 -268.991424)
					(end 171.22267 -268.982444)
				)
				(arc
					(start 171.22267 -268.487906)
					(mid 171.22639 -268.478926)
					(end 171.23537 -268.475206)
				)
				(arc
					(start 172.70857 -268.475206)
					(mid 172.71755 -268.478926)
					(end 172.72127 -268.487906)
				)
			)
		)
	)
	(zone
		(layer "In1.Cu")
		(hatch none 0.5)
		(connect_pads
			(clearance 0)
		)
		(min_thickness 0.25)
		(keepout
			(tracks not_allowed)
			(vias allowed)
			(pads allowed)
			(copperpour not_allowed)
			(footprints allowed)
		)
		(placement
			(enabled no)
			(sheetname "")
		)
		(fill
			(thermal_gap 0.5)
			(thermal_bridge_width 0.5)
			(island_removal_mode 0)
		)
		(polygon
			(pts
				(arc
					(start 60.177426 -200.98258)
					(mid 60.173706 -200.99156)
					(end 60.164726 -200.99528)
				)
				(arc
					(start 58.691526 -200.99528)
					(mid 58.682546 -200.99156)
					(end 58.678826 -200.98258)
				)
				(arc
					(start 58.678826 -200.488042)
					(mid 58.682546 -200.479062)
					(end 58.691526 -200.475342)
				)
				(arc
					(start 60.164726 -200.475342)
					(mid 60.173706 -200.479062)
					(end 60.177426 -200.488042)
				)
			)
		)
	)
	(zone
		(layer "In1.Cu")
		(hatch none 0.5)
		(connect_pads
			(clearance 0)
		)
		(min_thickness 0.25)
		(keepout
			(tracks not_allowed)
			(vias allowed)
			(pads allowed)
			(copperpour not_allowed)
			(footprints allowed)
		)
		(placement
			(enabled no)
			(sheetname "")
		)
		(fill
			(thermal_gap 0.5)
			(thermal_bridge_width 0.5)
			(island_removal_mode 0)
		)
		(polygon
			(pts
				(arc
					(start 296.473372 -277.4823)
					(mid 296.469652 -277.49128)
					(end 296.460672 -277.495)
				)
				(arc
					(start 294.987472 -277.495)
					(mid 294.978492 -277.49128)
					(end 294.974772 -277.4823)
				)
				(arc
					(start 294.974772 -276.987762)
					(mid 294.978492 -276.978782)
					(end 294.987472 -276.975062)
				)
				(arc
					(start 296.460672 -276.975062)
					(mid 296.469652 -276.978782)
					(end 296.473372 -276.987762)
				)
			)
		)
	)
	(zone
		(layer "In1.Cu")
		(hatch none 0.5)
		(connect_pads
			(clearance 0)
		)
		(min_thickness 0.25)
		(keepout
			(tracks not_allowed)
			(vias allowed)
			(pads allowed)
			(copperpour not_allowed)
			(footprints allowed)
		)
		(placement
			(enabled no)
			(sheetname "")
		)
		(fill
			(thermal_gap 0.5)
			(thermal_bridge_width 0.5)
			(island_removal_mode 0)
		)
		(polygon
			(pts
				(arc
					(start 37.545264 -244.332506)
					(mid 37.541544 -244.341486)
					(end 37.532564 -244.345206)
				)
				(arc
					(start 36.059364 -244.345206)
					(mid 36.050384 -244.341486)
					(end 36.046664 -244.332506)
				)
				(arc
					(start 36.046664 -243.837968)
					(mid 36.050384 -243.828988)
					(end 36.059364 -243.825268)
				)
				(arc
					(start 37.532564 -243.825268)
					(mid 37.541544 -243.828988)
					(end 37.545264 -243.837968)
				)
			)
		)
	)
	(zone
		(layer "In1.Cu")
		(hatch none 0.5)
		(connect_pads
			(clearance 0)
		)
		(min_thickness 0.25)
		(keepout
			(tracks not_allowed)
			(vias allowed)
			(pads allowed)
			(copperpour not_allowed)
			(footprints allowed)
		)
		(placement
			(enabled no)
			(sheetname "")
		)
		(fill
			(thermal_gap 0.5)
			(thermal_bridge_width 0.5)
			(island_removal_mode 0)
		)
		(polygon
			(pts
				(arc
					(start 413.117284 -308.932326)
					(mid 413.113564 -308.941306)
					(end 413.104584 -308.945026)
				)
				(arc
					(start 411.631384 -308.945026)
					(mid 411.622404 -308.941306)
					(end 411.618684 -308.932326)
				)
				(arc
					(start 411.618684 -308.437788)
					(mid 411.622404 -308.428808)
					(end 411.631384 -308.425088)
				)
				(arc
					(start 413.104584 -308.425088)
					(mid 413.113564 -308.428808)
					(end 413.117284 -308.437788)
				)
			)
		)
	)
	(zone
		(layer "In1.Cu")
		(hatch none 0.5)
		(connect_pads
			(clearance 0)
		)
		(min_thickness 0.25)
		(keepout
			(tracks not_allowed)
			(vias allowed)
			(pads allowed)
			(copperpour not_allowed)
			(footprints allowed)
		)
		(placement
			(enabled no)
			(sheetname "")
		)
		(fill
			(thermal_gap 0.5)
			(thermal_bridge_width 0.5)
			(island_removal_mode 0)
		)
		(polygon
			(pts
				(arc
					(start 162.218624 -391.319258)
					(mid 162.345624 -391.446258)
					(end 162.472624 -391.319258)
				)
				(arc
					(start 162.472624 -391.243058)
					(mid 162.345624 -391.116058)
					(end 162.218624 -391.243058)
				)
			)
		)
	)
	(zone
		(layer "In1.Cu")
		(hatch none 0.5)
		(connect_pads
			(clearance 0)
		)
		(min_thickness 0.25)
		(keepout
			(tracks not_allowed)
			(vias allowed)
			(pads allowed)
			(copperpour not_allowed)
			(footprints allowed)
		)
		(placement
			(enabled no)
			(sheetname "")
		)
		(fill
			(thermal_gap 0.5)
			(thermal_bridge_width 0.5)
			(island_removal_mode 0)
		)
		(polygon
			(pts
				(arc
					(start 265.87831 -297.635168)
					(mid 265.21791 -297.635168)
					(end 265.87831 -297.635168)
				)
			)
		)
	)
	(zone
		(layer "In1.Cu")
		(hatch none 0.5)
		(connect_pads
			(clearance 0)
		)
		(min_thickness 0.25)
		(keepout
			(tracks not_allowed)
			(vias allowed)
			(pads allowed)
			(copperpour not_allowed)
			(footprints allowed)
		)
		(placement
			(enabled no)
			(sheetname "")
		)
		(fill
			(thermal_gap 0.5)
			(thermal_bridge_width 0.5)
			(island_removal_mode 0)
		)
		(polygon
			(pts
				(arc
					(start 176.821338 -208.632552)
					(mid 176.817618 -208.641532)
					(end 176.808638 -208.645252)
				)
				(arc
					(start 175.335438 -208.645252)
					(mid 175.326458 -208.641532)
					(end 175.322738 -208.632552)
				)
				(arc
					(start 175.322738 -208.138014)
					(mid 175.326458 -208.129034)
					(end 175.335438 -208.125314)
				)
				(arc
					(start 176.808638 -208.125314)
					(mid 176.817618 -208.129034)
					(end 176.821338 -208.138014)
				)
			)
		)
	)
	(zone
		(layer "In1.Cu")
		(hatch none 0.5)
		(connect_pads
			(clearance 0)
		)
		(min_thickness 0.25)
		(keepout
			(tracks not_allowed)
			(vias allowed)
			(pads allowed)
			(copperpour not_allowed)
			(footprints allowed)
		)
		(placement
			(enabled no)
			(sheetname "")
		)
		(fill
			(thermal_gap 0.5)
			(thermal_bridge_width 0.5)
			(island_removal_mode 0)
		)
		(polygon
			(pts
				(arc
					(start 199.4535 -239.23244)
					(mid 199.44978 -239.24142)
					(end 199.4408 -239.24514)
				)
				(arc
					(start 197.9676 -239.24514)
					(mid 197.95862 -239.24142)
					(end 197.9549 -239.23244)
				)
				(arc
					(start 197.9549 -238.737902)
					(mid 197.95862 -238.728922)
					(end 197.9676 -238.725202)
				)
				(arc
					(start 199.4408 -238.725202)
					(mid 199.44978 -238.728922)
					(end 199.4535 -238.737902)
				)
			)
		)
	)
	(zone
		(layer "In1.Cu")
		(hatch none 0.5)
		(connect_pads
			(clearance 0)
		)
		(min_thickness 0.25)
		(keepout
			(tracks not_allowed)
			(vias allowed)
			(pads allowed)
			(copperpour not_allowed)
			(footprints allowed)
		)
		(placement
			(enabled no)
			(sheetname "")
		)
		(fill
			(thermal_gap 0.5)
			(thermal_bridge_width 0.5)
			(island_removal_mode 0)
		)
		(polygon
			(pts
				(arc
					(start 22.45741 -244.332506)
					(mid 22.45369 -244.341486)
					(end 22.44471 -244.345206)
				)
				(arc
					(start 20.97151 -244.345206)
					(mid 20.96253 -244.341486)
					(end 20.95881 -244.332506)
				)
				(arc
					(start 20.95881 -243.837968)
					(mid 20.96253 -243.828988)
					(end 20.97151 -243.825268)
				)
				(arc
					(start 22.44471 -243.825268)
					(mid 22.45369 -243.828988)
					(end 22.45741 -243.837968)
				)
			)
		)
	)
	(zone
		(layer "In1.Cu")
		(hatch none 0.5)
		(connect_pads
			(clearance 0)
		)
		(min_thickness 0.25)
		(keepout
			(tracks not_allowed)
			(vias allowed)
			(pads allowed)
			(copperpour not_allowed)
			(footprints allowed)
		)
		(placement
			(enabled no)
			(sheetname "")
		)
		(fill
			(thermal_gap 0.5)
			(thermal_bridge_width 0.5)
			(island_removal_mode 0)
		)
		(polygon
			(pts
				(arc
					(start 165.177216 -207.782414)
					(mid 165.173496 -207.791394)
					(end 165.164516 -207.795114)
				)
				(arc
					(start 163.691316 -207.795114)
					(mid 163.682336 -207.791394)
					(end 163.678616 -207.782414)
				)
				(arc
					(start 163.678616 -207.287876)
					(mid 163.682336 -207.278896)
					(end 163.691316 -207.275176)
				)
				(arc
					(start 165.164516 -207.275176)
					(mid 165.173496 -207.278896)
					(end 165.177216 -207.287876)
				)
			)
		)
	)
	(zone
		(layer "In1.Cu")
		(hatch none 0.5)
		(connect_pads
			(clearance 0)
		)
		(min_thickness 0.25)
		(keepout
			(tracks not_allowed)
			(vias allowed)
			(pads allowed)
			(copperpour not_allowed)
			(footprints allowed)
		)
		(placement
			(enabled no)
			(sheetname "")
		)
		(fill
			(thermal_gap 0.5)
			(thermal_bridge_width 0.5)
			(island_removal_mode 0)
		)
		(polygon
			(pts
				(arc
					(start 311.860946 -393.69238)
					(mid 311.479946 -393.69238)
					(end 311.860946 -393.69238)
				)
			)
		)
	)
	(zone
		(layer "In1.Cu")
		(hatch none 0.5)
		(connect_pads
			(clearance 0)
		)
		(min_thickness 0.25)
		(keepout
			(tracks not_allowed)
			(vias allowed)
			(pads allowed)
			(copperpour not_allowed)
			(footprints allowed)
		)
		(placement
			(enabled no)
			(sheetname "")
		)
		(fill
			(thermal_gap 0.5)
			(thermal_bridge_width 0.5)
			(island_removal_mode 0)
		)
		(polygon
			(pts
				(arc
					(start 382.09093 -399.701258)
					(mid 382.21793 -399.828258)
					(end 382.34493 -399.701258)
				)
				(arc
					(start 382.34493 -399.625058)
					(mid 382.21793 -399.498058)
					(end 382.09093 -399.625058)
				)
			)
		)
	)
	(zone
		(layer "In1.Cu")
		(hatch none 0.5)
		(connect_pads
			(clearance 0)
		)
		(min_thickness 0.25)
		(keepout
			(tracks not_allowed)
			(vias allowed)
			(pads allowed)
			(copperpour not_allowed)
			(footprints allowed)
		)
		(placement
			(enabled no)
			(sheetname "")
		)
		(fill
			(thermal_gap 0.5)
			(thermal_bridge_width 0.5)
			(island_removal_mode 0)
		)
		(polygon
			(pts
				(arc
					(start 169.277284 -297.032426)
					(mid 169.273564 -297.041406)
					(end 169.264584 -297.045126)
				)
				(arc
					(start 167.791384 -297.045126)
					(mid 167.782404 -297.041406)
					(end 167.778684 -297.032426)
				)
				(arc
					(start 167.778684 -296.537888)
					(mid 167.782404 -296.528908)
					(end 167.791384 -296.525188)
				)
				(arc
					(start 169.264584 -296.525188)
					(mid 169.273564 -296.528908)
					(end 169.277284 -296.537888)
				)
			)
		)
	)
	(zone
		(layer "In1.Cu")
		(hatch none 0.5)
		(connect_pads
			(clearance 0)
		)
		(min_thickness 0.25)
		(keepout
			(tracks not_allowed)
			(vias allowed)
			(pads allowed)
			(copperpour not_allowed)
			(footprints allowed)
		)
		(placement
			(enabled no)
			(sheetname "")
		)
		(fill
			(thermal_gap 0.5)
			(thermal_bridge_width 0.5)
			(island_removal_mode 0)
		)
		(polygon
			(pts
				(arc
					(start 151.998172 -383.92227)
					(mid 151.693372 -383.92227)
					(end 151.998172 -383.92227)
				)
			)
		)
	)
	(zone
		(layer "In1.Cu")
		(hatch none 0.5)
		(connect_pads
			(clearance 0)
		)
		(min_thickness 0.25)
		(keepout
			(tracks not_allowed)
			(vias allowed)
			(pads allowed)
			(copperpour not_allowed)
			(footprints allowed)
		)
		(placement
			(enabled no)
			(sheetname "")
		)
		(fill
			(thermal_gap 0.5)
			(thermal_bridge_width 0.5)
			(island_removal_mode 0)
		)
		(polygon
			(pts
				(arc
					(start 87.918798 -391.319258)
					(mid 88.045798 -391.446258)
					(end 88.172798 -391.319258)
				)
				(arc
					(start 88.172798 -391.243058)
					(mid 88.045798 -391.116058)
					(end 87.918798 -391.243058)
				)
			)
		)
	)
	(zone
		(layer "In1.Cu")
		(hatch none 0.5)
		(connect_pads
			(clearance 0)
		)
		(min_thickness 0.25)
		(keepout
			(tracks not_allowed)
			(vias allowed)
			(pads allowed)
			(copperpour not_allowed)
			(footprints allowed)
		)
		(placement
			(enabled no)
			(sheetname "")
		)
		(fill
			(thermal_gap 0.5)
			(thermal_bridge_width 0.5)
			(island_removal_mode 0)
		)
		(polygon
			(pts
				(arc
					(start 450.8373 -221.382082)
					(mid 450.83358 -221.391062)
					(end 450.8246 -221.394782)
				)
				(arc
					(start 449.3514 -221.394782)
					(mid 449.34242 -221.391062)
					(end 449.3387 -221.382082)
				)
				(arc
					(start 449.3387 -220.887544)
					(mid 449.34242 -220.878564)
					(end 449.3514 -220.874844)
				)
				(arc
					(start 450.8246 -220.874844)
					(mid 450.83358 -220.878564)
					(end 450.8373 -220.887544)
				)
			)
		)
	)
	(zone
		(layer "In1.Cu")
		(hatch none 0.5)
		(connect_pads
			(clearance 0)
		)
		(min_thickness 0.25)
		(keepout
			(tracks not_allowed)
			(vias allowed)
			(pads allowed)
			(copperpour not_allowed)
			(footprints allowed)
		)
		(placement
			(enabled no)
			(sheetname "")
		)
		(fill
			(thermal_gap 0.5)
			(thermal_bridge_width 0.5)
			(island_removal_mode 0)
		)
		(polygon
			(pts
				(arc
					(start 304.017426 -248.58218)
					(mid 304.013706 -248.59116)
					(end 304.004726 -248.59488)
				)
				(arc
					(start 302.531526 -248.59488)
					(mid 302.522546 -248.59116)
					(end 302.518826 -248.58218)
				)
				(arc
					(start 302.518826 -248.087642)
					(mid 302.522546 -248.078662)
					(end 302.531526 -248.074942)
				)
				(arc
					(start 304.004726 -248.074942)
					(mid 304.013706 -248.078662)
					(end 304.017426 -248.087642)
				)
			)
		)
	)
	(zone
		(layer "In1.Cu")
		(hatch none 0.5)
		(connect_pads
			(clearance 0)
		)
		(min_thickness 0.25)
		(keepout
			(tracks not_allowed)
			(vias allowed)
			(pads allowed)
			(copperpour not_allowed)
			(footprints allowed)
		)
		(placement
			(enabled no)
			(sheetname "")
		)
		(fill
			(thermal_gap 0.5)
			(thermal_bridge_width 0.5)
			(island_removal_mode 0)
		)
		(polygon
			(pts
				(arc
					(start 165.177216 -217.132408)
					(mid 165.173496 -217.141388)
					(end 165.164516 -217.145108)
				)
				(arc
					(start 163.691316 -217.145108)
					(mid 163.682336 -217.141388)
					(end 163.678616 -217.132408)
				)
				(arc
					(start 163.678616 -216.63787)
					(mid 163.682336 -216.62889)
					(end 163.691316 -216.62517)
				)
				(arc
					(start 165.164516 -216.62517)
					(mid 165.173496 -216.62889)
					(end 165.177216 -216.63787)
				)
			)
		)
	)
	(zone
		(layer "In1.Cu")
		(hatch none 0.5)
		(connect_pads
			(clearance 0)
		)
		(min_thickness 0.25)
		(keepout
			(tracks not_allowed)
			(vias allowed)
			(pads allowed)
			(copperpour not_allowed)
			(footprints allowed)
		)
		(placement
			(enabled no)
			(sheetname "")
		)
		(fill
			(thermal_gap 0.5)
			(thermal_bridge_width 0.5)
			(island_removal_mode 0)
		)
		(polygon
			(pts
				(arc
					(start 202.897232 -235.832396)
					(mid 202.893512 -235.841376)
					(end 202.884532 -235.845096)
				)
				(arc
					(start 201.411332 -235.845096)
					(mid 201.402352 -235.841376)
					(end 201.398632 -235.832396)
				)
				(arc
					(start 201.398632 -235.337858)
					(mid 201.402352 -235.328878)
					(end 201.411332 -235.325158)
				)
				(arc
					(start 202.884532 -235.325158)
					(mid 202.893512 -235.328878)
					(end 202.897232 -235.337858)
				)
			)
		)
	)
	(zone
		(layer "In1.Cu")
		(hatch none 0.5)
		(connect_pads
			(clearance 0)
		)
		(min_thickness 0.25)
		(keepout
			(tracks not_allowed)
			(vias allowed)
			(pads allowed)
			(copperpour not_allowed)
			(footprints allowed)
		)
		(placement
			(enabled no)
			(sheetname "")
		)
		(fill
			(thermal_gap 0.5)
			(thermal_bridge_width 0.5)
			(island_removal_mode 0)
		)
		(polygon
			(pts
				(arc
					(start 304.017426 -265.582146)
					(mid 304.013706 -265.591126)
					(end 304.004726 -265.594846)
				)
				(arc
					(start 302.531526 -265.594846)
					(mid 302.522546 -265.591126)
					(end 302.518826 -265.582146)
				)
				(arc
					(start 302.518826 -265.087608)
					(mid 302.522546 -265.078628)
					(end 302.531526 -265.074908)
				)
				(arc
					(start 304.004726 -265.074908)
					(mid 304.013706 -265.078628)
					(end 304.017426 -265.087608)
				)
			)
		)
	)
	(zone
		(layer "In1.Cu")
		(hatch none 0.5)
		(connect_pads
			(clearance 0)
		)
		(min_thickness 0.25)
		(keepout
			(tracks not_allowed)
			(vias allowed)
			(pads allowed)
			(copperpour not_allowed)
			(footprints allowed)
		)
		(placement
			(enabled no)
			(sheetname "")
		)
		(fill
			(thermal_gap 0.5)
			(thermal_bridge_width 0.5)
			(island_removal_mode 0)
		)
		(polygon
			(pts
				(arc
					(start 454.937368 -229.032308)
					(mid 454.933648 -229.041288)
					(end 454.924668 -229.045008)
				)
				(arc
					(start 453.451468 -229.045008)
					(mid 453.442488 -229.041288)
					(end 453.438768 -229.032308)
				)
				(arc
					(start 453.438768 -228.53777)
					(mid 453.442488 -228.52879)
					(end 453.451468 -228.52507)
				)
				(arc
					(start 454.924668 -228.52507)
					(mid 454.933648 -228.52879)
					(end 454.937368 -228.53777)
				)
			)
		)
	)
	(zone
		(layer "In1.Cu")
		(hatch none 0.5)
		(connect_pads
			(clearance 0)
		)
		(min_thickness 0.25)
		(keepout
			(tracks not_allowed)
			(vias allowed)
			(pads allowed)
			(copperpour not_allowed)
			(footprints allowed)
		)
		(placement
			(enabled no)
			(sheetname "")
		)
		(fill
			(thermal_gap 0.5)
			(thermal_bridge_width 0.5)
			(island_removal_mode 0)
		)
		(polygon
			(pts
				(arc
					(start 30.001464 -247.73255)
					(mid 29.997744 -247.74153)
					(end 29.988764 -247.74525)
				)
				(arc
					(start 28.515564 -247.74525)
					(mid 28.506584 -247.74153)
					(end 28.502864 -247.73255)
				)
				(arc
					(start 28.502864 -247.238012)
					(mid 28.506584 -247.229032)
					(end 28.515564 -247.225312)
				)
				(arc
					(start 29.988764 -247.225312)
					(mid 29.997744 -247.229032)
					(end 30.001464 -247.238012)
				)
			)
		)
	)
	(zone
		(layer "In1.Cu")
		(hatch none 0.5)
		(connect_pads
			(clearance 0)
		)
		(min_thickness 0.25)
		(keepout
			(tracks not_allowed)
			(vias allowed)
			(pads allowed)
			(copperpour not_allowed)
			(footprints allowed)
		)
		(placement
			(enabled no)
			(sheetname "")
		)
		(fill
			(thermal_gap 0.5)
			(thermal_bridge_width 0.5)
			(island_removal_mode 0)
		)
		(polygon
			(pts
				(arc
					(start 116.161058 -386.003292)
					(mid 115.780058 -386.003292)
					(end 116.161058 -386.003292)
				)
			)
		)
	)
	(zone
		(layer "In1.Cu")
		(hatch none 0.5)
		(connect_pads
			(clearance 0)
		)
		(min_thickness 0.25)
		(keepout
			(tracks not_allowed)
			(vias allowed)
			(pads allowed)
			(copperpour not_allowed)
			(footprints allowed)
		)
		(placement
			(enabled no)
			(sheetname "")
		)
		(fill
			(thermal_gap 0.5)
			(thermal_bridge_width 0.5)
			(island_removal_mode 0)
		)
		(polygon
			(pts
				(arc
					(start 124.161296 -385.31038)
					(mid 123.780296 -385.31038)
					(end 124.161296 -385.31038)
				)
			)
		)
	)
	(zone
		(layer "In1.Cu")
		(hatch none 0.5)
		(connect_pads
			(clearance 0)
		)
		(min_thickness 0.25)
		(keepout
			(tracks not_allowed)
			(vias allowed)
			(pads allowed)
			(copperpour not_allowed)
			(footprints allowed)
		)
		(placement
			(enabled no)
			(sheetname "")
		)
		(fill
			(thermal_gap 0.5)
			(thermal_bridge_width 0.5)
			(island_removal_mode 0)
		)
		(polygon
			(pts
				(arc
					(start 176.821338 -270.682466)
					(mid 176.817618 -270.691446)
					(end 176.808638 -270.695166)
				)
				(arc
					(start 175.335438 -270.695166)
					(mid 175.326458 -270.691446)
					(end 175.322738 -270.682466)
				)
				(arc
					(start 175.322738 -270.187928)
					(mid 175.326458 -270.178948)
					(end 175.335438 -270.175228)
				)
				(arc
					(start 176.808638 -270.175228)
					(mid 176.817618 -270.178948)
					(end 176.821338 -270.187928)
				)
			)
		)
	)
	(zone
		(layer "In1.Cu")
		(hatch none 0.5)
		(connect_pads
			(clearance 0)
		)
		(min_thickness 0.25)
		(keepout
			(tracks not_allowed)
			(vias allowed)
			(pads allowed)
			(copperpour not_allowed)
			(footprints allowed)
		)
		(placement
			(enabled no)
			(sheetname "")
		)
		(fill
			(thermal_gap 0.5)
			(thermal_bridge_width 0.5)
			(island_removal_mode 0)
		)
		(polygon
			(pts
				(arc
					(start 81.588864 -389.467344)
					(mid 81.207864 -389.467344)
					(end 81.588864 -389.467344)
				)
			)
		)
	)
	(zone
		(layer "In1.Cu")
		(hatch none 0.5)
		(connect_pads
			(clearance 0)
		)
		(min_thickness 0.25)
		(keepout
			(tracks not_allowed)
			(vias allowed)
			(pads allowed)
			(copperpour not_allowed)
			(footprints allowed)
		)
		(placement
			(enabled no)
			(sheetname "")
		)
		(fill
			(thermal_gap 0.5)
			(thermal_bridge_width 0.5)
			(island_removal_mode 0)
		)
		(polygon
			(pts
				(arc
					(start 273.841464 -314.032138)
					(mid 273.837744 -314.041118)
					(end 273.828764 -314.044838)
				)
				(arc
					(start 272.355564 -314.044838)
					(mid 272.346584 -314.041118)
					(end 272.342864 -314.032138)
				)
				(arc
					(start 272.342864 -313.5376)
					(mid 272.346584 -313.52862)
					(end 272.355564 -313.5249)
				)
				(arc
					(start 273.828764 -313.5249)
					(mid 273.837744 -313.52862)
					(end 273.841464 -313.5376)
				)
			)
		)
	)
	(zone
		(layer "In1.Cu")
		(hatch none 0.5)
		(connect_pads
			(clearance 0)
		)
		(min_thickness 0.25)
		(keepout
			(tracks not_allowed)
			(vias allowed)
			(pads allowed)
			(copperpour not_allowed)
			(footprints allowed)
		)
		(placement
			(enabled no)
			(sheetname "")
		)
		(fill
			(thermal_gap 0.5)
			(thermal_bridge_width 0.5)
			(island_removal_mode 0)
		)
		(polygon
			(pts
				(arc
					(start 165.177216 -263.882378)
					(mid 165.173496 -263.891358)
					(end 165.164516 -263.895078)
				)
				(arc
					(start 163.691316 -263.895078)
					(mid 163.682336 -263.891358)
					(end 163.678616 -263.882378)
				)
				(arc
					(start 163.678616 -263.38784)
					(mid 163.682336 -263.37886)
					(end 163.691316 -263.37514)
				)
				(arc
					(start 165.164516 -263.37514)
					(mid 165.173496 -263.37886)
					(end 165.177216 -263.38784)
				)
			)
		)
	)
	(zone
		(layer "In1.Cu")
		(hatch none 0.5)
		(connect_pads
			(clearance 0)
		)
		(min_thickness 0.25)
		(keepout
			(tracks not_allowed)
			(vias allowed)
			(pads allowed)
			(copperpour not_allowed)
			(footprints allowed)
		)
		(placement
			(enabled no)
			(sheetname "")
		)
		(fill
			(thermal_gap 0.5)
			(thermal_bridge_width 0.5)
			(island_removal_mode 0)
		)
		(polygon
			(pts
				(arc
					(start 172.72127 -201.832464)
					(mid 172.71755 -201.841444)
					(end 172.70857 -201.845164)
				)
				(arc
					(start 171.23537 -201.845164)
					(mid 171.22639 -201.841444)
					(end 171.22267 -201.832464)
				)
				(arc
					(start 171.22267 -201.337926)
					(mid 171.22639 -201.328946)
					(end 171.23537 -201.325226)
				)
				(arc
					(start 172.70857 -201.325226)
					(mid 172.71755 -201.328946)
					(end 172.72127 -201.337926)
				)
			)
		)
	)
	(zone
		(layer "In1.Cu")
		(hatch none 0.5)
		(connect_pads
			(clearance 0)
		)
		(min_thickness 0.25)
		(keepout
			(tracks not_allowed)
			(vias allowed)
			(pads allowed)
			(copperpour not_allowed)
			(footprints allowed)
		)
		(placement
			(enabled no)
			(sheetname "")
		)
		(fill
			(thermal_gap 0.5)
			(thermal_bridge_width 0.5)
			(island_removal_mode 0)
		)
		(polygon
			(pts
				(arc
					(start 169.277284 -315.732414)
					(mid 169.273564 -315.741394)
					(end 169.264584 -315.745114)
				)
				(arc
					(start 167.791384 -315.745114)
					(mid 167.782404 -315.741394)
					(end 167.778684 -315.732414)
				)
				(arc
					(start 167.778684 -315.237876)
					(mid 167.782404 -315.228896)
					(end 167.791384 -315.225176)
				)
				(arc
					(start 169.264584 -315.225176)
					(mid 169.273564 -315.228896)
					(end 169.277284 -315.237876)
				)
			)
		)
	)
	(zone
		(layer "In1.Cu")
		(hatch none 0.5)
		(connect_pads
			(clearance 0)
		)
		(min_thickness 0.25)
		(keepout
			(tracks not_allowed)
			(vias allowed)
			(pads allowed)
			(copperpour not_allowed)
			(footprints allowed)
		)
		(placement
			(enabled no)
			(sheetname "")
		)
		(fill
			(thermal_gap 0.5)
			(thermal_bridge_width 0.5)
			(island_removal_mode 0)
		)
		(polygon
			(pts
				(arc
					(start 187.809378 -304.682398)
					(mid 187.805658 -304.691378)
					(end 187.796678 -304.695098)
				)
				(arc
					(start 186.323478 -304.695098)
					(mid 186.314498 -304.691378)
					(end 186.310778 -304.682398)
				)
				(arc
					(start 186.310778 -304.18786)
					(mid 186.314498 -304.17888)
					(end 186.323478 -304.17516)
				)
				(arc
					(start 187.796678 -304.17516)
					(mid 187.805658 -304.17888)
					(end 187.809378 -304.18786)
				)
			)
		)
	)
	(zone
		(layer "In1.Cu")
		(hatch none 0.5)
		(connect_pads
			(clearance 0)
		)
		(min_thickness 0.25)
		(keepout
			(tracks not_allowed)
			(vias allowed)
			(pads allowed)
			(copperpour not_allowed)
			(footprints allowed)
		)
		(placement
			(enabled no)
			(sheetname "")
		)
		(fill
			(thermal_gap 0.5)
			(thermal_bridge_width 0.5)
			(island_removal_mode 0)
		)
		(polygon
			(pts
				(arc
					(start 270.397478 -306.382166)
					(mid 270.393758 -306.391146)
					(end 270.384778 -306.394866)
				)
				(arc
					(start 268.911578 -306.394866)
					(mid 268.902598 -306.391146)
					(end 268.898878 -306.382166)
				)
				(arc
					(start 268.898878 -305.887628)
					(mid 268.902598 -305.878648)
					(end 268.911578 -305.874928)
				)
				(arc
					(start 270.384778 -305.874928)
					(mid 270.393758 -305.878648)
					(end 270.397478 -305.887628)
				)
			)
		)
	)
	(zone
		(layer "In1.Cu")
		(hatch none 0.5)
		(connect_pads
			(clearance 0)
		)
		(min_thickness 0.25)
		(keepout
			(tracks not_allowed)
			(vias allowed)
			(pads allowed)
			(copperpour not_allowed)
			(footprints allowed)
		)
		(placement
			(enabled no)
			(sheetname "")
		)
		(fill
			(thermal_gap 0.5)
			(thermal_bridge_width 0.5)
			(island_removal_mode 0)
		)
		(polygon
			(pts
				(arc
					(start 285.485332 -300.432216)
					(mid 285.481612 -300.441196)
					(end 285.472632 -300.444916)
				)
				(arc
					(start 283.999432 -300.444916)
					(mid 283.990452 -300.441196)
					(end 283.986732 -300.432216)
				)
				(arc
					(start 283.986732 -299.937678)
					(mid 283.990452 -299.928698)
					(end 283.999432 -299.924978)
				)
				(arc
					(start 285.472632 -299.924978)
					(mid 285.481612 -299.928698)
					(end 285.485332 -299.937678)
				)
			)
		)
	)
	(zone
		(layer "In1.Cu")
		(hatch none 0.5)
		(connect_pads
			(clearance 0)
		)
		(min_thickness 0.25)
		(keepout
			(tracks not_allowed)
			(vias allowed)
			(pads allowed)
			(copperpour not_allowed)
			(footprints allowed)
		)
		(placement
			(enabled no)
			(sheetname "")
		)
		(fill
			(thermal_gap 0.5)
			(thermal_bridge_width 0.5)
			(island_removal_mode 0)
		)
		(polygon
			(pts
				(arc
					(start 172.72127 -213.732364)
					(mid 172.71755 -213.741344)
					(end 172.70857 -213.745064)
				)
				(arc
					(start 171.23537 -213.745064)
					(mid 171.22639 -213.741344)
					(end 171.22267 -213.732364)
				)
				(arc
					(start 171.22267 -213.237826)
					(mid 171.22639 -213.228846)
					(end 171.23537 -213.225126)
				)
				(arc
					(start 172.70857 -213.225126)
					(mid 172.71755 -213.228846)
					(end 172.72127 -213.237826)
				)
			)
		)
	)
	(zone
		(layer "In1.Cu")
		(hatch none 0.5)
		(connect_pads
			(clearance 0)
		)
		(min_thickness 0.25)
		(keepout
			(tracks not_allowed)
			(vias allowed)
			(pads allowed)
			(copperpour not_allowed)
			(footprints allowed)
		)
		(placement
			(enabled no)
			(sheetname "")
		)
		(fill
			(thermal_gap 0.5)
			(thermal_bridge_width 0.5)
			(island_removal_mode 0)
		)
		(polygon
			(pts
				(arc
					(start 64.470534 -389.276844)
					(mid 64.470534 -389.657844)
					(end 64.470534 -389.276844)
				)
			)
		)
	)
	(zone
		(layer "In1.Cu")
		(hatch none 0.5)
		(connect_pads
			(clearance 0)
		)
		(min_thickness 0.25)
		(keepout
			(tracks not_allowed)
			(vias allowed)
			(pads allowed)
			(copperpour not_allowed)
			(footprints allowed)
		)
		(placement
			(enabled no)
			(sheetname "")
		)
		(fill
			(thermal_gap 0.5)
			(thermal_bridge_width 0.5)
			(island_removal_mode 0)
		)
		(polygon
			(pts
				(arc
					(start 432.30546 -298.732194)
					(mid 432.30174 -298.741174)
					(end 432.29276 -298.744894)
				)
				(arc
					(start 430.81956 -298.744894)
					(mid 430.81058 -298.741174)
					(end 430.80686 -298.732194)
				)
				(arc
					(start 430.80686 -298.237656)
					(mid 430.81058 -298.228676)
					(end 430.81956 -298.224956)
				)
				(arc
					(start 432.29276 -298.224956)
					(mid 432.30174 -298.228676)
					(end 432.30546 -298.237656)
				)
			)
		)
	)
	(zone
		(layer "In1.Cu")
		(hatch none 0.5)
		(connect_pads
			(clearance 0)
		)
		(min_thickness 0.25)
		(keepout
			(tracks not_allowed)
			(vias allowed)
			(pads allowed)
			(copperpour not_allowed)
			(footprints allowed)
		)
		(placement
			(enabled no)
			(sheetname "")
		)
		(fill
			(thermal_gap 0.5)
			(thermal_bridge_width 0.5)
			(island_removal_mode 0)
		)
		(polygon
			(pts
				(arc
					(start 45.089318 -263.032494)
					(mid 45.085598 -263.041474)
					(end 45.076618 -263.045194)
				)
				(arc
					(start 43.603418 -263.045194)
					(mid 43.594438 -263.041474)
					(end 43.590718 -263.032494)
				)
				(arc
					(start 43.590718 -262.537956)
					(mid 43.594438 -262.528976)
					(end 43.603418 -262.525256)
				)
				(arc
					(start 45.076618 -262.525256)
					(mid 45.085598 -262.528976)
					(end 45.089318 -262.537956)
				)
			)
		)
	)
	(zone
		(layer "In1.Cu")
		(hatch none 0.5)
		(connect_pads
			(clearance 0)
		)
		(min_thickness 0.25)
		(keepout
			(tracks not_allowed)
			(vias allowed)
			(pads allowed)
			(copperpour not_allowed)
			(footprints allowed)
		)
		(placement
			(enabled no)
			(sheetname "")
		)
		(fill
			(thermal_gap 0.5)
			(thermal_bridge_width 0.5)
			(island_removal_mode 0)
		)
		(polygon
			(pts
				(arc
					(start 424.761406 -238.382302)
					(mid 424.757686 -238.391282)
					(end 424.748706 -238.395002)
				)
				(arc
					(start 423.275506 -238.395002)
					(mid 423.266526 -238.391282)
					(end 423.262806 -238.382302)
				)
				(arc
					(start 423.262806 -237.887764)
					(mid 423.266526 -237.878784)
					(end 423.275506 -237.875064)
				)
				(arc
					(start 424.748706 -237.875064)
					(mid 424.757686 -237.878784)
					(end 424.761406 -237.887764)
				)
			)
		)
	)
	(zone
		(layer "In1.Cu")
		(hatch none 0.5)
		(connect_pads
			(clearance 0)
		)
		(min_thickness 0.25)
		(keepout
			(tracks not_allowed)
			(vias allowed)
			(pads allowed)
			(copperpour not_allowed)
			(footprints allowed)
		)
		(placement
			(enabled no)
			(sheetname "")
		)
		(fill
			(thermal_gap 0.5)
			(thermal_bridge_width 0.5)
			(island_removal_mode 0)
		)
		(polygon
			(pts
				(arc
					(start 350.388682 -397.156432)
					(mid 350.007682 -397.156432)
					(end 350.388682 -397.156432)
				)
			)
		)
	)
	(zone
		(layer "In1.Cu")
		(hatch none 0.5)
		(connect_pads
			(clearance 0)
		)
		(min_thickness 0.25)
		(keepout
			(tracks not_allowed)
			(vias allowed)
			(pads allowed)
			(copperpour not_allowed)
			(footprints allowed)
		)
		(placement
			(enabled no)
			(sheetname "")
		)
		(fill
			(thermal_gap 0.5)
			(thermal_bridge_width 0.5)
			(island_removal_mode 0)
		)
		(polygon
			(pts
				(arc
					(start 303.461166 -397.156432)
					(mid 303.080166 -397.156432)
					(end 303.461166 -397.156432)
				)
			)
		)
	)
	(zone
		(layer "In1.Cu")
		(hatch none 0.5)
		(connect_pads
			(clearance 0)
		)
		(min_thickness 0.25)
		(keepout
			(tracks not_allowed)
			(vias allowed)
			(pads allowed)
			(copperpour not_allowed)
			(footprints allowed)
		)
		(placement
			(enabled no)
			(sheetname "")
		)
		(fill
			(thermal_gap 0.5)
			(thermal_bridge_width 0.5)
			(island_removal_mode 0)
		)
		(polygon
			(pts
				(arc
					(start 124.891038 -391.319258)
					(mid 125.018038 -391.446258)
					(end 125.145038 -391.319258)
				)
				(arc
					(start 125.145038 -391.243058)
					(mid 125.018038 -391.116058)
					(end 124.891038 -391.243058)
				)
			)
		)
	)
	(zone
		(layer "In1.Cu")
		(hatch none 0.5)
		(connect_pads
			(clearance 0)
		)
		(min_thickness 0.25)
		(keepout
			(tracks not_allowed)
			(vias allowed)
			(pads allowed)
			(copperpour not_allowed)
			(footprints allowed)
		)
		(placement
			(enabled no)
			(sheetname "")
		)
		(fill
			(thermal_gap 0.5)
			(thermal_bridge_width 0.5)
			(island_removal_mode 0)
		)
		(polygon
			(pts
				(arc
					(start 435.749446 -296.182288)
					(mid 435.745726 -296.191268)
					(end 435.736746 -296.194988)
				)
				(arc
					(start 434.263546 -296.194988)
					(mid 434.254566 -296.191268)
					(end 434.250846 -296.182288)
				)
				(arc
					(start 434.250846 -295.68775)
					(mid 434.254566 -295.67877)
					(end 434.263546 -295.67505)
				)
				(arc
					(start 435.736746 -295.67505)
					(mid 435.745726 -295.67877)
					(end 435.749446 -295.68775)
				)
			)
		)
	)
	(zone
		(layer "In1.Cu")
		(hatch none 0.5)
		(connect_pads
			(clearance 0)
		)
		(min_thickness 0.25)
		(keepout
			(tracks not_allowed)
			(vias allowed)
			(pads allowed)
			(copperpour not_allowed)
			(footprints allowed)
		)
		(placement
			(enabled no)
			(sheetname "")
		)
		(fill
			(thermal_gap 0.5)
			(thermal_bridge_width 0.5)
			(island_removal_mode 0)
		)
		(polygon
			(pts
				(arc
					(start 191.909446 -200.98258)
					(mid 191.905726 -200.99156)
					(end 191.896746 -200.99528)
				)
				(arc
					(start 190.423546 -200.99528)
					(mid 190.414566 -200.99156)
					(end 190.410846 -200.98258)
				)
				(arc
					(start 190.410846 -200.488042)
					(mid 190.414566 -200.479062)
					(end 190.423546 -200.475342)
				)
				(arc
					(start 191.896746 -200.475342)
					(mid 191.905726 -200.479062)
					(end 191.909446 -200.488042)
				)
			)
		)
	)
	(zone
		(layer "In1.Cu")
		(hatch none 0.5)
		(connect_pads
			(clearance 0)
		)
		(min_thickness 0.25)
		(keepout
			(tracks not_allowed)
			(vias allowed)
			(pads allowed)
			(copperpour not_allowed)
			(footprints allowed)
		)
		(placement
			(enabled no)
			(sheetname "")
		)
		(fill
			(thermal_gap 0.5)
			(thermal_bridge_width 0.5)
			(island_removal_mode 0)
		)
		(polygon
			(pts
				(arc
					(start 428.205392 -314.882276)
					(mid 428.201672 -314.891256)
					(end 428.192692 -314.894976)
				)
				(arc
					(start 426.719492 -314.894976)
					(mid 426.710512 -314.891256)
					(end 426.706792 -314.882276)
				)
				(arc
					(start 426.706792 -314.387738)
					(mid 426.710512 -314.378758)
					(end 426.719492 -314.375038)
				)
				(arc
					(start 428.192692 -314.375038)
					(mid 428.201672 -314.378758)
					(end 428.205392 -314.387738)
				)
			)
		)
	)
	(zone
		(layer "In1.Cu")
		(hatch none 0.5)
		(connect_pads
			(clearance 0)
		)
		(min_thickness 0.25)
		(keepout
			(tracks not_allowed)
			(vias allowed)
			(pads allowed)
			(copperpour not_allowed)
			(footprints allowed)
		)
		(placement
			(enabled no)
			(sheetname "")
		)
		(fill
			(thermal_gap 0.5)
			(thermal_bridge_width 0.5)
			(island_removal_mode 0)
		)
		(polygon
			(pts
				(arc
					(start 313.460892 -397.849344)
					(mid 313.079892 -397.849344)
					(end 313.460892 -397.849344)
				)
			)
		)
	)
	(zone
		(layer "In1.Cu")
		(hatch none 0.5)
		(connect_pads
			(clearance 0)
		)
		(min_thickness 0.25)
		(keepout
			(tracks not_allowed)
			(vias allowed)
			(pads allowed)
			(copperpour not_allowed)
			(footprints allowed)
		)
		(placement
			(enabled no)
			(sheetname "")
		)
		(fill
			(thermal_gap 0.5)
			(thermal_bridge_width 0.5)
			(island_removal_mode 0)
		)
		(polygon
			(pts
				(arc
					(start 312.590688 -399.701258)
					(mid 312.717688 -399.828258)
					(end 312.844688 -399.701258)
				)
				(arc
					(start 312.844688 -399.625058)
					(mid 312.717688 -399.498058)
					(end 312.590688 -399.625058)
				)
			)
		)
	)
	(zone
		(layer "In1.Cu")
		(hatch none 0.5)
		(connect_pads
			(clearance 0)
		)
		(min_thickness 0.25)
		(keepout
			(tracks not_allowed)
			(vias allowed)
			(pads allowed)
			(copperpour not_allowed)
			(footprints allowed)
		)
		(placement
			(enabled no)
			(sheetname "")
		)
		(fill
			(thermal_gap 0.5)
			(thermal_bridge_width 0.5)
			(island_removal_mode 0)
		)
		(polygon
			(pts
				(arc
					(start 266.29741 -318.28232)
					(mid 266.29369 -318.2913)
					(end 266.28471 -318.29502)
				)
				(arc
					(start 264.81151 -318.29502)
					(mid 264.80253 -318.2913)
					(end 264.79881 -318.28232)
				)
				(arc
					(start 264.79881 -317.787782)
					(mid 264.80253 -317.778802)
					(end 264.81151 -317.775082)
				)
				(arc
					(start 266.28471 -317.775082)
					(mid 266.29369 -317.778802)
					(end 266.29741 -317.787782)
				)
			)
		)
	)
	(zone
		(layer "In1.Cu")
		(hatch none 0.5)
		(connect_pads
			(clearance 0)
		)
		(min_thickness 0.25)
		(keepout
			(tracks not_allowed)
			(vias allowed)
			(pads allowed)
			(copperpour not_allowed)
			(footprints allowed)
		)
		(placement
			(enabled no)
			(sheetname "")
		)
		(fill
			(thermal_gap 0.5)
			(thermal_bridge_width 0.5)
			(island_removal_mode 0)
		)
		(polygon
			(pts
				(arc
					(start 293.029386 -229.882192)
					(mid 293.025666 -229.891172)
					(end 293.016686 -229.894892)
				)
				(arc
					(start 291.543486 -229.894892)
					(mid 291.534506 -229.891172)
					(end 291.530786 -229.882192)
				)
				(arc
					(start 291.530786 -229.387654)
					(mid 291.534506 -229.378674)
					(end 291.543486 -229.374954)
				)
				(arc
					(start 293.016686 -229.374954)
					(mid 293.025666 -229.378674)
					(end 293.029386 -229.387654)
				)
			)
		)
	)
	(zone
		(layer "In1.Cu")
		(hatch none 0.5)
		(connect_pads
			(clearance 0)
		)
		(min_thickness 0.25)
		(keepout
			(tracks not_allowed)
			(vias allowed)
			(pads allowed)
			(copperpour not_allowed)
			(footprints allowed)
		)
		(placement
			(enabled no)
			(sheetname "")
		)
		(fill
			(thermal_gap 0.5)
			(thermal_bridge_width 0.5)
			(island_removal_mode 0)
		)
		(polygon
			(pts
				(arc
					(start 411.59811 -399.143474)
					(mid 411.29331 -399.143474)
					(end 411.59811 -399.143474)
				)
			)
		)
	)
	(zone
		(layer "In1.Cu")
		(hatch none 0.5)
		(connect_pads
			(clearance 0)
		)
		(min_thickness 0.25)
		(keepout
			(tracks not_allowed)
			(vias allowed)
			(pads allowed)
			(copperpour not_allowed)
			(footprints allowed)
		)
		(placement
			(enabled no)
			(sheetname "")
		)
		(fill
			(thermal_gap 0.5)
			(thermal_bridge_width 0.5)
			(island_removal_mode 0)
		)
		(polygon
			(pts
				(arc
					(start 405.488902 -397.156432)
					(mid 405.107902 -397.156432)
					(end 405.488902 -397.156432)
				)
			)
		)
	)
	(zone
		(layer "In1.Cu")
		(hatch none 0.5)
		(connect_pads
			(clearance 0)
		)
		(min_thickness 0.25)
		(keepout
			(tracks not_allowed)
			(vias allowed)
			(pads allowed)
			(copperpour not_allowed)
			(footprints allowed)
		)
		(placement
			(enabled no)
			(sheetname "")
		)
		(fill
			(thermal_gap 0.5)
			(thermal_bridge_width 0.5)
			(island_removal_mode 0)
		)
		(polygon
			(pts
				(arc
					(start 195.353432 -288.53257)
					(mid 195.349712 -288.54155)
					(end 195.340732 -288.54527)
				)
				(arc
					(start 193.867532 -288.54527)
					(mid 193.858552 -288.54155)
					(end 193.854832 -288.53257)
				)
				(arc
					(start 193.854832 -288.038032)
					(mid 193.858552 -288.029052)
					(end 193.867532 -288.025332)
				)
				(arc
					(start 195.340732 -288.025332)
					(mid 195.349712 -288.029052)
					(end 195.353432 -288.038032)
				)
			)
		)
	)
	(zone
		(layer "In1.Cu")
		(hatch none 0.5)
		(connect_pads
			(clearance 0)
		)
		(min_thickness 0.25)
		(keepout
			(tracks not_allowed)
			(vias allowed)
			(pads allowed)
			(copperpour not_allowed)
			(footprints allowed)
		)
		(placement
			(enabled no)
			(sheetname "")
		)
		(fill
			(thermal_gap 0.5)
			(thermal_bridge_width 0.5)
			(island_removal_mode 0)
		)
		(polygon
			(pts
				(arc
					(start 339.588856 -393.69238)
					(mid 339.207856 -393.69238)
					(end 339.588856 -393.69238)
				)
			)
		)
	)
	(zone
		(layer "In1.Cu")
		(hatch none 0.5)
		(connect_pads
			(clearance 0)
		)
		(min_thickness 0.25)
		(keepout
			(tracks not_allowed)
			(vias allowed)
			(pads allowed)
			(copperpour not_allowed)
			(footprints allowed)
		)
		(placement
			(enabled no)
			(sheetname "")
		)
		(fill
			(thermal_gap 0.5)
			(thermal_bridge_width 0.5)
			(island_removal_mode 0)
		)
		(polygon
			(pts
				(arc
					(start 273.841464 -318.28232)
					(mid 273.837744 -318.2913)
					(end 273.828764 -318.29502)
				)
				(arc
					(start 272.355564 -318.29502)
					(mid 272.346584 -318.2913)
					(end 272.342864 -318.28232)
				)
				(arc
					(start 272.342864 -317.787782)
					(mid 272.346584 -317.778802)
					(end 272.355564 -317.775082)
				)
				(arc
					(start 273.828764 -317.775082)
					(mid 273.837744 -317.778802)
					(end 273.841464 -317.787782)
				)
			)
		)
	)
	(zone
		(layer "In1.Cu")
		(hatch none 0.5)
		(connect_pads
			(clearance 0)
		)
		(min_thickness 0.25)
		(keepout
			(tracks not_allowed)
			(vias allowed)
			(pads allowed)
			(copperpour not_allowed)
			(footprints allowed)
		)
		(placement
			(enabled no)
			(sheetname "")
		)
		(fill
			(thermal_gap 0.5)
			(thermal_bridge_width 0.5)
			(island_removal_mode 0)
		)
		(polygon
			(pts
				(arc
					(start 119.470424 -390.761474)
					(mid 119.165624 -390.761474)
					(end 119.470424 -390.761474)
				)
			)
		)
	)
	(zone
		(layer "In1.Cu")
		(hatch none 0.5)
		(connect_pads
			(clearance 0)
		)
		(min_thickness 0.25)
		(keepout
			(tracks not_allowed)
			(vias allowed)
			(pads allowed)
			(copperpour not_allowed)
			(footprints allowed)
		)
		(placement
			(enabled no)
			(sheetname "")
		)
		(fill
			(thermal_gap 0.5)
			(thermal_bridge_width 0.5)
			(island_removal_mode 0)
		)
		(polygon
			(pts
				(arc
					(start 85.98916 -385.31038)
					(mid 85.60816 -385.31038)
					(end 85.98916 -385.31038)
				)
			)
		)
	)
	(zone
		(layer "In1.Cu")
		(hatch none 0.5)
		(connect_pads
			(clearance 0)
		)
		(min_thickness 0.25)
		(keepout
			(tracks not_allowed)
			(vias allowed)
			(pads allowed)
			(copperpour not_allowed)
			(footprints allowed)
		)
		(placement
			(enabled no)
			(sheetname "")
		)
		(fill
			(thermal_gap 0.5)
			(thermal_bridge_width 0.5)
			(island_removal_mode 0)
		)
		(polygon
			(pts
				(arc
					(start 40.98925 -235.832396)
					(mid 40.98553 -235.841376)
					(end 40.97655 -235.845096)
				)
				(arc
					(start 39.50335 -235.845096)
					(mid 39.49437 -235.841376)
					(end 39.49065 -235.832396)
				)
				(arc
					(start 39.49065 -235.337858)
					(mid 39.49437 -235.328878)
					(end 39.50335 -235.325158)
				)
				(arc
					(start 40.97655 -235.325158)
					(mid 40.98553 -235.328878)
					(end 40.98925 -235.337858)
				)
			)
		)
	)
	(zone
		(layer "In1.Cu")
		(hatch none 0.5)
		(connect_pads
			(clearance 0)
		)
		(min_thickness 0.25)
		(keepout
			(tracks not_allowed)
			(vias allowed)
			(pads allowed)
			(copperpour not_allowed)
			(footprints allowed)
		)
		(placement
			(enabled no)
			(sheetname "")
		)
		(fill
			(thermal_gap 0.5)
			(thermal_bridge_width 0.5)
			(island_removal_mode 0)
		)
		(polygon
			(pts
				(arc
					(start 37.545264 -285.98241)
					(mid 37.541544 -285.99139)
					(end 37.532564 -285.99511)
				)
				(arc
					(start 36.059364 -285.99511)
					(mid 36.050384 -285.99139)
					(end 36.046664 -285.98241)
				)
				(arc
					(start 36.046664 -285.487872)
					(mid 36.050384 -285.478892)
					(end 36.059364 -285.475172)
				)
				(arc
					(start 37.532564 -285.475172)
					(mid 37.541544 -285.478892)
					(end 37.545264 -285.487872)
				)
			)
		)
	)
	(zone
		(layer "In1.Cu")
		(hatch none 0.5)
		(connect_pads
			(clearance 0)
		)
		(min_thickness 0.25)
		(keepout
			(tracks not_allowed)
			(vias allowed)
			(pads allowed)
			(copperpour not_allowed)
			(footprints allowed)
		)
		(placement
			(enabled no)
			(sheetname "")
		)
		(fill
			(thermal_gap 0.5)
			(thermal_bridge_width 0.5)
			(island_removal_mode 0)
		)
		(polygon
			(pts
				(arc
					(start 266.29741 -212.032088)
					(mid 266.29369 -212.041068)
					(end 266.28471 -212.044788)
				)
				(arc
					(start 264.81151 -212.044788)
					(mid 264.80253 -212.041068)
					(end 264.79881 -212.032088)
				)
				(arc
					(start 264.79881 -211.53755)
					(mid 264.80253 -211.52857)
					(end 264.81151 -211.52485)
				)
				(arc
					(start 266.28471 -211.52485)
					(mid 266.29369 -211.52857)
					(end 266.29741 -211.53755)
				)
			)
		)
	)
	(zone
		(layer "In1.Cu")
		(hatch none 0.5)
		(connect_pads
			(clearance 0)
		)
		(min_thickness 0.25)
		(keepout
			(tracks not_allowed)
			(vias allowed)
			(pads allowed)
			(copperpour not_allowed)
			(footprints allowed)
		)
		(placement
			(enabled no)
			(sheetname "")
		)
		(fill
			(thermal_gap 0.5)
			(thermal_bridge_width 0.5)
			(island_removal_mode 0)
		)
		(polygon
			(pts
				(arc
					(start 447.393568 -302.132238)
					(mid 447.389848 -302.141218)
					(end 447.380868 -302.144938)
				)
				(arc
					(start 445.907668 -302.144938)
					(mid 445.898688 -302.141218)
					(end 445.894968 -302.132238)
				)
				(arc
					(start 445.894968 -301.6377)
					(mid 445.898688 -301.62872)
					(end 445.907668 -301.625)
				)
				(arc
					(start 447.380868 -301.625)
					(mid 447.389848 -301.62872)
					(end 447.393568 -301.6377)
				)
			)
		)
	)
	(zone
		(layer "In1.Cu")
		(hatch none 0.5)
		(connect_pads
			(clearance 0)
		)
		(min_thickness 0.25)
		(keepout
			(tracks not_allowed)
			(vias allowed)
			(pads allowed)
			(copperpour not_allowed)
			(footprints allowed)
		)
		(placement
			(enabled no)
			(sheetname "")
		)
		(fill
			(thermal_gap 0.5)
			(thermal_bridge_width 0.5)
			(island_removal_mode 0)
		)
		(polygon
			(pts
				(arc
					(start 413.117284 -305.532282)
					(mid 413.113564 -305.541262)
					(end 413.104584 -305.544982)
				)
				(arc
					(start 411.631384 -305.544982)
					(mid 411.622404 -305.541262)
					(end 411.618684 -305.532282)
				)
				(arc
					(start 411.618684 -305.037744)
					(mid 411.622404 -305.028764)
					(end 411.631384 -305.025044)
				)
				(arc
					(start 413.104584 -305.025044)
					(mid 413.113564 -305.028764)
					(end 413.117284 -305.037744)
				)
			)
		)
	)
	(zone
		(layer "In1.Cu")
		(hatch none 0.5)
		(connect_pads
			(clearance 0)
		)
		(min_thickness 0.25)
		(keepout
			(tracks not_allowed)
			(vias allowed)
			(pads allowed)
			(copperpour not_allowed)
			(footprints allowed)
		)
		(placement
			(enabled no)
			(sheetname "")
		)
		(fill
			(thermal_gap 0.5)
			(thermal_bridge_width 0.5)
			(island_removal_mode 0)
		)
		(polygon
			(pts
				(arc
					(start 277.941532 -203.532232)
					(mid 277.937812 -203.541212)
					(end 277.928832 -203.544932)
				)
				(arc
					(start 276.455632 -203.544932)
					(mid 276.446652 -203.541212)
					(end 276.442932 -203.532232)
				)
				(arc
					(start 276.442932 -203.037694)
					(mid 276.446652 -203.028714)
					(end 276.455632 -203.024994)
				)
				(arc
					(start 277.928832 -203.024994)
					(mid 277.937812 -203.028714)
					(end 277.941532 -203.037694)
				)
			)
		)
	)
	(zone
		(layer "In1.Cu")
		(hatch none 0.5)
		(connect_pads
			(clearance 0)
		)
		(min_thickness 0.25)
		(keepout
			(tracks not_allowed)
			(vias allowed)
			(pads allowed)
			(copperpour not_allowed)
			(footprints allowed)
		)
		(placement
			(enabled no)
			(sheetname "")
		)
		(fill
			(thermal_gap 0.5)
			(thermal_bridge_width 0.5)
			(island_removal_mode 0)
		)
		(polygon
			(pts
				(arc
					(start 172.72127 -218.83243)
					(mid 172.71755 -218.84141)
					(end 172.70857 -218.84513)
				)
				(arc
					(start 171.23537 -218.84513)
					(mid 171.22639 -218.84141)
					(end 171.22267 -218.83243)
				)
				(arc
					(start 171.22267 -218.337892)
					(mid 171.22639 -218.328912)
					(end 171.23537 -218.325192)
				)
				(arc
					(start 172.70857 -218.325192)
					(mid 172.71755 -218.328912)
					(end 172.72127 -218.337892)
				)
			)
		)
	)
	(zone
		(layer "In1.Cu")
		(hatch none 0.5)
		(connect_pads
			(clearance 0)
		)
		(min_thickness 0.25)
		(keepout
			(tracks not_allowed)
			(vias allowed)
			(pads allowed)
			(copperpour not_allowed)
			(footprints allowed)
		)
		(placement
			(enabled no)
			(sheetname "")
		)
		(fill
			(thermal_gap 0.5)
			(thermal_bridge_width 0.5)
			(island_removal_mode 0)
		)
		(polygon
			(pts
				(arc
					(start 270.397478 -206.932276)
					(mid 270.393758 -206.941256)
					(end 270.384778 -206.944976)
				)
				(arc
					(start 268.911578 -206.944976)
					(mid 268.902598 -206.941256)
					(end 268.898878 -206.932276)
				)
				(arc
					(start 268.898878 -206.437738)
					(mid 268.902598 -206.428758)
					(end 268.911578 -206.425038)
				)
				(arc
					(start 270.384778 -206.425038)
					(mid 270.393758 -206.428758)
					(end 270.397478 -206.437738)
				)
			)
		)
	)
	(zone
		(layer "In1.Cu")
		(hatch none 0.5)
		(connect_pads
			(clearance 0)
		)
		(min_thickness 0.25)
		(keepout
			(tracks not_allowed)
			(vias allowed)
			(pads allowed)
			(copperpour not_allowed)
			(footprints allowed)
		)
		(placement
			(enabled no)
			(sheetname "")
		)
		(fill
			(thermal_gap 0.5)
			(thermal_bridge_width 0.5)
			(island_removal_mode 0)
		)
		(polygon
			(pts
				(arc
					(start 80.388968 -386.003292)
					(mid 80.007968 -386.003292)
					(end 80.388968 -386.003292)
				)
			)
		)
	)
	(zone
		(layer "In1.Cu")
		(hatch none 0.5)
		(connect_pads
			(clearance 0)
		)
		(min_thickness 0.25)
		(keepout
			(tracks not_allowed)
			(vias allowed)
			(pads allowed)
			(copperpour not_allowed)
			(footprints allowed)
		)
		(placement
			(enabled no)
			(sheetname "")
		)
		(fill
			(thermal_gap 0.5)
			(thermal_bridge_width 0.5)
			(island_removal_mode 0)
		)
		(polygon
			(pts
				(arc
					(start 432.30546 -201.83221)
					(mid 432.30174 -201.84119)
					(end 432.29276 -201.84491)
				)
				(arc
					(start 430.81956 -201.84491)
					(mid 430.81058 -201.84119)
					(end 430.80686 -201.83221)
				)
				(arc
					(start 430.80686 -201.337672)
					(mid 430.81058 -201.328692)
					(end 430.81956 -201.324972)
				)
				(arc
					(start 432.29276 -201.324972)
					(mid 432.30174 -201.328692)
					(end 432.30546 -201.337672)
				)
			)
		)
	)
	(zone
		(layer "In1.Cu")
		(hatch none 0.5)
		(connect_pads
			(clearance 0)
		)
		(min_thickness 0.25)
		(keepout
			(tracks not_allowed)
			(vias allowed)
			(pads allowed)
			(copperpour not_allowed)
			(footprints allowed)
		)
		(placement
			(enabled no)
			(sheetname "")
		)
		(fill
			(thermal_gap 0.5)
			(thermal_bridge_width 0.5)
			(island_removal_mode 0)
		)
		(polygon
			(pts
				(arc
					(start 180.265324 -286.832548)
					(mid 180.261604 -286.841528)
					(end 180.252624 -286.845248)
				)
				(arc
					(start 178.779424 -286.845248)
					(mid 178.770444 -286.841528)
					(end 178.766724 -286.832548)
				)
				(arc
					(start 178.766724 -286.33801)
					(mid 178.770444 -286.32903)
					(end 178.779424 -286.32531)
				)
				(arc
					(start 180.252624 -286.32531)
					(mid 180.261604 -286.32903)
					(end 180.265324 -286.33801)
				)
			)
		)
	)
	(zone
		(layer "In1.Cu")
		(hatch none 0.5)
		(connect_pads
			(clearance 0)
		)
		(min_thickness 0.25)
		(keepout
			(tracks not_allowed)
			(vias allowed)
			(pads allowed)
			(copperpour not_allowed)
			(footprints allowed)
		)
		(placement
			(enabled no)
			(sheetname "")
		)
		(fill
			(thermal_gap 0.5)
			(thermal_bridge_width 0.5)
			(island_removal_mode 0)
		)
		(polygon
			(pts
				(arc
					(start 417.217352 -247.732296)
					(mid 417.213632 -247.741276)
					(end 417.204652 -247.744996)
				)
				(arc
					(start 415.731452 -247.744996)
					(mid 415.722472 -247.741276)
					(end 415.718752 -247.732296)
				)
				(arc
					(start 415.718752 -247.237758)
					(mid 415.722472 -247.228778)
					(end 415.731452 -247.225058)
				)
				(arc
					(start 417.204652 -247.225058)
					(mid 417.213632 -247.228778)
					(end 417.217352 -247.237758)
				)
			)
		)
	)
	(zone
		(layer "In1.Cu")
		(hatch none 0.5)
		(connect_pads
			(clearance 0)
		)
		(min_thickness 0.25)
		(keepout
			(tracks not_allowed)
			(vias allowed)
			(pads allowed)
			(copperpour not_allowed)
			(footprints allowed)
		)
		(placement
			(enabled no)
			(sheetname "")
		)
		(fill
			(thermal_gap 0.5)
			(thermal_bridge_width 0.5)
			(island_removal_mode 0)
		)
		(polygon
			(pts
				(arc
					(start 22.45741 -252.832362)
					(mid 22.45369 -252.841342)
					(end 22.44471 -252.845062)
				)
				(arc
					(start 20.97151 -252.845062)
					(mid 20.96253 -252.841342)
					(end 20.95881 -252.832362)
				)
				(arc
					(start 20.95881 -252.337824)
					(mid 20.96253 -252.328844)
					(end 20.97151 -252.325124)
				)
				(arc
					(start 22.44471 -252.325124)
					(mid 22.45369 -252.328844)
					(end 22.45741 -252.337824)
				)
			)
		)
	)
	(zone
		(layer "In1.Cu")
		(hatch none 0.5)
		(connect_pads
			(clearance 0)
		)
		(min_thickness 0.25)
		(keepout
			(tracks not_allowed)
			(vias allowed)
			(pads allowed)
			(copperpour not_allowed)
			(footprints allowed)
		)
		(placement
			(enabled no)
			(sheetname "")
		)
		(fill
			(thermal_gap 0.5)
			(thermal_bridge_width 0.5)
			(island_removal_mode 0)
		)
		(polygon
			(pts
				(arc
					(start 439.849514 -304.682144)
					(mid 439.845794 -304.691124)
					(end 439.836814 -304.694844)
				)
				(arc
					(start 438.363614 -304.694844)
					(mid 438.354634 -304.691124)
					(end 438.350914 -304.682144)
				)
				(arc
					(start 438.350914 -304.187606)
					(mid 438.354634 -304.178626)
					(end 438.363614 -304.174906)
				)
				(arc
					(start 439.836814 -304.174906)
					(mid 439.845794 -304.178626)
					(end 439.849514 -304.187606)
				)
			)
		)
	)
	(zone
		(layer "In1.Cu")
		(hatch none 0.5)
		(connect_pads
			(clearance 0)
		)
		(min_thickness 0.25)
		(keepout
			(tracks not_allowed)
			(vias allowed)
			(pads allowed)
			(copperpour not_allowed)
			(footprints allowed)
		)
		(placement
			(enabled no)
			(sheetname "")
		)
		(fill
			(thermal_gap 0.5)
			(thermal_bridge_width 0.5)
			(island_removal_mode 0)
		)
		(polygon
			(pts
				(arc
					(start 56.077358 -312.33237)
					(mid 56.073638 -312.34135)
					(end 56.064658 -312.34507)
				)
				(arc
					(start 54.591458 -312.34507)
					(mid 54.582478 -312.34135)
					(end 54.578758 -312.33237)
				)
				(arc
					(start 54.578758 -311.837832)
					(mid 54.582478 -311.828852)
					(end 54.591458 -311.825132)
				)
				(arc
					(start 56.064658 -311.825132)
					(mid 56.073638 -311.828852)
					(end 56.077358 -311.837832)
				)
			)
		)
	)
	(zone
		(layer "In1.Cu")
		(hatch none 0.5)
		(connect_pads
			(clearance 0)
		)
		(min_thickness 0.25)
		(keepout
			(tracks not_allowed)
			(vias allowed)
			(pads allowed)
			(copperpour not_allowed)
			(footprints allowed)
		)
		(placement
			(enabled no)
			(sheetname "")
		)
		(fill
			(thermal_gap 0.5)
			(thermal_bridge_width 0.5)
			(island_removal_mode 0)
		)
		(polygon
			(pts
				(arc
					(start 450.8373 -285.982156)
					(mid 450.83358 -285.991136)
					(end 450.8246 -285.994856)
				)
				(arc
					(start 449.3514 -285.994856)
					(mid 449.34242 -285.991136)
					(end 449.3387 -285.982156)
				)
				(arc
					(start 449.3387 -285.487618)
					(mid 449.34242 -285.478638)
					(end 449.3514 -285.474918)
				)
				(arc
					(start 450.8246 -285.474918)
					(mid 450.83358 -285.478638)
					(end 450.8373 -285.487618)
				)
			)
		)
	)
	(zone
		(layer "In1.Cu")
		(hatch none 0.5)
		(connect_pads
			(clearance 0)
		)
		(min_thickness 0.25)
		(keepout
			(tracks not_allowed)
			(vias allowed)
			(pads allowed)
			(copperpour not_allowed)
			(footprints allowed)
		)
		(placement
			(enabled no)
			(sheetname "")
		)
		(fill
			(thermal_gap 0.5)
			(thermal_bridge_width 0.5)
			(island_removal_mode 0)
		)
		(polygon
			(pts
				(arc
					(start 416.25139 -11.91768)
					(mid 416.229072 -11.971562)
					(end 416.17519 -11.99388)
				)
				(arc
					(start 415.138616 -11.99388)
					(mid 415.084734 -11.971562)
					(end 415.062416 -11.91768)
				)
				(arc
					(start 415.062416 -10.51814)
					(mid 415.084734 -10.464258)
					(end 415.138616 -10.44194)
				)
				(arc
					(start 416.17519 -10.44194)
					(mid 416.229072 -10.464258)
					(end 416.25139 -10.51814)
				)
			)
		)
	)
	(zone
		(layer "In1.Cu")
		(hatch none 0.5)
		(connect_pads
			(clearance 0)
		)
		(min_thickness 0.25)
		(keepout
			(tracks not_allowed)
			(vias allowed)
			(pads allowed)
			(copperpour not_allowed)
			(footprints allowed)
		)
		(placement
			(enabled no)
			(sheetname "")
		)
		(fill
			(thermal_gap 0.5)
			(thermal_bridge_width 0.5)
			(island_removal_mode 0)
		)
		(polygon
			(pts
				(arc
					(start 18.357342 -228.182424)
					(mid 18.353622 -228.191404)
					(end 18.344642 -228.195124)
				)
				(arc
					(start 16.871442 -228.195124)
					(mid 16.862462 -228.191404)
					(end 16.858742 -228.182424)
				)
				(arc
					(start 16.858742 -227.687886)
					(mid 16.862462 -227.678906)
					(end 16.871442 -227.675186)
				)
				(arc
					(start 18.344642 -227.675186)
					(mid 18.353622 -227.678906)
					(end 18.357342 -227.687886)
				)
			)
		)
	)
	(zone
		(layer "In1.Cu")
		(hatch none 0.5)
		(connect_pads
			(clearance 0)
		)
		(min_thickness 0.25)
		(keepout
			(tracks not_allowed)
			(vias allowed)
			(pads allowed)
			(copperpour not_allowed)
			(footprints allowed)
		)
		(placement
			(enabled no)
			(sheetname "")
		)
		(fill
			(thermal_gap 0.5)
			(thermal_bridge_width 0.5)
			(island_removal_mode 0)
		)
		(polygon
			(pts
				(arc
					(start 81.91881 -383.440686)
					(mid 82.04581 -383.567686)
					(end 82.17281 -383.440686)
				)
				(arc
					(start 82.17281 -383.364486)
					(mid 82.04581 -383.237486)
					(end 81.91881 -383.364486)
				)
			)
		)
	)
	(zone
		(layer "In1.Cu")
		(hatch none 0.5)
		(connect_pads
			(clearance 0)
		)
		(min_thickness 0.25)
		(keepout
			(tracks not_allowed)
			(vias allowed)
			(pads allowed)
			(copperpour not_allowed)
			(footprints allowed)
		)
		(placement
			(enabled no)
			(sheetname "")
		)
		(fill
			(thermal_gap 0.5)
			(thermal_bridge_width 0.5)
			(island_removal_mode 0)
		)
		(polygon
			(pts
				(arc
					(start 172.72127 -239.23244)
					(mid 172.71755 -239.24142)
					(end 172.70857 -239.24514)
				)
				(arc
					(start 171.23537 -239.24514)
					(mid 171.22639 -239.24142)
					(end 171.22267 -239.23244)
				)
				(arc
					(start 171.22267 -238.737902)
					(mid 171.22639 -238.728922)
					(end 171.23537 -238.725202)
				)
				(arc
					(start 172.70857 -238.725202)
					(mid 172.71755 -238.728922)
					(end 172.72127 -238.737902)
				)
			)
		)
	)
	(zone
		(layer "In1.Cu")
		(hatch none 0.5)
		(connect_pads
			(clearance 0)
		)
		(min_thickness 0.25)
		(keepout
			(tracks not_allowed)
			(vias allowed)
			(pads allowed)
			(copperpour not_allowed)
			(footprints allowed)
		)
		(placement
			(enabled no)
			(sheetname "")
		)
		(fill
			(thermal_gap 0.5)
			(thermal_bridge_width 0.5)
			(island_removal_mode 0)
		)
		(polygon
			(pts
				(arc
					(start 265.87831 -305.28514)
					(mid 265.21791 -305.28514)
					(end 265.87831 -305.28514)
				)
			)
		)
	)
	(zone
		(layer "In1.Cu")
		(hatch none 0.5)
		(connect_pads
			(clearance 0)
		)
		(min_thickness 0.25)
		(keepout
			(tracks not_allowed)
			(vias allowed)
			(pads allowed)
			(copperpour not_allowed)
			(footprints allowed)
		)
		(placement
			(enabled no)
			(sheetname "")
		)
		(fill
			(thermal_gap 0.5)
			(thermal_bridge_width 0.5)
			(island_removal_mode 0)
		)
		(polygon
			(pts
				(arc
					(start 169.277284 -266.432538)
					(mid 169.273564 -266.441518)
					(end 169.264584 -266.445238)
				)
				(arc
					(start 167.791384 -266.445238)
					(mid 167.782404 -266.441518)
					(end 167.778684 -266.432538)
				)
				(arc
					(start 167.778684 -265.938)
					(mid 167.782404 -265.92902)
					(end 167.791384 -265.9253)
				)
				(arc
					(start 169.264584 -265.9253)
					(mid 169.273564 -265.92902)
					(end 169.277284 -265.938)
				)
			)
		)
	)
	(zone
		(layer "In1.Cu")
		(hatch none 0.5)
		(connect_pads
			(clearance 0)
		)
		(min_thickness 0.25)
		(keepout
			(tracks not_allowed)
			(vias allowed)
			(pads allowed)
			(copperpour not_allowed)
			(footprints allowed)
		)
		(placement
			(enabled no)
			(sheetname "")
		)
		(fill
			(thermal_gap 0.5)
			(thermal_bridge_width 0.5)
			(island_removal_mode 0)
		)
		(polygon
			(pts
				(arc
					(start 277.941532 -311.482232)
					(mid 277.937812 -311.491212)
					(end 277.928832 -311.494932)
				)
				(arc
					(start 276.455632 -311.494932)
					(mid 276.446652 -311.491212)
					(end 276.442932 -311.482232)
				)
				(arc
					(start 276.442932 -310.987694)
					(mid 276.446652 -310.978714)
					(end 276.455632 -310.974994)
				)
				(arc
					(start 277.928832 -310.974994)
					(mid 277.937812 -310.978714)
					(end 277.941532 -310.987694)
				)
			)
		)
	)
	(zone
		(layer "In1.Cu")
		(hatch none 0.5)
		(connect_pads
			(clearance 0)
		)
		(min_thickness 0.25)
		(keepout
			(tracks not_allowed)
			(vias allowed)
			(pads allowed)
			(copperpour not_allowed)
			(footprints allowed)
		)
		(placement
			(enabled no)
			(sheetname "")
		)
		(fill
			(thermal_gap 0.5)
			(thermal_bridge_width 0.5)
			(island_removal_mode 0)
		)
		(polygon
			(pts
				(arc
					(start 126.561342 -388.774432)
					(mid 126.180342 -388.774432)
					(end 126.561342 -388.774432)
				)
			)
		)
	)
	(zone
		(layer "In1.Cu")
		(hatch none 0.5)
		(connect_pads
			(clearance 0)
		)
		(min_thickness 0.25)
		(keepout
			(tracks not_allowed)
			(vias allowed)
			(pads allowed)
			(copperpour not_allowed)
			(footprints allowed)
		)
		(placement
			(enabled no)
			(sheetname "")
		)
		(fill
			(thermal_gap 0.5)
			(thermal_bridge_width 0.5)
			(island_removal_mode 0)
		)
		(polygon
			(pts
				(arc
					(start 277.941532 -205.232254)
					(mid 277.937812 -205.241234)
					(end 277.928832 -205.244954)
				)
				(arc
					(start 276.455632 -205.244954)
					(mid 276.446652 -205.241234)
					(end 276.442932 -205.232254)
				)
				(arc
					(start 276.442932 -204.737716)
					(mid 276.446652 -204.728736)
					(end 276.455632 -204.725016)
				)
				(arc
					(start 277.928832 -204.725016)
					(mid 277.937812 -204.728736)
					(end 277.941532 -204.737716)
				)
			)
		)
	)
	(zone
		(layer "In1.Cu")
		(hatch none 0.5)
		(connect_pads
			(clearance 0)
		)
		(min_thickness 0.25)
		(keepout
			(tracks not_allowed)
			(vias allowed)
			(pads allowed)
			(copperpour not_allowed)
			(footprints allowed)
		)
		(placement
			(enabled no)
			(sheetname "")
		)
		(fill
			(thermal_gap 0.5)
			(thermal_bridge_width 0.5)
			(island_removal_mode 0)
		)
		(polygon
			(pts
				(arc
					(start 417.217352 -287.682178)
					(mid 417.213632 -287.691158)
					(end 417.204652 -287.694878)
				)
				(arc
					(start 415.731452 -287.694878)
					(mid 415.722472 -287.691158)
					(end 415.718752 -287.682178)
				)
				(arc
					(start 415.718752 -287.18764)
					(mid 415.722472 -287.17866)
					(end 415.731452 -287.17494)
				)
				(arc
					(start 417.204652 -287.17494)
					(mid 417.213632 -287.17866)
					(end 417.217352 -287.18764)
				)
			)
		)
	)
	(zone
		(layer "In1.Cu")
		(hatch none 0.5)
		(connect_pads
			(clearance 0)
		)
		(min_thickness 0.25)
		(keepout
			(tracks not_allowed)
			(vias allowed)
			(pads allowed)
			(copperpour not_allowed)
			(footprints allowed)
		)
		(placement
			(enabled no)
			(sheetname "")
		)
		(fill
			(thermal_gap 0.5)
			(thermal_bridge_width 0.5)
			(island_removal_mode 0)
		)
		(polygon
			(pts
				(arc
					(start 40.98925 -243.482368)
					(mid 40.98553 -243.491348)
					(end 40.97655 -243.495068)
				)
				(arc
					(start 39.50335 -243.495068)
					(mid 39.49437 -243.491348)
					(end 39.49065 -243.482368)
				)
				(arc
					(start 39.49065 -242.98783)
					(mid 39.49437 -242.97885)
					(end 39.50335 -242.97513)
				)
				(arc
					(start 40.97655 -242.97513)
					(mid 40.98553 -242.97885)
					(end 40.98925 -242.98783)
				)
			)
		)
	)
	(zone
		(layer "In1.Cu")
		(hatch none 0.5)
		(connect_pads
			(clearance 0)
		)
		(min_thickness 0.25)
		(keepout
			(tracks not_allowed)
			(vias allowed)
			(pads allowed)
			(copperpour not_allowed)
			(footprints allowed)
		)
		(placement
			(enabled no)
			(sheetname "")
		)
		(fill
			(thermal_gap 0.5)
			(thermal_bridge_width 0.5)
			(island_removal_mode 0)
		)
		(polygon
			(pts
				(arc
					(start 424.761406 -275.782278)
					(mid 424.757686 -275.791258)
					(end 424.748706 -275.794978)
				)
				(arc
					(start 423.275506 -275.794978)
					(mid 423.266526 -275.791258)
					(end 423.262806 -275.782278)
				)
				(arc
					(start 423.262806 -275.28774)
					(mid 423.266526 -275.27876)
					(end 423.275506 -275.27504)
				)
				(arc
					(start 424.748706 -275.27504)
					(mid 424.757686 -275.27876)
					(end 424.761406 -275.28774)
				)
			)
		)
	)
	(zone
		(layer "In1.Cu")
		(hatch none 0.5)
		(connect_pads
			(clearance 0)
		)
		(min_thickness 0.25)
		(keepout
			(tracks not_allowed)
			(vias allowed)
			(pads allowed)
			(copperpour not_allowed)
			(footprints allowed)
		)
		(placement
			(enabled no)
			(sheetname "")
		)
		(fill
			(thermal_gap 0.5)
			(thermal_bridge_width 0.5)
			(island_removal_mode 0)
		)
		(polygon
			(pts
				(arc
					(start 320.660776 -394.385292)
					(mid 320.279776 -394.385292)
					(end 320.660776 -394.385292)
				)
			)
		)
	)
	(zone
		(layer "In1.Cu")
		(hatch none 0.5)
		(connect_pads
			(clearance 0)
		)
		(min_thickness 0.25)
		(keepout
			(tracks not_allowed)
			(vias allowed)
			(pads allowed)
			(copperpour not_allowed)
			(footprints allowed)
		)
		(placement
			(enabled no)
			(sheetname "")
		)
		(fill
			(thermal_gap 0.5)
			(thermal_bridge_width 0.5)
			(island_removal_mode 0)
		)
		(polygon
			(pts
				(arc
					(start 428.205392 -305.532282)
					(mid 428.201672 -305.541262)
					(end 428.192692 -305.544982)
				)
				(arc
					(start 426.719492 -305.544982)
					(mid 426.710512 -305.541262)
					(end 426.706792 -305.532282)
				)
				(arc
					(start 426.706792 -305.037744)
					(mid 426.710512 -305.028764)
					(end 426.719492 -305.025044)
				)
				(arc
					(start 428.192692 -305.025044)
					(mid 428.201672 -305.028764)
					(end 428.205392 -305.037744)
				)
			)
		)
	)
	(zone
		(layer "In1.Cu")
		(hatch none 0.5)
		(connect_pads
			(clearance 0)
		)
		(min_thickness 0.25)
		(keepout
			(tracks not_allowed)
			(vias allowed)
			(pads allowed)
			(copperpour not_allowed)
			(footprints allowed)
		)
		(placement
			(enabled no)
			(sheetname "")
		)
		(fill
			(thermal_gap 0.5)
			(thermal_bridge_width 0.5)
			(island_removal_mode 0)
		)
		(polygon
			(pts
				(arc
					(start 424.761406 -229.882192)
					(mid 424.757686 -229.891172)
					(end 424.748706 -229.894892)
				)
				(arc
					(start 423.275506 -229.894892)
					(mid 423.266526 -229.891172)
					(end 423.262806 -229.882192)
				)
				(arc
					(start 423.262806 -229.387654)
					(mid 423.266526 -229.378674)
					(end 423.275506 -229.374954)
				)
				(arc
					(start 424.748706 -229.374954)
					(mid 424.757686 -229.378674)
					(end 424.761406 -229.387654)
				)
			)
		)
	)
	(zone
		(layer "In1.Cu")
		(hatch none 0.5)
		(connect_pads
			(clearance 0)
		)
		(min_thickness 0.25)
		(keepout
			(tracks not_allowed)
			(vias allowed)
			(pads allowed)
			(copperpour not_allowed)
			(footprints allowed)
		)
		(placement
			(enabled no)
			(sheetname "")
		)
		(fill
			(thermal_gap 0.5)
			(thermal_bridge_width 0.5)
			(island_removal_mode 0)
		)
		(polygon
			(pts
				(arc
					(start 172.72127 -267.282422)
					(mid 172.71755 -267.291402)
					(end 172.70857 -267.295122)
				)
				(arc
					(start 171.23537 -267.295122)
					(mid 171.22639 -267.291402)
					(end 171.22267 -267.282422)
				)
				(arc
					(start 171.22267 -266.787884)
					(mid 171.22639 -266.778904)
					(end 171.23537 -266.775184)
				)
				(arc
					(start 172.70857 -266.775184)
					(mid 172.71755 -266.778904)
					(end 172.72127 -266.787884)
				)
			)
		)
	)
	(zone
		(layer "In1.Cu")
		(hatch none 0.5)
		(connect_pads
			(clearance 0)
		)
		(min_thickness 0.25)
		(keepout
			(tracks not_allowed)
			(vias allowed)
			(pads allowed)
			(copperpour not_allowed)
			(footprints allowed)
		)
		(placement
			(enabled no)
			(sheetname "")
		)
		(fill
			(thermal_gap 0.5)
			(thermal_bridge_width 0.5)
			(island_removal_mode 0)
		)
		(polygon
			(pts
				(arc
					(start 155.488894 -388.774432)
					(mid 155.107894 -388.774432)
					(end 155.488894 -388.774432)
				)
			)
		)
	)
	(zone
		(layer "In1.Cu")
		(hatch none 0.5)
		(connect_pads
			(clearance 0)
		)
		(min_thickness 0.25)
		(keepout
			(tracks not_allowed)
			(vias allowed)
			(pads allowed)
			(copperpour not_allowed)
			(footprints allowed)
		)
		(placement
			(enabled no)
			(sheetname "")
		)
		(fill
			(thermal_gap 0.5)
			(thermal_bridge_width 0.5)
			(island_removal_mode 0)
		)
		(polygon
			(pts
				(arc
					(start 165.177216 -282.582366)
					(mid 165.173496 -282.591346)
					(end 165.164516 -282.595066)
				)
				(arc
					(start 163.691316 -282.595066)
					(mid 163.682336 -282.591346)
					(end 163.678616 -282.582366)
				)
				(arc
					(start 163.678616 -282.087828)
					(mid 163.682336 -282.078848)
					(end 163.691316 -282.075128)
				)
				(arc
					(start 165.164516 -282.075128)
					(mid 165.173496 -282.078848)
					(end 165.177216 -282.087828)
				)
			)
		)
	)
	(zone
		(layer "In1.Cu")
		(hatch none 0.5)
		(connect_pads
			(clearance 0)
		)
		(min_thickness 0.25)
		(keepout
			(tracks not_allowed)
			(vias allowed)
			(pads allowed)
			(copperpour not_allowed)
			(footprints allowed)
		)
		(placement
			(enabled no)
			(sheetname "")
		)
		(fill
			(thermal_gap 0.5)
			(thermal_bridge_width 0.5)
			(island_removal_mode 0)
		)
		(polygon
			(pts
				(arc
					(start 55.970424 -383.92227)
					(mid 55.665624 -383.92227)
					(end 55.970424 -383.92227)
				)
			)
		)
	)
	(zone
		(layer "In1.Cu")
		(hatch none 0.5)
		(connect_pads
			(clearance 0)
		)
		(min_thickness 0.25)
		(keepout
			(tracks not_allowed)
			(vias allowed)
			(pads allowed)
			(copperpour not_allowed)
			(footprints allowed)
		)
		(placement
			(enabled no)
			(sheetname "")
		)
		(fill
			(thermal_gap 0.5)
			(thermal_bridge_width 0.5)
			(island_removal_mode 0)
		)
		(polygon
			(pts
				(arc
					(start 191.909446 -225.632518)
					(mid 191.905726 -225.641498)
					(end 191.896746 -225.645218)
				)
				(arc
					(start 190.423546 -225.645218)
					(mid 190.414566 -225.641498)
					(end 190.410846 -225.632518)
				)
				(arc
					(start 190.410846 -225.13798)
					(mid 190.414566 -225.129)
					(end 190.423546 -225.12528)
				)
				(arc
					(start 191.896746 -225.12528)
					(mid 191.905726 -225.129)
					(end 191.909446 -225.13798)
				)
			)
		)
	)
	(zone
		(layer "In1.Cu")
		(hatch none 0.5)
		(connect_pads
			(clearance 0)
		)
		(min_thickness 0.25)
		(keepout
			(tracks not_allowed)
			(vias allowed)
			(pads allowed)
			(copperpour not_allowed)
			(footprints allowed)
		)
		(placement
			(enabled no)
			(sheetname "")
		)
		(fill
			(thermal_gap 0.5)
			(thermal_bridge_width 0.5)
			(island_removal_mode 0)
		)
		(polygon
			(pts
				(arc
					(start 199.4535 -272.382488)
					(mid 199.44978 -272.391468)
					(end 199.4408 -272.395188)
				)
				(arc
					(start 197.9676 -272.395188)
					(mid 197.95862 -272.391468)
					(end 197.9549 -272.382488)
				)
				(arc
					(start 197.9549 -271.88795)
					(mid 197.95862 -271.87897)
					(end 197.9676 -271.87525)
				)
				(arc
					(start 199.4408 -271.87525)
					(mid 199.44978 -271.87897)
					(end 199.4535 -271.88795)
				)
			)
		)
	)
	(zone
		(layer "In1.Cu")
		(hatch none 0.5)
		(connect_pads
			(clearance 0)
		)
		(min_thickness 0.25)
		(keepout
			(tracks not_allowed)
			(vias allowed)
			(pads allowed)
			(copperpour not_allowed)
			(footprints allowed)
		)
		(placement
			(enabled no)
			(sheetname "")
		)
		(fill
			(thermal_gap 0.5)
			(thermal_bridge_width 0.5)
			(island_removal_mode 0)
		)
		(polygon
			(pts
				(arc
					(start 293.029386 -298.732194)
					(mid 293.025666 -298.741174)
					(end 293.016686 -298.744894)
				)
				(arc
					(start 291.543486 -298.744894)
					(mid 291.534506 -298.741174)
					(end 291.530786 -298.732194)
				)
				(arc
					(start 291.530786 -298.237656)
					(mid 291.534506 -298.228676)
					(end 291.543486 -298.224956)
				)
				(arc
					(start 293.016686 -298.224956)
					(mid 293.025666 -298.228676)
					(end 293.029386 -298.237656)
				)
			)
		)
	)
	(zone
		(layer "In1.Cu")
		(hatch none 0.5)
		(connect_pads
			(clearance 0)
		)
		(min_thickness 0.25)
		(keepout
			(tracks not_allowed)
			(vias allowed)
			(pads allowed)
			(copperpour not_allowed)
			(footprints allowed)
		)
		(placement
			(enabled no)
			(sheetname "")
		)
		(fill
			(thermal_gap 0.5)
			(thermal_bridge_width 0.5)
			(island_removal_mode 0)
		)
		(polygon
			(pts
				(arc
					(start 172.72127 -224.78238)
					(mid 172.71755 -224.79136)
					(end 172.70857 -224.79508)
				)
				(arc
					(start 171.23537 -224.79508)
					(mid 171.22639 -224.79136)
					(end 171.22267 -224.78238)
				)
				(arc
					(start 171.22267 -224.287842)
					(mid 171.22639 -224.278862)
					(end 171.23537 -224.275142)
				)
				(arc
					(start 172.70857 -224.275142)
					(mid 172.71755 -224.278862)
					(end 172.72127 -224.287842)
				)
			)
		)
	)
	(zone
		(layer "In1.Cu")
		(hatch none 0.5)
		(connect_pads
			(clearance 0)
		)
		(min_thickness 0.25)
		(keepout
			(tracks not_allowed)
			(vias allowed)
			(pads allowed)
			(copperpour not_allowed)
			(footprints allowed)
		)
		(placement
			(enabled no)
			(sheetname "")
		)
		(fill
			(thermal_gap 0.5)
			(thermal_bridge_width 0.5)
			(island_removal_mode 0)
		)
		(polygon
			(pts
				(arc
					(start 202.897232 -288.53257)
					(mid 202.893512 -288.54155)
					(end 202.884532 -288.54527)
				)
				(arc
					(start 201.411332 -288.54527)
					(mid 201.402352 -288.54155)
					(end 201.398632 -288.53257)
				)
				(arc
					(start 201.398632 -288.038032)
					(mid 201.402352 -288.029052)
					(end 201.411332 -288.025332)
				)
				(arc
					(start 202.884532 -288.025332)
					(mid 202.893512 -288.029052)
					(end 202.897232 -288.038032)
				)
			)
		)
	)
	(zone
		(layer "In1.Cu")
		(hatch none 0.5)
		(connect_pads
			(clearance 0)
		)
		(min_thickness 0.25)
		(keepout
			(tracks not_allowed)
			(vias allowed)
			(pads allowed)
			(copperpour not_allowed)
			(footprints allowed)
		)
		(placement
			(enabled no)
			(sheetname "")
		)
		(fill
			(thermal_gap 0.5)
			(thermal_bridge_width 0.5)
			(island_removal_mode 0)
		)
		(polygon
			(pts
				(arc
					(start 419.888924 -393.69238)
					(mid 419.507924 -393.69238)
					(end 419.888924 -393.69238)
				)
			)
		)
	)
	(zone
		(layer "In1.Cu")
		(hatch none 0.5)
		(connect_pads
			(clearance 0)
		)
		(min_thickness 0.25)
		(keepout
			(tracks not_allowed)
			(vias allowed)
			(pads allowed)
			(copperpour not_allowed)
			(footprints allowed)
		)
		(placement
			(enabled no)
			(sheetname "")
		)
		(fill
			(thermal_gap 0.5)
			(thermal_bridge_width 0.5)
			(island_removal_mode 0)
		)
		(polygon
			(pts
				(arc
					(start 321.460876 -393.69238)
					(mid 321.079876 -393.69238)
					(end 321.460876 -393.69238)
				)
			)
		)
	)
	(zone
		(layer "In1.Cu")
		(hatch none 0.5)
		(connect_pads
			(clearance 0)
		)
		(min_thickness 0.25)
		(keepout
			(tracks not_allowed)
			(vias allowed)
			(pads allowed)
			(copperpour not_allowed)
			(footprints allowed)
		)
		(placement
			(enabled no)
			(sheetname "")
		)
		(fill
			(thermal_gap 0.5)
			(thermal_bridge_width 0.5)
			(island_removal_mode 0)
		)
		(polygon
			(pts
				(arc
					(start 296.473372 -213.73211)
					(mid 296.469652 -213.74109)
					(end 296.460672 -213.74481)
				)
				(arc
					(start 294.987472 -213.74481)
					(mid 294.978492 -213.74109)
					(end 294.974772 -213.73211)
				)
				(arc
					(start 294.974772 -213.237572)
					(mid 294.978492 -213.228592)
					(end 294.987472 -213.224872)
				)
				(arc
					(start 296.460672 -213.224872)
					(mid 296.469652 -213.228592)
					(end 296.473372 -213.237572)
				)
			)
		)
	)
	(zone
		(layer "In1.Cu")
		(hatch none 0.5)
		(connect_pads
			(clearance 0)
		)
		(min_thickness 0.25)
		(keepout
			(tracks not_allowed)
			(vias allowed)
			(pads allowed)
			(copperpour not_allowed)
			(footprints allowed)
		)
		(placement
			(enabled no)
			(sheetname "")
		)
		(fill
			(thermal_gap 0.5)
			(thermal_bridge_width 0.5)
			(island_removal_mode 0)
		)
		(polygon
			(pts
				(arc
					(start 428.205392 -308.932326)
					(mid 428.201672 -308.941306)
					(end 428.192692 -308.945026)
				)
				(arc
					(start 426.719492 -308.945026)
					(mid 426.710512 -308.941306)
					(end 426.706792 -308.932326)
				)
				(arc
					(start 426.706792 -308.437788)
					(mid 426.710512 -308.428808)
					(end 426.719492 -308.425088)
				)
				(arc
					(start 428.192692 -308.425088)
					(mid 428.201672 -308.428808)
					(end 428.205392 -308.437788)
				)
			)
		)
	)
	(zone
		(layer "In1.Cu")
		(hatch none 0.5)
		(connect_pads
			(clearance 0)
		)
		(min_thickness 0.25)
		(keepout
			(tracks not_allowed)
			(vias allowed)
			(pads allowed)
			(copperpour not_allowed)
			(footprints allowed)
		)
		(placement
			(enabled no)
			(sheetname "")
		)
		(fill
			(thermal_gap 0.5)
			(thermal_bridge_width 0.5)
			(island_removal_mode 0)
		)
		(polygon
			(pts
				(arc
					(start 202.897232 -213.732364)
					(mid 202.893512 -213.741344)
					(end 202.884532 -213.745064)
				)
				(arc
					(start 201.411332 -213.745064)
					(mid 201.402352 -213.741344)
					(end 201.398632 -213.732364)
				)
				(arc
					(start 201.398632 -213.237826)
					(mid 201.402352 -213.228846)
					(end 201.411332 -213.225126)
				)
				(arc
					(start 202.884532 -213.225126)
					(mid 202.893512 -213.228846)
					(end 202.897232 -213.237826)
				)
			)
		)
	)
	(zone
		(layer "In1.Cu")
		(hatch none 0.5)
		(connect_pads
			(clearance 0)
		)
		(min_thickness 0.25)
		(keepout
			(tracks not_allowed)
			(vias allowed)
			(pads allowed)
			(copperpour not_allowed)
			(footprints allowed)
		)
		(placement
			(enabled no)
			(sheetname "")
		)
		(fill
			(thermal_gap 0.5)
			(thermal_bridge_width 0.5)
			(island_removal_mode 0)
		)
		(polygon
			(pts
				(arc
					(start 122.490992 -383.440686)
					(mid 122.617992 -383.567686)
					(end 122.744992 -383.440686)
				)
				(arc
					(start 122.744992 -383.364486)
					(mid 122.617992 -383.237486)
					(end 122.490992 -383.364486)
				)
			)
		)
	)
	(zone
		(layer "In1.Cu")
		(hatch none 0.5)
		(connect_pads
			(clearance 0)
		)
		(min_thickness 0.25)
		(keepout
			(tracks not_allowed)
			(vias allowed)
			(pads allowed)
			(copperpour not_allowed)
			(footprints allowed)
		)
		(placement
			(enabled no)
			(sheetname "")
		)
		(fill
			(thermal_gap 0.5)
			(thermal_bridge_width 0.5)
			(island_removal_mode 0)
		)
		(polygon
			(pts
				(arc
					(start 281.385264 -220.532198)
					(mid 281.381544 -220.541178)
					(end 281.372564 -220.544898)
				)
				(arc
					(start 279.899364 -220.544898)
					(mid 279.890384 -220.541178)
					(end 279.886664 -220.532198)
				)
				(arc
					(start 279.886664 -220.03766)
					(mid 279.890384 -220.02868)
					(end 279.899364 -220.02496)
				)
				(arc
					(start 281.372564 -220.02496)
					(mid 281.381544 -220.02868)
					(end 281.385264 -220.03766)
				)
			)
		)
	)
	(zone
		(layer "In1.Cu")
		(hatch none 0.5)
		(connect_pads
			(clearance 0)
		)
		(min_thickness 0.25)
		(keepout
			(tracks not_allowed)
			(vias allowed)
			(pads allowed)
			(copperpour not_allowed)
			(footprints allowed)
		)
		(placement
			(enabled no)
			(sheetname "")
		)
		(fill
			(thermal_gap 0.5)
			(thermal_bridge_width 0.5)
			(island_removal_mode 0)
		)
		(polygon
			(pts
				(arc
					(start 342.388698 -397.849344)
					(mid 342.007698 -397.849344)
					(end 342.388698 -397.849344)
				)
			)
		)
	)
	(zone
		(layer "In1.Cu")
		(hatch none 0.5)
		(connect_pads
			(clearance 0)
		)
		(min_thickness 0.25)
		(keepout
			(tracks not_allowed)
			(vias allowed)
			(pads allowed)
			(copperpour not_allowed)
			(footprints allowed)
		)
		(placement
			(enabled no)
			(sheetname "")
		)
		(fill
			(thermal_gap 0.5)
			(thermal_bridge_width 0.5)
			(island_removal_mode 0)
		)
		(polygon
			(pts
				(arc
					(start 187.809378 -223.082358)
					(mid 187.805658 -223.091338)
					(end 187.796678 -223.095058)
				)
				(arc
					(start 186.323478 -223.095058)
					(mid 186.314498 -223.091338)
					(end 186.310778 -223.082358)
				)
				(arc
					(start 186.310778 -222.58782)
					(mid 186.314498 -222.57884)
					(end 186.323478 -222.57512)
				)
				(arc
					(start 187.796678 -222.57512)
					(mid 187.805658 -222.57884)
					(end 187.809378 -222.58782)
				)
			)
		)
	)
	(zone
		(layer "In1.Cu")
		(hatch none 0.5)
		(connect_pads
			(clearance 0)
		)
		(min_thickness 0.25)
		(keepout
			(tracks not_allowed)
			(vias allowed)
			(pads allowed)
			(copperpour not_allowed)
			(footprints allowed)
		)
		(placement
			(enabled no)
			(sheetname "")
		)
		(fill
			(thermal_gap 0.5)
			(thermal_bridge_width 0.5)
			(island_removal_mode 0)
		)
		(polygon
			(pts
				(arc
					(start 265.87831 -248.335038)
					(mid 265.21791 -248.335038)
					(end 265.87831 -248.335038)
				)
			)
		)
	)
	(zone
		(layer "In1.Cu")
		(hatch none 0.5)
		(connect_pads
			(clearance 0)
		)
		(min_thickness 0.25)
		(keepout
			(tracks not_allowed)
			(vias allowed)
			(pads allowed)
			(copperpour not_allowed)
			(footprints allowed)
		)
		(placement
			(enabled no)
			(sheetname "")
		)
		(fill
			(thermal_gap 0.5)
			(thermal_bridge_width 0.5)
			(island_removal_mode 0)
		)
		(polygon
			(pts
				(arc
					(start 293.029386 -283.43225)
					(mid 293.025666 -283.44123)
					(end 293.016686 -283.44495)
				)
				(arc
					(start 291.543486 -283.44495)
					(mid 291.534506 -283.44123)
					(end 291.530786 -283.43225)
				)
				(arc
					(start 291.530786 -282.937712)
					(mid 291.534506 -282.928732)
					(end 291.543486 -282.925012)
				)
				(arc
					(start 293.016686 -282.925012)
					(mid 293.025666 -282.928732)
					(end 293.029386 -282.937712)
				)
			)
		)
	)
	(zone
		(layer "In1.Cu")
		(hatch none 0.5)
		(connect_pads
			(clearance 0)
		)
		(min_thickness 0.25)
		(keepout
			(tracks not_allowed)
			(vias allowed)
			(pads allowed)
			(copperpour not_allowed)
			(footprints allowed)
		)
		(placement
			(enabled no)
			(sheetname "")
		)
		(fill
			(thermal_gap 0.5)
			(thermal_bridge_width 0.5)
			(island_removal_mode 0)
		)
		(polygon
			(pts
				(arc
					(start 18.357342 -243.482368)
					(mid 18.353622 -243.491348)
					(end 18.344642 -243.495068)
				)
				(arc
					(start 16.871442 -243.495068)
					(mid 16.862462 -243.491348)
					(end 16.858742 -243.482368)
				)
				(arc
					(start 16.858742 -242.98783)
					(mid 16.862462 -242.97885)
					(end 16.871442 -242.97513)
				)
				(arc
					(start 18.344642 -242.97513)
					(mid 18.353622 -242.97885)
					(end 18.357342 -242.98783)
				)
			)
		)
	)
	(zone
		(layer "In1.Cu")
		(hatch none 0.5)
		(connect_pads
			(clearance 0)
		)
		(min_thickness 0.25)
		(keepout
			(tracks not_allowed)
			(vias allowed)
			(pads allowed)
			(copperpour not_allowed)
			(footprints allowed)
		)
		(placement
			(enabled no)
			(sheetname "")
		)
		(fill
			(thermal_gap 0.5)
			(thermal_bridge_width 0.5)
			(island_removal_mode 0)
		)
		(polygon
			(pts
				(arc
					(start 317.060834 -394.385292)
					(mid 316.679834 -394.385292)
					(end 317.060834 -394.385292)
				)
			)
		)
	)
	(zone
		(layer "In1.Cu")
		(hatch none 0.5)
		(connect_pads
			(clearance 0)
		)
		(min_thickness 0.25)
		(keepout
			(tracks not_allowed)
			(vias allowed)
			(pads allowed)
			(copperpour not_allowed)
			(footprints allowed)
		)
		(placement
			(enabled no)
			(sheetname "")
		)
		(fill
			(thermal_gap 0.5)
			(thermal_bridge_width 0.5)
			(island_removal_mode 0)
		)
		(polygon
			(pts
				(arc
					(start 169.277284 -212.88248)
					(mid 169.273564 -212.89146)
					(end 169.264584 -212.89518)
				)
				(arc
					(start 167.791384 -212.89518)
					(mid 167.782404 -212.89146)
					(end 167.778684 -212.88248)
				)
				(arc
					(start 167.778684 -212.387942)
					(mid 167.782404 -212.378962)
					(end 167.791384 -212.375242)
				)
				(arc
					(start 169.264584 -212.375242)
					(mid 169.273564 -212.378962)
					(end 169.277284 -212.387942)
				)
			)
		)
	)
	(zone
		(layer "In1.Cu")
		(hatch none 0.5)
		(connect_pads
			(clearance 0)
		)
		(min_thickness 0.25)
		(keepout
			(tracks not_allowed)
			(vias allowed)
			(pads allowed)
			(copperpour not_allowed)
			(footprints allowed)
		)
		(placement
			(enabled no)
			(sheetname "")
		)
		(fill
			(thermal_gap 0.5)
			(thermal_bridge_width 0.5)
			(island_removal_mode 0)
		)
		(polygon
			(pts
				(arc
					(start 25.901396 -218.83243)
					(mid 25.897676 -218.84141)
					(end 25.888696 -218.84513)
				)
				(arc
					(start 24.415496 -218.84513)
					(mid 24.406516 -218.84141)
					(end 24.402796 -218.83243)
				)
				(arc
					(start 24.402796 -218.337892)
					(mid 24.406516 -218.328912)
					(end 24.415496 -218.325192)
				)
				(arc
					(start 25.888696 -218.325192)
					(mid 25.897676 -218.328912)
					(end 25.901396 -218.337892)
				)
			)
		)
	)
	(zone
		(layer "In1.Cu")
		(hatch none 0.5)
		(connect_pads
			(clearance 0)
		)
		(min_thickness 0.25)
		(keepout
			(tracks not_allowed)
			(vias allowed)
			(pads allowed)
			(copperpour not_allowed)
			(footprints allowed)
		)
		(placement
			(enabled no)
			(sheetname "")
		)
		(fill
			(thermal_gap 0.5)
			(thermal_bridge_width 0.5)
			(island_removal_mode 0)
		)
		(polygon
			(pts
				(arc
					(start 447.393568 -242.63223)
					(mid 447.389848 -242.64121)
					(end 447.380868 -242.64493)
				)
				(arc
					(start 445.907668 -242.64493)
					(mid 445.898688 -242.64121)
					(end 445.894968 -242.63223)
				)
				(arc
					(start 445.894968 -242.137692)
					(mid 445.898688 -242.128712)
					(end 445.907668 -242.124992)
				)
				(arc
					(start 447.380868 -242.124992)
					(mid 447.389848 -242.128712)
					(end 447.393568 -242.137692)
				)
			)
		)
	)
	(zone
		(layer "In1.Cu")
		(hatch none 0.5)
		(connect_pads
			(clearance 0)
		)
		(min_thickness 0.25)
		(keepout
			(tracks not_allowed)
			(vias allowed)
			(pads allowed)
			(copperpour not_allowed)
			(footprints allowed)
		)
		(placement
			(enabled no)
			(sheetname "")
		)
		(fill
			(thermal_gap 0.5)
			(thermal_bridge_width 0.5)
			(island_removal_mode 0)
		)
		(polygon
			(pts
				(arc
					(start 273.841464 -282.582112)
					(mid 273.837744 -282.591092)
					(end 273.828764 -282.594812)
				)
				(arc
					(start 272.355564 -282.594812)
					(mid 272.346584 -282.591092)
					(end 272.342864 -282.582112)
				)
				(arc
					(start 272.342864 -282.087574)
					(mid 272.346584 -282.078594)
					(end 272.355564 -282.074874)
				)
				(arc
					(start 273.828764 -282.074874)
					(mid 273.837744 -282.078594)
					(end 273.841464 -282.087574)
				)
			)
		)
	)
	(zone
		(layer "In1.Cu")
		(hatch none 0.5)
		(connect_pads
			(clearance 0)
		)
		(min_thickness 0.25)
		(keepout
			(tracks not_allowed)
			(vias allowed)
			(pads allowed)
			(copperpour not_allowed)
			(footprints allowed)
		)
		(placement
			(enabled no)
			(sheetname "")
		)
		(fill
			(thermal_gap 0.5)
			(thermal_bridge_width 0.5)
			(island_removal_mode 0)
		)
		(polygon
			(pts
				(arc
					(start 428.205392 -282.582112)
					(mid 428.201672 -282.591092)
					(end 428.192692 -282.594812)
				)
				(arc
					(start 426.719492 -282.594812)
					(mid 426.710512 -282.591092)
					(end 426.706792 -282.582112)
				)
				(arc
					(start 426.706792 -282.087574)
					(mid 426.710512 -282.078594)
					(end 426.719492 -282.074874)
				)
				(arc
					(start 428.192692 -282.074874)
					(mid 428.201672 -282.078594)
					(end 428.205392 -282.087574)
				)
			)
		)
	)
	(zone
		(layer "In1.Cu")
		(hatch none 0.5)
		(connect_pads
			(clearance 0)
		)
		(min_thickness 0.25)
		(keepout
			(tracks not_allowed)
			(vias allowed)
			(pads allowed)
			(copperpour not_allowed)
			(footprints allowed)
		)
		(placement
			(enabled no)
			(sheetname "")
		)
		(fill
			(thermal_gap 0.5)
			(thermal_bridge_width 0.5)
			(island_removal_mode 0)
		)
		(polygon
			(pts
				(arc
					(start 266.29741 -245.182136)
					(mid 266.29369 -245.191116)
					(end 266.28471 -245.194836)
				)
				(arc
					(start 264.81151 -245.194836)
					(mid 264.80253 -245.191116)
					(end 264.79881 -245.182136)
				)
				(arc
					(start 264.79881 -244.687598)
					(mid 264.80253 -244.678618)
					(end 264.81151 -244.674898)
				)
				(arc
					(start 266.28471 -244.674898)
					(mid 266.29369 -244.678618)
					(end 266.29741 -244.687598)
				)
			)
		)
	)
	(zone
		(layer "In1.Cu")
		(hatch none 0.5)
		(connect_pads
			(clearance 0)
		)
		(min_thickness 0.25)
		(keepout
			(tracks not_allowed)
			(vias allowed)
			(pads allowed)
			(copperpour not_allowed)
			(footprints allowed)
		)
		(placement
			(enabled no)
			(sheetname "")
		)
		(fill
			(thermal_gap 0.5)
			(thermal_bridge_width 0.5)
			(island_removal_mode 0)
		)
		(polygon
			(pts
				(arc
					(start 57.46115 -386.003292)
					(mid 57.08015 -386.003292)
					(end 57.46115 -386.003292)
				)
			)
		)
	)
	(zone
		(layer "In1.Cu")
		(hatch none 0.5)
		(connect_pads
			(clearance 0)
		)
		(min_thickness 0.25)
		(keepout
			(tracks not_allowed)
			(vias allowed)
			(pads allowed)
			(copperpour not_allowed)
			(footprints allowed)
		)
		(placement
			(enabled no)
			(sheetname "")
		)
		(fill
			(thermal_gap 0.5)
			(thermal_bridge_width 0.5)
			(island_removal_mode 0)
		)
		(polygon
			(pts
				(arc
					(start 56.077358 -204.38237)
					(mid 56.073638 -204.39135)
					(end 56.064658 -204.39507)
				)
				(arc
					(start 54.591458 -204.39507)
					(mid 54.582478 -204.39135)
					(end 54.578758 -204.38237)
				)
				(arc
					(start 54.578758 -203.887832)
					(mid 54.582478 -203.878852)
					(end 54.591458 -203.875132)
				)
				(arc
					(start 56.064658 -203.875132)
					(mid 56.073638 -203.878852)
					(end 56.077358 -203.887832)
				)
			)
		)
	)
	(zone
		(layer "In1.Cu")
		(hatch none 0.5)
		(connect_pads
			(clearance 0)
		)
		(min_thickness 0.25)
		(keepout
			(tracks not_allowed)
			(vias allowed)
			(pads allowed)
			(copperpour not_allowed)
			(footprints allowed)
		)
		(placement
			(enabled no)
			(sheetname "")
		)
		(fill
			(thermal_gap 0.5)
			(thermal_bridge_width 0.5)
			(island_removal_mode 0)
		)
		(polygon
			(pts
				(arc
					(start 206.9973 -313.182508)
					(mid 206.99358 -313.191488)
					(end 206.9846 -313.195208)
				)
				(arc
					(start 205.5114 -313.195208)
					(mid 205.50242 -313.191488)
					(end 205.4987 -313.182508)
				)
				(arc
					(start 205.4987 -312.68797)
					(mid 205.50242 -312.67899)
					(end 205.5114 -312.67527)
				)
				(arc
					(start 206.9846 -312.67527)
					(mid 206.99358 -312.67899)
					(end 206.9973 -312.68797)
				)
			)
		)
	)
	(zone
		(layer "In1.Cu")
		(hatch none 0.5)
		(connect_pads
			(clearance 0)
		)
		(min_thickness 0.25)
		(keepout
			(tracks not_allowed)
			(vias allowed)
			(pads allowed)
			(copperpour not_allowed)
			(footprints allowed)
		)
		(placement
			(enabled no)
			(sheetname "")
		)
		(fill
			(thermal_gap 0.5)
			(thermal_bridge_width 0.5)
			(island_removal_mode 0)
		)
		(polygon
			(pts
				(arc
					(start 450.8373 -296.182288)
					(mid 450.83358 -296.191268)
					(end 450.8246 -296.194988)
				)
				(arc
					(start 449.3514 -296.194988)
					(mid 449.34242 -296.191268)
					(end 449.3387 -296.182288)
				)
				(arc
					(start 449.3387 -295.68775)
					(mid 449.34242 -295.67877)
					(end 449.3514 -295.67505)
				)
				(arc
					(start 450.8246 -295.67505)
					(mid 450.83358 -295.67877)
					(end 450.8373 -295.68775)
				)
			)
		)
	)
	(zone
		(layer "In1.Cu")
		(hatch none 0.5)
		(connect_pads
			(clearance 0)
		)
		(min_thickness 0.25)
		(keepout
			(tracks not_allowed)
			(vias allowed)
			(pads allowed)
			(copperpour not_allowed)
			(footprints allowed)
		)
		(placement
			(enabled no)
			(sheetname "")
		)
		(fill
			(thermal_gap 0.5)
			(thermal_bridge_width 0.5)
			(island_removal_mode 0)
		)
		(polygon
			(pts
				(arc
					(start 180.265324 -290.232592)
					(mid 180.261604 -290.241572)
					(end 180.252624 -290.245292)
				)
				(arc
					(start 178.779424 -290.245292)
					(mid 178.770444 -290.241572)
					(end 178.766724 -290.232592)
				)
				(arc
					(start 178.766724 -289.738054)
					(mid 178.770444 -289.729074)
					(end 178.779424 -289.725354)
				)
				(arc
					(start 180.252624 -289.725354)
					(mid 180.261604 -289.729074)
					(end 180.265324 -289.738054)
				)
			)
		)
	)
	(zone
		(layer "In1.Cu")
		(hatch none 0.5)
		(connect_pads
			(clearance 0)
		)
		(min_thickness 0.25)
		(keepout
			(tracks not_allowed)
			(vias allowed)
			(pads allowed)
			(copperpour not_allowed)
			(footprints allowed)
		)
		(placement
			(enabled no)
			(sheetname "")
		)
		(fill
			(thermal_gap 0.5)
			(thermal_bridge_width 0.5)
			(island_removal_mode 0)
		)
		(polygon
			(pts
				(arc
					(start 439.849514 -240.932208)
					(mid 439.845794 -240.941188)
					(end 439.836814 -240.944908)
				)
				(arc
					(start 438.363614 -240.944908)
					(mid 438.354634 -240.941188)
					(end 438.350914 -240.932208)
				)
				(arc
					(start 438.350914 -240.43767)
					(mid 438.354634 -240.42869)
					(end 438.363614 -240.42497)
				)
				(arc
					(start 439.836814 -240.42497)
					(mid 439.845794 -240.42869)
					(end 439.849514 -240.43767)
				)
			)
		)
	)
	(zone
		(layer "In1.Cu")
		(hatch none 0.5)
		(connect_pads
			(clearance 0)
		)
		(min_thickness 0.25)
		(keepout
			(tracks not_allowed)
			(vias allowed)
			(pads allowed)
			(copperpour not_allowed)
			(footprints allowed)
		)
		(placement
			(enabled no)
			(sheetname "")
		)
		(fill
			(thermal_gap 0.5)
			(thermal_bridge_width 0.5)
			(island_removal_mode 0)
		)
		(polygon
			(pts
				(arc
					(start 300.57344 -278.332184)
					(mid 300.56972 -278.341164)
					(end 300.56074 -278.344884)
				)
				(arc
					(start 299.08754 -278.344884)
					(mid 299.07856 -278.341164)
					(end 299.07484 -278.332184)
				)
				(arc
					(start 299.07484 -277.837646)
					(mid 299.07856 -277.828666)
					(end 299.08754 -277.824946)
				)
				(arc
					(start 300.56074 -277.824946)
					(mid 300.56972 -277.828666)
					(end 300.57344 -277.837646)
				)
			)
		)
	)
	(zone
		(layer "In1.Cu")
		(hatch none 0.5)
		(connect_pads
			(clearance 0)
		)
		(min_thickness 0.25)
		(keepout
			(tracks not_allowed)
			(vias allowed)
			(pads allowed)
			(copperpour not_allowed)
			(footprints allowed)
		)
		(placement
			(enabled no)
			(sheetname "")
		)
		(fill
			(thermal_gap 0.5)
			(thermal_bridge_width 0.5)
			(island_removal_mode 0)
		)
		(polygon
			(pts
				(arc
					(start 172.72127 -204.38237)
					(mid 172.71755 -204.39135)
					(end 172.70857 -204.39507)
				)
				(arc
					(start 171.23537 -204.39507)
					(mid 171.22639 -204.39135)
					(end 171.22267 -204.38237)
				)
				(arc
					(start 171.22267 -203.887832)
					(mid 171.22639 -203.878852)
					(end 171.23537 -203.875132)
				)
				(arc
					(start 172.70857 -203.875132)
					(mid 172.71755 -203.878852)
					(end 172.72127 -203.887832)
				)
			)
		)
	)
	(zone
		(layer "In1.Cu")
		(hatch none 0.5)
		(connect_pads
			(clearance 0)
		)
		(min_thickness 0.25)
		(keepout
			(tracks not_allowed)
			(vias allowed)
			(pads allowed)
			(copperpour not_allowed)
			(footprints allowed)
		)
		(placement
			(enabled no)
			(sheetname "")
		)
		(fill
			(thermal_gap 0.5)
			(thermal_bridge_width 0.5)
			(island_removal_mode 0)
		)
		(polygon
			(pts
				(arc
					(start 191.909446 -270.682466)
					(mid 191.905726 -270.691446)
					(end 191.896746 -270.695166)
				)
				(arc
					(start 190.423546 -270.695166)
					(mid 190.414566 -270.691446)
					(end 190.410846 -270.682466)
				)
				(arc
					(start 190.410846 -270.187928)
					(mid 190.414566 -270.178948)
					(end 190.423546 -270.175228)
				)
				(arc
					(start 191.896746 -270.175228)
					(mid 191.905726 -270.178948)
					(end 191.909446 -270.187928)
				)
			)
		)
	)
	(zone
		(layer "In1.Cu")
		(hatch none 0.5)
		(connect_pads
			(clearance 0)
		)
		(min_thickness 0.25)
		(keepout
			(tracks not_allowed)
			(vias allowed)
			(pads allowed)
			(copperpour not_allowed)
			(footprints allowed)
		)
		(placement
			(enabled no)
			(sheetname "")
		)
		(fill
			(thermal_gap 0.5)
			(thermal_bridge_width 0.5)
			(island_removal_mode 0)
		)
		(polygon
			(pts
				(arc
					(start 180.265324 -263.882378)
					(mid 180.261604 -263.891358)
					(end 180.252624 -263.895078)
				)
				(arc
					(start 178.779424 -263.895078)
					(mid 178.770444 -263.891358)
					(end 178.766724 -263.882378)
				)
				(arc
					(start 178.766724 -263.38784)
					(mid 178.770444 -263.37886)
					(end 178.779424 -263.37514)
				)
				(arc
					(start 180.252624 -263.37514)
					(mid 180.261604 -263.37886)
					(end 180.265324 -263.38784)
				)
			)
		)
	)
	(zone
		(layer "In1.Cu")
		(hatch none 0.5)
		(connect_pads
			(clearance 0)
		)
		(min_thickness 0.25)
		(keepout
			(tracks not_allowed)
			(vias allowed)
			(pads allowed)
			(copperpour not_allowed)
			(footprints allowed)
		)
		(placement
			(enabled no)
			(sheetname "")
		)
		(fill
			(thermal_gap 0.5)
			(thermal_bridge_width 0.5)
			(island_removal_mode 0)
		)
		(polygon
			(pts
				(arc
					(start 199.4535 -306.38242)
					(mid 199.44978 -306.3914)
					(end 199.4408 -306.39512)
				)
				(arc
					(start 197.9676 -306.39512)
					(mid 197.95862 -306.3914)
					(end 197.9549 -306.38242)
				)
				(arc
					(start 197.9549 -305.887882)
					(mid 197.95862 -305.878902)
					(end 197.9676 -305.875182)
				)
				(arc
					(start 199.4408 -305.875182)
					(mid 199.44978 -305.878902)
					(end 199.4535 -305.887882)
				)
			)
		)
	)
	(zone
		(layer "In1.Cu")
		(hatch none 0.5)
		(connect_pads
			(clearance 0)
		)
		(min_thickness 0.25)
		(keepout
			(tracks not_allowed)
			(vias allowed)
			(pads allowed)
			(copperpour not_allowed)
			(footprints allowed)
		)
		(placement
			(enabled no)
			(sheetname "")
		)
		(fill
			(thermal_gap 0.5)
			(thermal_bridge_width 0.5)
			(island_removal_mode 0)
		)
		(polygon
			(pts
				(arc
					(start 176.821338 -291.082476)
					(mid 176.817618 -291.091456)
					(end 176.808638 -291.095176)
				)
				(arc
					(start 175.335438 -291.095176)
					(mid 175.326458 -291.091456)
					(end 175.322738 -291.082476)
				)
				(arc
					(start 175.322738 -290.587938)
					(mid 175.326458 -290.578958)
					(end 175.335438 -290.575238)
				)
				(arc
					(start 176.808638 -290.575238)
					(mid 176.817618 -290.578958)
					(end 176.821338 -290.587938)
				)
			)
		)
	)
	(zone
		(layer "In1.Cu")
		(hatch none 0.5)
		(connect_pads
			(clearance 0)
		)
		(min_thickness 0.25)
		(keepout
			(tracks not_allowed)
			(vias allowed)
			(pads allowed)
			(copperpour not_allowed)
			(footprints allowed)
		)
		(placement
			(enabled no)
			(sheetname "")
		)
		(fill
			(thermal_gap 0.5)
			(thermal_bridge_width 0.5)
			(island_removal_mode 0)
		)
		(polygon
			(pts
				(arc
					(start 413.117284 -280.88209)
					(mid 413.113564 -280.89107)
					(end 413.104584 -280.89479)
				)
				(arc
					(start 411.631384 -280.89479)
					(mid 411.622404 -280.89107)
					(end 411.618684 -280.88209)
				)
				(arc
					(start 411.618684 -280.387552)
					(mid 411.622404 -280.378572)
					(end 411.631384 -280.374852)
				)
				(arc
					(start 413.104584 -280.374852)
					(mid 413.113564 -280.378572)
					(end 413.117284 -280.387552)
				)
			)
		)
	)
	(zone
		(layer "In1.Cu")
		(hatch none 0.5)
		(connect_pads
			(clearance 0)
		)
		(min_thickness 0.25)
		(keepout
			(tracks not_allowed)
			(vias allowed)
			(pads allowed)
			(copperpour not_allowed)
			(footprints allowed)
		)
		(placement
			(enabled no)
			(sheetname "")
		)
		(fill
			(thermal_gap 0.5)
			(thermal_bridge_width 0.5)
			(island_removal_mode 0)
		)
		(polygon
			(pts
				(arc
					(start 375.3612 -393.69238)
					(mid 374.9802 -393.69238)
					(end 375.3612 -393.69238)
				)
			)
		)
	)
	(zone
		(layer "In1.Cu")
		(hatch none 0.5)
		(connect_pads
			(clearance 0)
		)
		(min_thickness 0.25)
		(keepout
			(tracks not_allowed)
			(vias allowed)
			(pads allowed)
			(copperpour not_allowed)
			(footprints allowed)
		)
		(placement
			(enabled no)
			(sheetname "")
		)
		(fill
			(thermal_gap 0.5)
			(thermal_bridge_width 0.5)
			(island_removal_mode 0)
		)
		(polygon
			(pts
				(arc
					(start 447.393568 -303.83226)
					(mid 447.389848 -303.84124)
					(end 447.380868 -303.84496)
				)
				(arc
					(start 445.907668 -303.84496)
					(mid 445.898688 -303.84124)
					(end 445.894968 -303.83226)
				)
				(arc
					(start 445.894968 -303.337722)
					(mid 445.898688 -303.328742)
					(end 445.907668 -303.325022)
				)
				(arc
					(start 447.380868 -303.325022)
					(mid 447.389848 -303.328742)
					(end 447.393568 -303.337722)
				)
			)
		)
	)
	(zone
		(layer "In1.Cu")
		(hatch none 0.5)
		(connect_pads
			(clearance 0)
		)
		(min_thickness 0.25)
		(keepout
			(tracks not_allowed)
			(vias allowed)
			(pads allowed)
			(copperpour not_allowed)
			(footprints allowed)
		)
		(placement
			(enabled no)
			(sheetname "")
		)
		(fill
			(thermal_gap 0.5)
			(thermal_bridge_width 0.5)
			(island_removal_mode 0)
		)
		(polygon
			(pts
				(arc
					(start 48.533304 -290.232592)
					(mid 48.529584 -290.241572)
					(end 48.520604 -290.245292)
				)
				(arc
					(start 47.047404 -290.245292)
					(mid 47.038424 -290.241572)
					(end 47.034704 -290.232592)
				)
				(arc
					(start 47.034704 -289.738054)
					(mid 47.038424 -289.729074)
					(end 47.047404 -289.725354)
				)
				(arc
					(start 48.520604 -289.725354)
					(mid 48.529584 -289.729074)
					(end 48.533304 -289.738054)
				)
			)
		)
	)
	(zone
		(layer "In1.Cu")
		(hatch none 0.5)
		(connect_pads
			(clearance 0)
		)
		(min_thickness 0.25)
		(keepout
			(tracks not_allowed)
			(vias allowed)
			(pads allowed)
			(copperpour not_allowed)
			(footprints allowed)
		)
		(placement
			(enabled no)
			(sheetname "")
		)
		(fill
			(thermal_gap 0.5)
			(thermal_bridge_width 0.5)
			(island_removal_mode 0)
		)
		(polygon
			(pts
				(arc
					(start 187.809378 -305.532536)
					(mid 187.805658 -305.541516)
					(end 187.796678 -305.545236)
				)
				(arc
					(start 186.323478 -305.545236)
					(mid 186.314498 -305.541516)
					(end 186.310778 -305.532536)
				)
				(arc
					(start 186.310778 -305.037998)
					(mid 186.314498 -305.029018)
					(end 186.323478 -305.025298)
				)
				(arc
					(start 187.796678 -305.025298)
					(mid 187.805658 -305.029018)
					(end 187.809378 -305.037998)
				)
			)
		)
	)
	(zone
		(layer "In1.Cu")
		(hatch none 0.5)
		(connect_pads
			(clearance 0)
		)
		(min_thickness 0.25)
		(keepout
			(tracks not_allowed)
			(vias allowed)
			(pads allowed)
			(copperpour not_allowed)
			(footprints allowed)
		)
		(placement
			(enabled no)
			(sheetname "")
		)
		(fill
			(thermal_gap 0.5)
			(thermal_bridge_width 0.5)
			(island_removal_mode 0)
		)
		(polygon
			(pts
				(arc
					(start 162.797998 -390.761474)
					(mid 162.493198 -390.761474)
					(end 162.797998 -390.761474)
				)
			)
		)
	)
	(zone
		(layer "In1.Cu")
		(hatch none 0.5)
		(connect_pads
			(clearance 0)
		)
		(min_thickness 0.25)
		(keepout
			(tracks not_allowed)
			(vias allowed)
			(pads allowed)
			(copperpour not_allowed)
			(footprints allowed)
		)
		(placement
			(enabled no)
			(sheetname "")
		)
		(fill
			(thermal_gap 0.5)
			(thermal_bridge_width 0.5)
			(island_removal_mode 0)
		)
		(polygon
			(pts
				(arc
					(start 87.298276 -390.761474)
					(mid 86.993476 -390.761474)
					(end 87.298276 -390.761474)
				)
			)
		)
	)
	(zone
		(layer "In1.Cu")
		(hatch none 0.5)
		(connect_pads
			(clearance 0)
		)
		(min_thickness 0.25)
		(keepout
			(tracks not_allowed)
			(vias allowed)
			(pads allowed)
			(copperpour not_allowed)
			(footprints allowed)
		)
		(placement
			(enabled no)
			(sheetname "")
		)
		(fill
			(thermal_gap 0.5)
			(thermal_bridge_width 0.5)
			(island_removal_mode 0)
		)
		(polygon
			(pts
				(arc
					(start 202.897232 -245.18239)
					(mid 202.893512 -245.19137)
					(end 202.884532 -245.19509)
				)
				(arc
					(start 201.411332 -245.19509)
					(mid 201.402352 -245.19137)
					(end 201.398632 -245.18239)
				)
				(arc
					(start 201.398632 -244.687852)
					(mid 201.402352 -244.678872)
					(end 201.411332 -244.675152)
				)
				(arc
					(start 202.884532 -244.675152)
					(mid 202.893512 -244.678872)
					(end 202.897232 -244.687852)
				)
			)
		)
	)
	(zone
		(layer "In1.Cu")
		(hatch none 0.5)
		(connect_pads
			(clearance 0)
		)
		(min_thickness 0.25)
		(keepout
			(tracks not_allowed)
			(vias allowed)
			(pads allowed)
			(copperpour not_allowed)
			(footprints allowed)
		)
		(placement
			(enabled no)
			(sheetname "")
		)
		(fill
			(thermal_gap 0.5)
			(thermal_bridge_width 0.5)
			(island_removal_mode 0)
		)
		(polygon
			(pts
				(arc
					(start 169.277284 -222.232474)
					(mid 169.273564 -222.241454)
					(end 169.264584 -222.245174)
				)
				(arc
					(start 167.791384 -222.245174)
					(mid 167.782404 -222.241454)
					(end 167.778684 -222.232474)
				)
				(arc
					(start 167.778684 -221.737936)
					(mid 167.782404 -221.728956)
					(end 167.791384 -221.725236)
				)
				(arc
					(start 169.264584 -221.725236)
					(mid 169.273564 -221.728956)
					(end 169.277284 -221.737936)
				)
			)
		)
	)
	(zone
		(layer "In1.Cu")
		(hatch none 0.5)
		(connect_pads
			(clearance 0)
		)
		(min_thickness 0.25)
		(keepout
			(tracks not_allowed)
			(vias allowed)
			(pads allowed)
			(copperpour not_allowed)
			(footprints allowed)
		)
		(placement
			(enabled no)
			(sheetname "")
		)
		(fill
			(thermal_gap 0.5)
			(thermal_bridge_width 0.5)
			(island_removal_mode 0)
		)
		(polygon
			(pts
				(arc
					(start 317.860934 -393.69238)
					(mid 317.479934 -393.69238)
					(end 317.860934 -393.69238)
				)
			)
		)
	)
	(zone
		(layer "In1.Cu")
		(hatch none 0.5)
		(connect_pads
			(clearance 0)
		)
		(min_thickness 0.25)
		(keepout
			(tracks not_allowed)
			(vias allowed)
			(pads allowed)
			(copperpour not_allowed)
			(footprints allowed)
		)
		(placement
			(enabled no)
			(sheetname "")
		)
		(fill
			(thermal_gap 0.5)
			(thermal_bridge_width 0.5)
			(island_removal_mode 0)
		)
		(polygon
			(pts
				(arc
					(start 50.261012 -386.003292)
					(mid 49.880012 -386.003292)
					(end 50.261012 -386.003292)
				)
			)
		)
	)
	(zone
		(layer "In1.Cu")
		(hatch none 0.5)
		(connect_pads
			(clearance 0)
		)
		(min_thickness 0.25)
		(keepout
			(tracks not_allowed)
			(vias allowed)
			(pads allowed)
			(copperpour not_allowed)
			(footprints allowed)
		)
		(placement
			(enabled no)
			(sheetname "")
		)
		(fill
			(thermal_gap 0.5)
			(thermal_bridge_width 0.5)
			(island_removal_mode 0)
		)
		(polygon
			(pts
				(arc
					(start 191.909446 -252.832362)
					(mid 191.905726 -252.841342)
					(end 191.896746 -252.845062)
				)
				(arc
					(start 190.423546 -252.845062)
					(mid 190.414566 -252.841342)
					(end 190.410846 -252.832362)
				)
				(arc
					(start 190.410846 -252.337824)
					(mid 190.414566 -252.328844)
					(end 190.423546 -252.325124)
				)
				(arc
					(start 191.896746 -252.325124)
					(mid 191.905726 -252.328844)
					(end 191.909446 -252.337824)
				)
			)
		)
	)
	(zone
		(layer "In1.Cu")
		(hatch none 0.5)
		(connect_pads
			(clearance 0)
		)
		(min_thickness 0.25)
		(keepout
			(tracks not_allowed)
			(vias allowed)
			(pads allowed)
			(copperpour not_allowed)
			(footprints allowed)
		)
		(placement
			(enabled no)
			(sheetname "")
		)
		(fill
			(thermal_gap 0.5)
			(thermal_bridge_width 0.5)
			(island_removal_mode 0)
		)
		(polygon
			(pts
				(arc
					(start 308.117494 -315.73216)
					(mid 308.113774 -315.74114)
					(end 308.104794 -315.74486)
				)
				(arc
					(start 306.631594 -315.74486)
					(mid 306.622614 -315.74114)
					(end 306.618894 -315.73216)
				)
				(arc
					(start 306.618894 -315.237622)
					(mid 306.622614 -315.228642)
					(end 306.631594 -315.224922)
				)
				(arc
					(start 308.104794 -315.224922)
					(mid 308.113774 -315.228642)
					(end 308.117494 -315.237622)
				)
			)
		)
	)
	(zone
		(layer "In1.Cu")
		(hatch none 0.5)
		(connect_pads
			(clearance 0)
		)
		(min_thickness 0.25)
		(keepout
			(tracks not_allowed)
			(vias allowed)
			(pads allowed)
			(copperpour not_allowed)
			(footprints allowed)
		)
		(placement
			(enabled no)
			(sheetname "")
		)
		(fill
			(thermal_gap 0.5)
			(thermal_bridge_width 0.5)
			(island_removal_mode 0)
		)
		(polygon
			(pts
				(arc
					(start 293.029386 -270.682212)
					(mid 293.025666 -270.691192)
					(end 293.016686 -270.694912)
				)
				(arc
					(start 291.543486 -270.694912)
					(mid 291.534506 -270.691192)
					(end 291.530786 -270.682212)
				)
				(arc
					(start 291.530786 -270.187674)
					(mid 291.534506 -270.178694)
					(end 291.543486 -270.174974)
				)
				(arc
					(start 293.016686 -270.174974)
					(mid 293.025666 -270.178694)
					(end 293.029386 -270.187674)
				)
			)
		)
	)
	(zone
		(layer "In1.Cu")
		(hatch none 0.5)
		(connect_pads
			(clearance 0)
		)
		(min_thickness 0.25)
		(keepout
			(tracks not_allowed)
			(vias allowed)
			(pads allowed)
			(copperpour not_allowed)
			(footprints allowed)
		)
		(placement
			(enabled no)
			(sheetname "")
		)
		(fill
			(thermal_gap 0.5)
			(thermal_bridge_width 0.5)
			(island_removal_mode 0)
		)
		(polygon
			(pts
				(arc
					(start 141.04112 -32.17926)
					(mid 141.063438 -32.233142)
					(end 141.11732 -32.25546)
				)
				(arc
					(start 141.47292 -32.25546)
					(mid 141.526802 -32.233142)
					(end 141.54912 -32.17926)
				)
				(arc
					(start 141.54912 -30.27426)
					(mid 141.526802 -30.220378)
					(end 141.47292 -30.19806)
				)
				(arc
					(start 141.11732 -30.19806)
					(mid 141.063438 -30.220378)
					(end 141.04112 -30.27426)
				)
			)
		)
	)
	(zone
		(layer "In1.Cu")
		(hatch none 0.5)
		(connect_pads
			(clearance 0)
		)
		(min_thickness 0.25)
		(keepout
			(tracks not_allowed)
			(vias allowed)
			(pads allowed)
			(copperpour not_allowed)
			(footprints allowed)
		)
		(placement
			(enabled no)
			(sheetname "")
		)
		(fill
			(thermal_gap 0.5)
			(thermal_bridge_width 0.5)
			(island_removal_mode 0)
		)
		(polygon
			(pts
				(arc
					(start 206.5782 -221.985332)
					(mid 205.9178 -221.985332)
					(end 206.5782 -221.985332)
				)
			)
		)
	)
	(zone
		(layer "In1.Cu")
		(hatch none 0.5)
		(connect_pads
			(clearance 0)
		)
		(min_thickness 0.25)
		(keepout
			(tracks not_allowed)
			(vias allowed)
			(pads allowed)
			(copperpour not_allowed)
			(footprints allowed)
		)
		(placement
			(enabled no)
			(sheetname "")
		)
		(fill
			(thermal_gap 0.5)
			(thermal_bridge_width 0.5)
			(island_removal_mode 0)
		)
		(polygon
			(pts
				(arc
					(start 45.089318 -214.582502)
					(mid 45.085598 -214.591482)
					(end 45.076618 -214.595202)
				)
				(arc
					(start 43.603418 -214.595202)
					(mid 43.594438 -214.591482)
					(end 43.590718 -214.582502)
				)
				(arc
					(start 43.590718 -214.087964)
					(mid 43.594438 -214.078984)
					(end 43.603418 -214.075264)
				)
				(arc
					(start 45.076618 -214.075264)
					(mid 45.085598 -214.078984)
					(end 45.089318 -214.087964)
				)
			)
		)
	)
	(zone
		(layer "In1.Cu")
		(hatch none 0.5)
		(connect_pads
			(clearance 0)
		)
		(min_thickness 0.25)
		(keepout
			(tracks not_allowed)
			(vias allowed)
			(pads allowed)
			(copperpour not_allowed)
			(footprints allowed)
		)
		(placement
			(enabled no)
			(sheetname "")
		)
		(fill
			(thermal_gap 0.5)
			(thermal_bridge_width 0.5)
			(island_removal_mode 0)
		)
		(polygon
			(pts
				(arc
					(start 30.001464 -201.832464)
					(mid 29.997744 -201.841444)
					(end 29.988764 -201.845164)
				)
				(arc
					(start 28.515564 -201.845164)
					(mid 28.506584 -201.841444)
					(end 28.502864 -201.832464)
				)
				(arc
					(start 28.502864 -201.337926)
					(mid 28.506584 -201.328946)
					(end 28.515564 -201.325226)
				)
				(arc
					(start 29.988764 -201.325226)
					(mid 29.997744 -201.328946)
					(end 30.001464 -201.337926)
				)
			)
		)
	)
	(zone
		(layer "In1.Cu")
		(hatch none 0.5)
		(connect_pads
			(clearance 0)
		)
		(min_thickness 0.25)
		(keepout
			(tracks not_allowed)
			(vias allowed)
			(pads allowed)
			(copperpour not_allowed)
			(footprints allowed)
		)
		(placement
			(enabled no)
			(sheetname "")
		)
		(fill
			(thermal_gap 0.5)
			(thermal_bridge_width 0.5)
			(island_removal_mode 0)
		)
		(polygon
			(pts
				(arc
					(start 345.69781 -399.143474)
					(mid 345.39301 -399.143474)
					(end 345.69781 -399.143474)
				)
			)
		)
	)
	(zone
		(layer "In1.Cu")
		(hatch none 0.5)
		(connect_pads
			(clearance 0)
		)
		(min_thickness 0.25)
		(keepout
			(tracks not_allowed)
			(vias allowed)
			(pads allowed)
			(copperpour not_allowed)
			(footprints allowed)
		)
		(placement
			(enabled no)
			(sheetname "")
		)
		(fill
			(thermal_gap 0.5)
			(thermal_bridge_width 0.5)
			(island_removal_mode 0)
		)
		(polygon
			(pts
				(arc
					(start 60.177426 -240.932462)
					(mid 60.173706 -240.941442)
					(end 60.164726 -240.945162)
				)
				(arc
					(start 58.691526 -240.945162)
					(mid 58.682546 -240.941442)
					(end 58.678826 -240.932462)
				)
				(arc
					(start 58.678826 -240.437924)
					(mid 58.682546 -240.428944)
					(end 58.691526 -240.425224)
				)
				(arc
					(start 60.164726 -240.425224)
					(mid 60.173706 -240.428944)
					(end 60.177426 -240.437924)
				)
			)
		)
	)
	(zone
		(layer "In1.Cu")
		(hatch none 0.5)
		(connect_pads
			(clearance 0)
		)
		(min_thickness 0.25)
		(keepout
			(tracks not_allowed)
			(vias allowed)
			(pads allowed)
			(copperpour not_allowed)
			(footprints allowed)
		)
		(placement
			(enabled no)
			(sheetname "")
		)
		(fill
			(thermal_gap 0.5)
			(thermal_bridge_width 0.5)
			(island_removal_mode 0)
		)
		(polygon
			(pts
				(arc
					(start 199.4535 -264.732516)
					(mid 199.44978 -264.741496)
					(end 199.4408 -264.745216)
				)
				(arc
					(start 197.9676 -264.745216)
					(mid 197.95862 -264.741496)
					(end 197.9549 -264.732516)
				)
				(arc
					(start 197.9549 -264.237978)
					(mid 197.95862 -264.228998)
					(end 197.9676 -264.225278)
				)
				(arc
					(start 199.4408 -264.225278)
					(mid 199.44978 -264.228998)
					(end 199.4535 -264.237978)
				)
			)
		)
	)
	(zone
		(layer "In1.Cu")
		(hatch none 0.5)
		(connect_pads
			(clearance 0)
		)
		(min_thickness 0.25)
		(keepout
			(tracks not_allowed)
			(vias allowed)
			(pads allowed)
			(copperpour not_allowed)
			(footprints allowed)
		)
		(placement
			(enabled no)
			(sheetname "")
		)
		(fill
			(thermal_gap 0.5)
			(thermal_bridge_width 0.5)
			(island_removal_mode 0)
		)
		(polygon
			(pts
				(arc
					(start 443.2935 -240.082324)
					(mid 443.28978 -240.091304)
					(end 443.2808 -240.095024)
				)
				(arc
					(start 441.8076 -240.095024)
					(mid 441.79862 -240.091304)
					(end 441.7949 -240.082324)
				)
				(arc
					(start 441.7949 -239.587786)
					(mid 441.79862 -239.578806)
					(end 441.8076 -239.575086)
				)
				(arc
					(start 443.2808 -239.575086)
					(mid 443.28978 -239.578806)
					(end 443.2935 -239.587786)
				)
			)
		)
	)
	(zone
		(layer "In1.Cu")
		(hatch none 0.5)
		(connect_pads
			(clearance 0)
		)
		(min_thickness 0.25)
		(keepout
			(tracks not_allowed)
			(vias allowed)
			(pads allowed)
			(copperpour not_allowed)
			(footprints allowed)
		)
		(placement
			(enabled no)
			(sheetname "")
		)
		(fill
			(thermal_gap 0.5)
			(thermal_bridge_width 0.5)
			(island_removal_mode 0)
		)
		(polygon
			(pts
				(arc
					(start 387.760972 -397.849344)
					(mid 387.379972 -397.849344)
					(end 387.760972 -397.849344)
				)
			)
		)
	)
	(zone
		(layer "In1.Cu")
		(hatch none 0.5)
		(connect_pads
			(clearance 0)
		)
		(min_thickness 0.25)
		(keepout
			(tracks not_allowed)
			(vias allowed)
			(pads allowed)
			(copperpour not_allowed)
			(footprints allowed)
		)
		(placement
			(enabled no)
			(sheetname "")
		)
		(fill
			(thermal_gap 0.5)
			(thermal_bridge_width 0.5)
			(island_removal_mode 0)
		)
		(polygon
			(pts
				(arc
					(start 450.8373 -314.032138)
					(mid 450.83358 -314.041118)
					(end 450.8246 -314.044838)
				)
				(arc
					(start 449.3514 -314.044838)
					(mid 449.34242 -314.041118)
					(end 449.3387 -314.032138)
				)
				(arc
					(start 449.3387 -313.5376)
					(mid 449.34242 -313.52862)
					(end 449.3514 -313.5249)
				)
				(arc
					(start 450.8246 -313.5249)
					(mid 450.83358 -313.52862)
					(end 450.8373 -313.5376)
				)
			)
		)
	)
	(zone
		(layer "In1.Cu")
		(hatch none 0.5)
		(connect_pads
			(clearance 0)
		)
		(min_thickness 0.25)
		(keepout
			(tracks not_allowed)
			(vias allowed)
			(pads allowed)
			(copperpour not_allowed)
			(footprints allowed)
		)
		(placement
			(enabled no)
			(sheetname "")
		)
		(fill
			(thermal_gap 0.5)
			(thermal_bridge_width 0.5)
			(island_removal_mode 0)
		)
		(polygon
			(pts
				(arc
					(start 370.961158 -397.849344)
					(mid 370.580158 -397.849344)
					(end 370.961158 -397.849344)
				)
			)
		)
	)
	(zone
		(layer "In1.Cu")
		(hatch none 0.5)
		(connect_pads
			(clearance 0)
		)
		(min_thickness 0.25)
		(keepout
			(tracks not_allowed)
			(vias allowed)
			(pads allowed)
			(copperpour not_allowed)
			(footprints allowed)
		)
		(placement
			(enabled no)
			(sheetname "")
		)
		(fill
			(thermal_gap 0.5)
			(thermal_bridge_width 0.5)
			(island_removal_mode 0)
		)
		(polygon
			(pts
				(arc
					(start 206.5782 -267.885418)
					(mid 205.9178 -267.885418)
					(end 206.5782 -267.885418)
				)
			)
		)
	)
	(zone
		(layer "In1.Cu")
		(hatch none 0.5)
		(connect_pads
			(clearance 0)
		)
		(min_thickness 0.25)
		(keepout
			(tracks not_allowed)
			(vias allowed)
			(pads allowed)
			(copperpour not_allowed)
			(footprints allowed)
		)
		(placement
			(enabled no)
			(sheetname "")
		)
		(fill
			(thermal_gap 0.5)
			(thermal_bridge_width 0.5)
			(island_removal_mode 0)
		)
		(polygon
			(pts
				(arc
					(start 22.45741 -292.782498)
					(mid 22.45369 -292.791478)
					(end 22.44471 -292.795198)
				)
				(arc
					(start 20.97151 -292.795198)
					(mid 20.96253 -292.791478)
					(end 20.95881 -292.782498)
				)
				(arc
					(start 20.95881 -292.28796)
					(mid 20.96253 -292.27898)
					(end 20.97151 -292.27526)
				)
				(arc
					(start 22.44471 -292.27526)
					(mid 22.45369 -292.27898)
					(end 22.45741 -292.28796)
				)
			)
		)
	)
	(zone
		(layer "In1.Cu")
		(hatch none 0.5)
		(connect_pads
			(clearance 0)
		)
		(min_thickness 0.25)
		(keepout
			(tracks not_allowed)
			(vias allowed)
			(pads allowed)
			(copperpour not_allowed)
			(footprints allowed)
		)
		(placement
			(enabled no)
			(sheetname "")
		)
		(fill
			(thermal_gap 0.5)
			(thermal_bridge_width 0.5)
			(island_removal_mode 0)
		)
		(polygon
			(pts
				(arc
					(start 37.545264 -261.332472)
					(mid 37.541544 -261.341452)
					(end 37.532564 -261.345172)
				)
				(arc
					(start 36.059364 -261.345172)
					(mid 36.050384 -261.341452)
					(end 36.046664 -261.332472)
				)
				(arc
					(start 36.046664 -260.837934)
					(mid 36.050384 -260.828954)
					(end 36.059364 -260.825234)
				)
				(arc
					(start 37.532564 -260.825234)
					(mid 37.541544 -260.828954)
					(end 37.545264 -260.837934)
				)
			)
		)
	)
	(zone
		(layer "In1.Cu")
		(hatch none 0.5)
		(connect_pads
			(clearance 0)
		)
		(min_thickness 0.25)
		(keepout
			(tracks not_allowed)
			(vias allowed)
			(pads allowed)
			(copperpour not_allowed)
			(footprints allowed)
		)
		(placement
			(enabled no)
			(sheetname "")
		)
		(fill
			(thermal_gap 0.5)
			(thermal_bridge_width 0.5)
			(island_removal_mode 0)
		)
		(polygon
			(pts
				(arc
					(start 45.089318 -210.332574)
					(mid 45.085598 -210.341554)
					(end 45.076618 -210.345274)
				)
				(arc
					(start 43.603418 -210.345274)
					(mid 43.594438 -210.341554)
					(end 43.590718 -210.332574)
				)
				(arc
					(start 43.590718 -209.838036)
					(mid 43.594438 -209.829056)
					(end 43.603418 -209.825336)
				)
				(arc
					(start 45.076618 -209.825336)
					(mid 45.085598 -209.829056)
					(end 45.089318 -209.838036)
				)
			)
		)
	)
	(zone
		(layer "In1.Cu")
		(hatch none 0.5)
		(connect_pads
			(clearance 0)
		)
		(min_thickness 0.25)
		(keepout
			(tracks not_allowed)
			(vias allowed)
			(pads allowed)
			(copperpour not_allowed)
			(footprints allowed)
		)
		(placement
			(enabled no)
			(sheetname "")
		)
		(fill
			(thermal_gap 0.5)
			(thermal_bridge_width 0.5)
			(island_removal_mode 0)
		)
		(polygon
			(pts
				(arc
					(start 40.98925 -282.582366)
					(mid 40.98553 -282.591346)
					(end 40.97655 -282.595066)
				)
				(arc
					(start 39.50335 -282.595066)
					(mid 39.49437 -282.591346)
					(end 39.49065 -282.582366)
				)
				(arc
					(start 39.49065 -282.087828)
					(mid 39.49437 -282.078848)
					(end 39.50335 -282.075128)
				)
				(arc
					(start 40.97655 -282.075128)
					(mid 40.98553 -282.078848)
					(end 40.98925 -282.087828)
				)
			)
		)
	)
	(zone
		(layer "In1.Cu")
		(hatch none 0.5)
		(connect_pads
			(clearance 0)
		)
		(min_thickness 0.25)
		(keepout
			(tracks not_allowed)
			(vias allowed)
			(pads allowed)
			(copperpour not_allowed)
			(footprints allowed)
		)
		(placement
			(enabled no)
			(sheetname "")
		)
		(fill
			(thermal_gap 0.5)
			(thermal_bridge_width 0.5)
			(island_removal_mode 0)
		)
		(polygon
			(pts
				(arc
					(start 169.277284 -289.382454)
					(mid 169.273564 -289.391434)
					(end 169.264584 -289.395154)
				)
				(arc
					(start 167.791384 -289.395154)
					(mid 167.782404 -289.391434)
					(end 167.778684 -289.382454)
				)
				(arc
					(start 167.778684 -288.887916)
					(mid 167.782404 -288.878936)
					(end 167.791384 -288.875216)
				)
				(arc
					(start 169.264584 -288.875216)
					(mid 169.273564 -288.878936)
					(end 169.277284 -288.887916)
				)
			)
		)
	)
	(zone
		(layer "In1.Cu")
		(hatch none 0.5)
		(connect_pads
			(clearance 0)
		)
		(min_thickness 0.25)
		(keepout
			(tracks not_allowed)
			(vias allowed)
			(pads allowed)
			(copperpour not_allowed)
			(footprints allowed)
		)
		(placement
			(enabled no)
			(sheetname "")
		)
		(fill
			(thermal_gap 0.5)
			(thermal_bridge_width 0.5)
			(island_removal_mode 0)
		)
		(polygon
			(pts
				(arc
					(start 40.98925 -314.88253)
					(mid 40.98553 -314.89151)
					(end 40.97655 -314.89523)
				)
				(arc
					(start 39.50335 -314.89523)
					(mid 39.49437 -314.89151)
					(end 39.49065 -314.88253)
				)
				(arc
					(start 39.49065 -314.387992)
					(mid 39.49437 -314.379012)
					(end 39.50335 -314.375292)
				)
				(arc
					(start 40.97655 -314.375292)
					(mid 40.98553 -314.379012)
					(end 40.98925 -314.387992)
				)
			)
		)
	)
	(zone
		(layer "In1.Cu")
		(hatch none 0.5)
		(connect_pads
			(clearance 0)
		)
		(min_thickness 0.25)
		(keepout
			(tracks not_allowed)
			(vias allowed)
			(pads allowed)
			(copperpour not_allowed)
			(footprints allowed)
		)
		(placement
			(enabled no)
			(sheetname "")
		)
		(fill
			(thermal_gap 0.5)
			(thermal_bridge_width 0.5)
			(island_removal_mode 0)
		)
		(polygon
			(pts
				(arc
					(start 273.841464 -237.532164)
					(mid 273.837744 -237.541144)
					(end 273.828764 -237.544864)
				)
				(arc
					(start 272.355564 -237.544864)
					(mid 272.346584 -237.541144)
					(end 272.342864 -237.532164)
				)
				(arc
					(start 272.342864 -237.037626)
					(mid 272.346584 -237.028646)
					(end 272.355564 -237.024926)
				)
				(arc
					(start 273.828764 -237.024926)
					(mid 273.837744 -237.028646)
					(end 273.841464 -237.037626)
				)
			)
		)
	)
	(zone
		(layer "In1.Cu")
		(hatch none 0.5)
		(connect_pads
			(clearance 0)
		)
		(min_thickness 0.25)
		(keepout
			(tracks not_allowed)
			(vias allowed)
			(pads allowed)
			(copperpour not_allowed)
			(footprints allowed)
		)
		(placement
			(enabled no)
			(sheetname "")
		)
		(fill
			(thermal_gap 0.5)
			(thermal_bridge_width 0.5)
			(island_removal_mode 0)
		)
		(polygon
			(pts
				(arc
					(start 22.45741 -216.282524)
					(mid 22.45369 -216.291504)
					(end 22.44471 -216.295224)
				)
				(arc
					(start 20.97151 -216.295224)
					(mid 20.96253 -216.291504)
					(end 20.95881 -216.282524)
				)
				(arc
					(start 20.95881 -215.787986)
					(mid 20.96253 -215.779006)
					(end 20.97151 -215.775286)
				)
				(arc
					(start 22.44471 -215.775286)
					(mid 22.45369 -215.779006)
					(end 22.45741 -215.787986)
				)
			)
		)
	)
	(zone
		(layer "In1.Cu")
		(hatch none 0.5)
		(connect_pads
			(clearance 0)
		)
		(min_thickness 0.25)
		(keepout
			(tracks not_allowed)
			(vias allowed)
			(pads allowed)
			(copperpour not_allowed)
			(footprints allowed)
		)
		(placement
			(enabled no)
			(sheetname "")
		)
		(fill
			(thermal_gap 0.5)
			(thermal_bridge_width 0.5)
			(island_removal_mode 0)
		)
		(polygon
			(pts
				(arc
					(start 450.8373 -254.53213)
					(mid 450.83358 -254.54111)
					(end 450.8246 -254.54483)
				)
				(arc
					(start 449.3514 -254.54483)
					(mid 449.34242 -254.54111)
					(end 449.3387 -254.53213)
				)
				(arc
					(start 449.3387 -254.037592)
					(mid 449.34242 -254.028612)
					(end 449.3514 -254.024892)
				)
				(arc
					(start 450.8246 -254.024892)
					(mid 450.83358 -254.028612)
					(end 450.8373 -254.037592)
				)
			)
		)
	)
	(zone
		(layer "In1.Cu")
		(hatch none 0.5)
		(connect_pads
			(clearance 0)
		)
		(min_thickness 0.25)
		(keepout
			(tracks not_allowed)
			(vias allowed)
			(pads allowed)
			(copperpour not_allowed)
			(footprints allowed)
		)
		(placement
			(enabled no)
			(sheetname "")
		)
		(fill
			(thermal_gap 0.5)
			(thermal_bridge_width 0.5)
			(island_removal_mode 0)
		)
		(polygon
			(pts
				(arc
					(start 199.4535 -298.732448)
					(mid 199.44978 -298.741428)
					(end 199.4408 -298.745148)
				)
				(arc
					(start 197.9676 -298.745148)
					(mid 197.95862 -298.741428)
					(end 197.9549 -298.732448)
				)
				(arc
					(start 197.9549 -298.23791)
					(mid 197.95862 -298.22893)
					(end 197.9676 -298.22521)
				)
				(arc
					(start 199.4408 -298.22521)
					(mid 199.44978 -298.22893)
					(end 199.4535 -298.23791)
				)
			)
		)
	)
	(zone
		(layer "In1.Cu")
		(hatch none 0.5)
		(connect_pads
			(clearance 0)
		)
		(min_thickness 0.25)
		(keepout
			(tracks not_allowed)
			(vias allowed)
			(pads allowed)
			(copperpour not_allowed)
			(footprints allowed)
		)
		(placement
			(enabled no)
			(sheetname "")
		)
		(fill
			(thermal_gap 0.5)
			(thermal_bridge_width 0.5)
			(island_removal_mode 0)
		)
		(polygon
			(pts
				(arc
					(start 49.149508 -16.443198)
					(mid 49.171826 -16.49708)
					(end 49.225708 -16.519398)
				)
				(arc
					(start 49.421288 -16.519398)
					(mid 49.443164 -16.516266)
					(end 49.463198 -16.506952)
				)
				(arc
					(start 49.756822 -16.31442)
					(mid 49.798478 -16.302018)
					(end 49.840134 -16.31442)
				)
				(arc
					(start 50.135028 -16.506952)
					(mid 50.154952 -16.516188)
					(end 50.176684 -16.519398)
				)
				(arc
					(start 50.371248 -16.519398)
					(mid 50.42513 -16.49708)
					(end 50.447448 -16.443198)
				)
				(arc
					(start 50.447448 -15.757398)
					(mid 50.42513 -15.703516)
					(end 50.371248 -15.681198)
				)
				(arc
					(start 50.176684 -15.681198)
					(mid 50.15494 -15.684366)
					(end 50.135028 -15.693644)
				)
				(arc
					(start 49.838864 -15.88643)
					(mid 49.79718 -15.898652)
					(end 49.755552 -15.886176)
				)
				(arc
					(start 49.461928 -15.693644)
					(mid 49.442004 -15.684408)
					(end 49.420272 -15.681198)
				)
				(arc
					(start 49.225708 -15.681198)
					(mid 49.171826 -15.703516)
					(end 49.149508 -15.757398)
				)
			)
		)
	)
	(zone
		(layer "In1.Cu")
		(hatch none 0.5)
		(connect_pads
			(clearance 0)
		)
		(min_thickness 0.25)
		(keepout
			(tracks not_allowed)
			(vias allowed)
			(pads allowed)
			(copperpour not_allowed)
			(footprints allowed)
		)
		(placement
			(enabled no)
			(sheetname "")
		)
		(fill
			(thermal_gap 0.5)
			(thermal_bridge_width 0.5)
			(island_removal_mode 0)
		)
		(polygon
			(pts
				(arc
					(start 187.809378 -253.6825)
					(mid 187.805658 -253.69148)
					(end 187.796678 -253.6952)
				)
				(arc
					(start 186.323478 -253.6952)
					(mid 186.314498 -253.69148)
					(end 186.310778 -253.6825)
				)
				(arc
					(start 186.310778 -253.187962)
					(mid 186.314498 -253.178982)
					(end 186.323478 -253.175262)
				)
				(arc
					(start 187.796678 -253.175262)
					(mid 187.805658 -253.178982)
					(end 187.809378 -253.187962)
				)
			)
		)
	)
	(zone
		(layer "In1.Cu")
		(hatch none 0.5)
		(connect_pads
			(clearance 0)
		)
		(min_thickness 0.25)
		(keepout
			(tracks not_allowed)
			(vias allowed)
			(pads allowed)
			(copperpour not_allowed)
			(footprints allowed)
		)
		(placement
			(enabled no)
			(sheetname "")
		)
		(fill
			(thermal_gap 0.5)
			(thermal_bridge_width 0.5)
			(island_removal_mode 0)
		)
		(polygon
			(pts
				(arc
					(start 308.117494 -231.582214)
					(mid 308.113774 -231.591194)
					(end 308.104794 -231.594914)
				)
				(arc
					(start 306.631594 -231.594914)
					(mid 306.622614 -231.591194)
					(end 306.618894 -231.582214)
				)
				(arc
					(start 306.618894 -231.087676)
					(mid 306.622614 -231.078696)
					(end 306.631594 -231.074976)
				)
				(arc
					(start 308.104794 -231.074976)
					(mid 308.113774 -231.078696)
					(end 308.117494 -231.087676)
				)
			)
		)
	)
	(zone
		(layer "In1.Cu")
		(hatch none 0.5)
		(connect_pads
			(clearance 0)
		)
		(min_thickness 0.25)
		(keepout
			(tracks not_allowed)
			(vias allowed)
			(pads allowed)
			(copperpour not_allowed)
			(footprints allowed)
		)
		(placement
			(enabled no)
			(sheetname "")
		)
		(fill
			(thermal_gap 0.5)
			(thermal_bridge_width 0.5)
			(island_removal_mode 0)
		)
		(polygon
			(pts
				(arc
					(start 447.393568 -251.132086)
					(mid 447.389848 -251.141066)
					(end 447.380868 -251.144786)
				)
				(arc
					(start 445.907668 -251.144786)
					(mid 445.898688 -251.141066)
					(end 445.894968 -251.132086)
				)
				(arc
					(start 445.894968 -250.637548)
					(mid 445.898688 -250.628568)
					(end 445.907668 -250.624848)
				)
				(arc
					(start 447.380868 -250.624848)
					(mid 447.389848 -250.628568)
					(end 447.393568 -250.637548)
				)
			)
		)
	)
	(zone
		(layer "In1.Cu")
		(hatch none 0.5)
		(connect_pads
			(clearance 0)
		)
		(min_thickness 0.25)
		(keepout
			(tracks not_allowed)
			(vias allowed)
			(pads allowed)
			(copperpour not_allowed)
			(footprints allowed)
		)
		(placement
			(enabled no)
			(sheetname "")
		)
		(fill
			(thermal_gap 0.5)
			(thermal_bridge_width 0.5)
			(island_removal_mode 0)
		)
		(polygon
			(pts
				(arc
					(start 308.117494 -210.33232)
					(mid 308.113774 -210.3413)
					(end 308.104794 -210.34502)
				)
				(arc
					(start 306.631594 -210.34502)
					(mid 306.622614 -210.3413)
					(end 306.618894 -210.33232)
				)
				(arc
					(start 306.618894 -209.837782)
					(mid 306.622614 -209.828802)
					(end 306.631594 -209.825082)
				)
				(arc
					(start 308.104794 -209.825082)
					(mid 308.113774 -209.828802)
					(end 308.117494 -209.837782)
				)
			)
		)
	)
	(zone
		(layer "In1.Cu")
		(hatch none 0.5)
		(connect_pads
			(clearance 0)
		)
		(min_thickness 0.25)
		(keepout
			(tracks not_allowed)
			(vias allowed)
			(pads allowed)
			(copperpour not_allowed)
			(footprints allowed)
		)
		(placement
			(enabled no)
			(sheetname "")
		)
		(fill
			(thermal_gap 0.5)
			(thermal_bridge_width 0.5)
			(island_removal_mode 0)
		)
		(polygon
			(pts
				(arc
					(start 447.393568 -278.332184)
					(mid 447.389848 -278.341164)
					(end 447.380868 -278.344884)
				)
				(arc
					(start 445.907668 -278.344884)
					(mid 445.898688 -278.341164)
					(end 445.894968 -278.332184)
				)
				(arc
					(start 445.894968 -277.837646)
					(mid 445.898688 -277.828666)
					(end 445.907668 -277.824946)
				)
				(arc
					(start 447.380868 -277.824946)
					(mid 447.389848 -277.828666)
					(end 447.393568 -277.837646)
				)
			)
		)
	)
	(zone
		(layer "In1.Cu")
		(hatch none 0.5)
		(connect_pads
			(clearance 0)
		)
		(min_thickness 0.25)
		(keepout
			(tracks not_allowed)
			(vias allowed)
			(pads allowed)
			(copperpour not_allowed)
			(footprints allowed)
		)
		(placement
			(enabled no)
			(sheetname "")
		)
		(fill
			(thermal_gap 0.5)
			(thermal_bridge_width 0.5)
			(island_removal_mode 0)
		)
		(polygon
			(pts
				(arc
					(start 417.217352 -236.68228)
					(mid 417.213632 -236.69126)
					(end 417.204652 -236.69498)
				)
				(arc
					(start 415.731452 -236.69498)
					(mid 415.722472 -236.69126)
					(end 415.718752 -236.68228)
				)
				(arc
					(start 415.718752 -236.187742)
					(mid 415.722472 -236.178762)
					(end 415.731452 -236.175042)
				)
				(arc
					(start 417.204652 -236.175042)
					(mid 417.213632 -236.178762)
					(end 417.217352 -236.187742)
				)
			)
		)
	)
	(zone
		(layer "In1.Cu")
		(hatch none 0.5)
		(connect_pads
			(clearance 0)
		)
		(min_thickness 0.25)
		(keepout
			(tracks not_allowed)
			(vias allowed)
			(pads allowed)
			(copperpour not_allowed)
			(footprints allowed)
		)
		(placement
			(enabled no)
			(sheetname "")
		)
		(fill
			(thermal_gap 0.5)
			(thermal_bridge_width 0.5)
			(island_removal_mode 0)
		)
		(polygon
			(pts
				(arc
					(start 420.661338 -237.532164)
					(mid 420.657618 -237.541144)
					(end 420.648638 -237.544864)
				)
				(arc
					(start 419.175438 -237.544864)
					(mid 419.166458 -237.541144)
					(end 419.162738 -237.532164)
				)
				(arc
					(start 419.162738 -237.037626)
					(mid 419.166458 -237.028646)
					(end 419.175438 -237.024926)
				)
				(arc
					(start 420.648638 -237.024926)
					(mid 420.657618 -237.028646)
					(end 420.661338 -237.037626)
				)
			)
		)
	)
	(zone
		(layer "In1.Cu")
		(hatch none 0.5)
		(connect_pads
			(clearance 0)
		)
		(min_thickness 0.25)
		(keepout
			(tracks not_allowed)
			(vias allowed)
			(pads allowed)
			(copperpour not_allowed)
			(footprints allowed)
		)
		(placement
			(enabled no)
			(sheetname "")
		)
		(fill
			(thermal_gap 0.5)
			(thermal_bridge_width 0.5)
			(island_removal_mode 0)
		)
		(polygon
			(pts
				(arc
					(start 103.808022 -31.978854)
					(mid 103.83034 -31.924972)
					(end 103.884222 -31.902654)
				)
				(arc
					(start 104.112822 -31.902654)
					(mid 104.166704 -31.924972)
					(end 104.189022 -31.978854)
				)
				(arc
					(start 104.189022 -32.131254)
					(mid 104.166704 -32.185136)
					(end 104.112822 -32.207454)
				)
				(arc
					(start 103.884222 -32.207454)
					(mid 103.83034 -32.185136)
					(end 103.808022 -32.131254)
				)
			)
		)
	)
	(zone
		(layer "In1.Cu")
		(hatch none 0.5)
		(connect_pads
			(clearance 0)
		)
		(min_thickness 0.25)
		(keepout
			(tracks not_allowed)
			(vias allowed)
			(pads allowed)
			(copperpour not_allowed)
			(footprints allowed)
		)
		(placement
			(enabled no)
			(sheetname "")
		)
		(fill
			(thermal_gap 0.5)
			(thermal_bridge_width 0.5)
			(island_removal_mode 0)
		)
		(polygon
			(pts
				(arc
					(start 454.937368 -216.28227)
					(mid 454.933648 -216.29125)
					(end 454.924668 -216.29497)
				)
				(arc
					(start 453.451468 -216.29497)
					(mid 453.442488 -216.29125)
					(end 453.438768 -216.28227)
				)
				(arc
					(start 453.438768 -215.787732)
					(mid 453.442488 -215.778752)
					(end 453.451468 -215.775032)
				)
				(arc
					(start 454.924668 -215.775032)
					(mid 454.933648 -215.778752)
					(end 454.937368 -215.787732)
				)
			)
		)
	)
	(zone
		(layer "In1.Cu")
		(hatch none 0.5)
		(connect_pads
			(clearance 0)
		)
		(min_thickness 0.25)
		(keepout
			(tracks not_allowed)
			(vias allowed)
			(pads allowed)
			(copperpour not_allowed)
			(footprints allowed)
		)
		(placement
			(enabled no)
			(sheetname "")
		)
		(fill
			(thermal_gap 0.5)
			(thermal_bridge_width 0.5)
			(island_removal_mode 0)
		)
		(polygon
			(pts
				(arc
					(start 40.98925 -218.83243)
					(mid 40.98553 -218.84141)
					(end 40.97655 -218.84513)
				)
				(arc
					(start 39.50335 -218.84513)
					(mid 39.49437 -218.84141)
					(end 39.49065 -218.83243)
				)
				(arc
					(start 39.49065 -218.337892)
					(mid 39.49437 -218.328912)
					(end 39.50335 -218.325192)
				)
				(arc
					(start 40.97655 -218.325192)
					(mid 40.98553 -218.328912)
					(end 40.98925 -218.337892)
				)
			)
		)
	)
	(zone
		(layer "In1.Cu")
		(hatch none 0.5)
		(connect_pads
			(clearance 0)
		)
		(min_thickness 0.25)
		(keepout
			(tracks not_allowed)
			(vias allowed)
			(pads allowed)
			(copperpour not_allowed)
			(footprints allowed)
		)
		(placement
			(enabled no)
			(sheetname "")
		)
		(fill
			(thermal_gap 0.5)
			(thermal_bridge_width 0.5)
			(island_removal_mode 0)
		)
		(polygon
			(pts
				(arc
					(start 49.391062 -391.319258)
					(mid 49.518062 -391.446258)
					(end 49.645062 -391.319258)
				)
				(arc
					(start 49.645062 -391.243058)
					(mid 49.518062 -391.116058)
					(end 49.391062 -391.243058)
				)
			)
		)
	)
	(zone
		(layer "In1.Cu")
		(hatch none 0.5)
		(connect_pads
			(clearance 0)
		)
		(min_thickness 0.25)
		(keepout
			(tracks not_allowed)
			(vias allowed)
			(pads allowed)
			(copperpour not_allowed)
			(footprints allowed)
		)
		(placement
			(enabled no)
			(sheetname "")
		)
		(fill
			(thermal_gap 0.5)
			(thermal_bridge_width 0.5)
			(island_removal_mode 0)
		)
		(polygon
			(pts
				(arc
					(start 127.291084 -383.440686)
					(mid 127.418084 -383.567686)
					(end 127.545084 -383.440686)
				)
				(arc
					(start 127.545084 -383.364486)
					(mid 127.418084 -383.237486)
					(end 127.291084 -383.364486)
				)
			)
		)
	)
	(zone
		(layer "In1.Cu")
		(hatch none 0.5)
		(connect_pads
			(clearance 0)
		)
		(min_thickness 0.25)
		(keepout
			(tracks not_allowed)
			(vias allowed)
			(pads allowed)
			(copperpour not_allowed)
			(footprints allowed)
		)
		(placement
			(enabled no)
			(sheetname "")
		)
		(fill
			(thermal_gap 0.5)
			(thermal_bridge_width 0.5)
			(island_removal_mode 0)
		)
		(polygon
			(pts
				(arc
					(start 420.661338 -316.582298)
					(mid 420.657618 -316.591278)
					(end 420.648638 -316.594998)
				)
				(arc
					(start 419.175438 -316.594998)
					(mid 419.166458 -316.591278)
					(end 419.162738 -316.582298)
				)
				(arc
					(start 419.162738 -316.08776)
					(mid 419.166458 -316.07878)
					(end 419.175438 -316.07506)
				)
				(arc
					(start 420.648638 -316.07506)
					(mid 420.657618 -316.07878)
					(end 420.661338 -316.08776)
				)
			)
		)
	)
	(zone
		(layer "In1.Cu")
		(hatch none 0.5)
		(connect_pads
			(clearance 0)
		)
		(min_thickness 0.25)
		(keepout
			(tracks not_allowed)
			(vias allowed)
			(pads allowed)
			(copperpour not_allowed)
			(footprints allowed)
		)
		(placement
			(enabled no)
			(sheetname "")
		)
		(fill
			(thermal_gap 0.5)
			(thermal_bridge_width 0.5)
			(island_removal_mode 0)
		)
		(polygon
			(pts
				(arc
					(start 94.38894 -388.774432)
					(mid 94.00794 -388.774432)
					(end 94.38894 -388.774432)
				)
			)
		)
	)
	(zone
		(layer "In1.Cu")
		(hatch none 0.5)
		(connect_pads
			(clearance 0)
		)
		(min_thickness 0.25)
		(keepout
			(tracks not_allowed)
			(vias allowed)
			(pads allowed)
			(copperpour not_allowed)
			(footprints allowed)
		)
		(placement
			(enabled no)
			(sheetname "")
		)
		(fill
			(thermal_gap 0.5)
			(thermal_bridge_width 0.5)
			(island_removal_mode 0)
		)
		(polygon
			(pts
				(arc
					(start 420.661338 -248.58218)
					(mid 420.657618 -248.59116)
					(end 420.648638 -248.59488)
				)
				(arc
					(start 419.175438 -248.59488)
					(mid 419.166458 -248.59116)
					(end 419.162738 -248.58218)
				)
				(arc
					(start 419.162738 -248.087642)
					(mid 419.166458 -248.078662)
					(end 419.175438 -248.074942)
				)
				(arc
					(start 420.648638 -248.074942)
					(mid 420.657618 -248.078662)
					(end 420.661338 -248.087642)
				)
			)
		)
	)
	(zone
		(layer "In1.Cu")
		(hatch none 0.5)
		(connect_pads
			(clearance 0)
		)
		(min_thickness 0.25)
		(keepout
			(tracks not_allowed)
			(vias allowed)
			(pads allowed)
			(copperpour not_allowed)
			(footprints allowed)
		)
		(placement
			(enabled no)
			(sheetname "")
		)
		(fill
			(thermal_gap 0.5)
			(thermal_bridge_width 0.5)
			(island_removal_mode 0)
		)
		(polygon
			(pts
				(arc
					(start 450.8373 -229.882192)
					(mid 450.83358 -229.891172)
					(end 450.8246 -229.894892)
				)
				(arc
					(start 449.3514 -229.894892)
					(mid 449.34242 -229.891172)
					(end 449.3387 -229.882192)
				)
				(arc
					(start 449.3387 -229.387654)
					(mid 449.34242 -229.378674)
					(end 449.3514 -229.374954)
				)
				(arc
					(start 450.8246 -229.374954)
					(mid 450.83358 -229.378674)
					(end 450.8373 -229.387654)
				)
			)
		)
	)
	(zone
		(layer "In1.Cu")
		(hatch none 0.5)
		(connect_pads
			(clearance 0)
		)
		(min_thickness 0.25)
		(keepout
			(tracks not_allowed)
			(vias allowed)
			(pads allowed)
			(copperpour not_allowed)
			(footprints allowed)
		)
		(placement
			(enabled no)
			(sheetname "")
		)
		(fill
			(thermal_gap 0.5)
			(thermal_bridge_width 0.5)
			(island_removal_mode 0)
		)
		(polygon
			(pts
				(arc
					(start 195.353432 -318.282574)
					(mid 195.349712 -318.291554)
					(end 195.340732 -318.295274)
				)
				(arc
					(start 193.867532 -318.295274)
					(mid 193.858552 -318.291554)
					(end 193.854832 -318.282574)
				)
				(arc
					(start 193.854832 -317.788036)
					(mid 193.858552 -317.779056)
					(end 193.867532 -317.775336)
				)
				(arc
					(start 195.340732 -317.775336)
					(mid 195.349712 -317.779056)
					(end 195.353432 -317.788036)
				)
			)
		)
	)
	(zone
		(layer "In1.Cu")
		(hatch none 0.5)
		(connect_pads
			(clearance 0)
		)
		(min_thickness 0.25)
		(keepout
			(tracks not_allowed)
			(vias allowed)
			(pads allowed)
			(copperpour not_allowed)
			(footprints allowed)
		)
		(placement
			(enabled no)
			(sheetname "")
		)
		(fill
			(thermal_gap 0.5)
			(thermal_bridge_width 0.5)
			(island_removal_mode 0)
		)
		(polygon
			(pts
				(arc
					(start 435.749446 -279.182322)
					(mid 435.745726 -279.191302)
					(end 435.736746 -279.195022)
				)
				(arc
					(start 434.263546 -279.195022)
					(mid 434.254566 -279.191302)
					(end 434.250846 -279.182322)
				)
				(arc
					(start 434.250846 -278.687784)
					(mid 434.254566 -278.678804)
					(end 434.263546 -278.675084)
				)
				(arc
					(start 435.736746 -278.675084)
					(mid 435.745726 -278.678804)
					(end 435.749446 -278.687784)
				)
			)
		)
	)
	(zone
		(layer "In1.Cu")
		(hatch none 0.5)
		(connect_pads
			(clearance 0)
		)
		(min_thickness 0.25)
		(keepout
			(tracks not_allowed)
			(vias allowed)
			(pads allowed)
			(copperpour not_allowed)
			(footprints allowed)
		)
		(placement
			(enabled no)
			(sheetname "")
		)
		(fill
			(thermal_gap 0.5)
			(thermal_bridge_width 0.5)
			(island_removal_mode 0)
		)
		(polygon
			(pts
				(arc
					(start 165.177216 -299.582586)
					(mid 165.173496 -299.591566)
					(end 165.164516 -299.595286)
				)
				(arc
					(start 163.691316 -299.595286)
					(mid 163.682336 -299.591566)
					(end 163.678616 -299.582586)
				)
				(arc
					(start 163.678616 -299.088048)
					(mid 163.682336 -299.079068)
					(end 163.691316 -299.075348)
				)
				(arc
					(start 165.164516 -299.075348)
					(mid 165.173496 -299.079068)
					(end 165.177216 -299.088048)
				)
			)
		)
	)
	(zone
		(layer "In1.Cu")
		(hatch none 0.5)
		(connect_pads
			(clearance 0)
		)
		(min_thickness 0.25)
		(keepout
			(tracks not_allowed)
			(vias allowed)
			(pads allowed)
			(copperpour not_allowed)
			(footprints allowed)
		)
		(placement
			(enabled no)
			(sheetname "")
		)
		(fill
			(thermal_gap 0.5)
			(thermal_bridge_width 0.5)
			(island_removal_mode 0)
		)
		(polygon
			(pts
				(arc
					(start 37.545264 -270.682466)
					(mid 37.541544 -270.691446)
					(end 37.532564 -270.695166)
				)
				(arc
					(start 36.059364 -270.695166)
					(mid 36.050384 -270.691446)
					(end 36.046664 -270.682466)
				)
				(arc
					(start 36.046664 -270.187928)
					(mid 36.050384 -270.178948)
					(end 36.059364 -270.175228)
				)
				(arc
					(start 37.532564 -270.175228)
					(mid 37.541544 -270.178948)
					(end 37.545264 -270.187928)
				)
			)
		)
	)
	(zone
		(layer "In1.Cu")
		(hatch none 0.5)
		(connect_pads
			(clearance 0)
		)
		(min_thickness 0.25)
		(keepout
			(tracks not_allowed)
			(vias allowed)
			(pads allowed)
			(copperpour not_allowed)
			(footprints allowed)
		)
		(placement
			(enabled no)
			(sheetname "")
		)
		(fill
			(thermal_gap 0.5)
			(thermal_bridge_width 0.5)
			(island_removal_mode 0)
		)
		(polygon
			(pts
				(arc
					(start 130.891026 -383.440686)
					(mid 131.018026 -383.567686)
					(end 131.145026 -383.440686)
				)
				(arc
					(start 131.145026 -383.364486)
					(mid 131.018026 -383.237486)
					(end 130.891026 -383.364486)
				)
			)
		)
	)
	(zone
		(layer "In1.Cu")
		(hatch none 0.5)
		(connect_pads
			(clearance 0)
		)
		(min_thickness 0.25)
		(keepout
			(tracks not_allowed)
			(vias allowed)
			(pads allowed)
			(copperpour not_allowed)
			(footprints allowed)
		)
		(placement
			(enabled no)
			(sheetname "")
		)
		(fill
			(thermal_gap 0.5)
			(thermal_bridge_width 0.5)
			(island_removal_mode 0)
		)
		(polygon
			(pts
				(arc
					(start 435.749446 -226.482148)
					(mid 435.745726 -226.491128)
					(end 435.736746 -226.494848)
				)
				(arc
					(start 434.263546 -226.494848)
					(mid 434.254566 -226.491128)
					(end 434.250846 -226.482148)
				)
				(arc
					(start 434.250846 -225.98761)
					(mid 434.254566 -225.97863)
					(end 434.263546 -225.97491)
				)
				(arc
					(start 435.736746 -225.97491)
					(mid 435.745726 -225.97863)
					(end 435.749446 -225.98761)
				)
			)
		)
	)
	(zone
		(layer "In1.Cu")
		(hatch none 0.5)
		(connect_pads
			(clearance 0)
		)
		(min_thickness 0.25)
		(keepout
			(tracks not_allowed)
			(vias allowed)
			(pads allowed)
			(copperpour not_allowed)
			(footprints allowed)
		)
		(placement
			(enabled no)
			(sheetname "")
		)
		(fill
			(thermal_gap 0.5)
			(thermal_bridge_width 0.5)
			(island_removal_mode 0)
		)
		(polygon
			(pts
				(arc
					(start 277.941532 -223.932242)
					(mid 277.937812 -223.941222)
					(end 277.928832 -223.944942)
				)
				(arc
					(start 276.455632 -223.944942)
					(mid 276.446652 -223.941222)
					(end 276.442932 -223.932242)
				)
				(arc
					(start 276.442932 -223.437704)
					(mid 276.446652 -223.428724)
					(end 276.455632 -223.425004)
				)
				(arc
					(start 277.928832 -223.425004)
					(mid 277.937812 -223.428724)
					(end 277.941532 -223.437704)
				)
			)
		)
	)
	(zone
		(layer "In1.Cu")
		(hatch none 0.5)
		(connect_pads
			(clearance 0)
		)
		(min_thickness 0.25)
		(keepout
			(tracks not_allowed)
			(vias allowed)
			(pads allowed)
			(copperpour not_allowed)
			(footprints allowed)
		)
		(placement
			(enabled no)
			(sheetname "")
		)
		(fill
			(thermal_gap 0.5)
			(thermal_bridge_width 0.5)
			(island_removal_mode 0)
		)
		(polygon
			(pts
				(arc
					(start 288.929318 -223.082104)
					(mid 288.925598 -223.091084)
					(end 288.916618 -223.094804)
				)
				(arc
					(start 287.443418 -223.094804)
					(mid 287.434438 -223.091084)
					(end 287.430718 -223.082104)
				)
				(arc
					(start 287.430718 -222.587566)
					(mid 287.434438 -222.578586)
					(end 287.443418 -222.574866)
				)
				(arc
					(start 288.916618 -222.574866)
					(mid 288.925598 -222.578586)
					(end 288.929318 -222.587566)
				)
			)
		)
	)
	(zone
		(layer "In1.Cu")
		(hatch none 0.5)
		(connect_pads
			(clearance 0)
		)
		(min_thickness 0.25)
		(keepout
			(tracks not_allowed)
			(vias allowed)
			(pads allowed)
			(copperpour not_allowed)
			(footprints allowed)
		)
		(placement
			(enabled no)
			(sheetname "")
		)
		(fill
			(thermal_gap 0.5)
			(thermal_bridge_width 0.5)
			(island_removal_mode 0)
		)
		(polygon
			(pts
				(arc
					(start 288.929318 -232.432098)
					(mid 288.925598 -232.441078)
					(end 288.916618 -232.444798)
				)
				(arc
					(start 287.443418 -232.444798)
					(mid 287.434438 -232.441078)
					(end 287.430718 -232.432098)
				)
				(arc
					(start 287.430718 -231.93756)
					(mid 287.434438 -231.92858)
					(end 287.443418 -231.92486)
				)
				(arc
					(start 288.916618 -231.92486)
					(mid 288.925598 -231.92858)
					(end 288.929318 -231.93756)
				)
			)
		)
	)
	(zone
		(layer "In1.Cu")
		(hatch none 0.5)
		(connect_pads
			(clearance 0)
		)
		(min_thickness 0.25)
		(keepout
			(tracks not_allowed)
			(vias allowed)
			(pads allowed)
			(copperpour not_allowed)
			(footprints allowed)
		)
		(placement
			(enabled no)
			(sheetname "")
		)
		(fill
			(thermal_gap 0.5)
			(thermal_bridge_width 0.5)
			(island_removal_mode 0)
		)
		(polygon
			(pts
				(arc
					(start 25.901396 -207.782414)
					(mid 25.897676 -207.791394)
					(end 25.888696 -207.795114)
				)
				(arc
					(start 24.415496 -207.795114)
					(mid 24.406516 -207.791394)
					(end 24.402796 -207.782414)
				)
				(arc
					(start 24.402796 -207.287876)
					(mid 24.406516 -207.278896)
					(end 24.415496 -207.275176)
				)
				(arc
					(start 25.888696 -207.275176)
					(mid 25.897676 -207.278896)
					(end 25.901396 -207.287876)
				)
			)
		)
	)
	(zone
		(layer "In1.Cu")
		(hatch none 0.5)
		(connect_pads
			(clearance 0)
		)
		(min_thickness 0.25)
		(keepout
			(tracks not_allowed)
			(vias allowed)
			(pads allowed)
			(copperpour not_allowed)
			(footprints allowed)
		)
		(placement
			(enabled no)
			(sheetname "")
		)
		(fill
			(thermal_gap 0.5)
			(thermal_bridge_width 0.5)
			(island_removal_mode 0)
		)
		(polygon
			(pts
				(arc
					(start 195.353432 -202.682348)
					(mid 195.349712 -202.691328)
					(end 195.340732 -202.695048)
				)
				(arc
					(start 193.867532 -202.695048)
					(mid 193.858552 -202.691328)
					(end 193.854832 -202.682348)
				)
				(arc
					(start 193.854832 -202.18781)
					(mid 193.858552 -202.17883)
					(end 193.867532 -202.17511)
				)
				(arc
					(start 195.340732 -202.17511)
					(mid 195.349712 -202.17883)
					(end 195.353432 -202.18781)
				)
			)
		)
	)
	(zone
		(layer "In1.Cu")
		(hatch none 0.5)
		(connect_pads
			(clearance 0)
		)
		(min_thickness 0.25)
		(keepout
			(tracks not_allowed)
			(vias allowed)
			(pads allowed)
			(copperpour not_allowed)
			(footprints allowed)
		)
		(placement
			(enabled no)
			(sheetname "")
		)
		(fill
			(thermal_gap 0.5)
			(thermal_bridge_width 0.5)
			(island_removal_mode 0)
		)
		(polygon
			(pts
				(arc
					(start 33.445196 -240.082578)
					(mid 33.441476 -240.091558)
					(end 33.432496 -240.095278)
				)
				(arc
					(start 31.959296 -240.095278)
					(mid 31.950316 -240.091558)
					(end 31.946596 -240.082578)
				)
				(arc
					(start 31.946596 -239.58804)
					(mid 31.950316 -239.57906)
					(end 31.959296 -239.57534)
				)
				(arc
					(start 33.432496 -239.57534)
					(mid 33.441476 -239.57906)
					(end 33.445196 -239.58804)
				)
			)
		)
	)
	(zone
		(layer "In1.Cu")
		(hatch none 0.5)
		(connect_pads
			(clearance 0)
		)
		(min_thickness 0.25)
		(keepout
			(tracks not_allowed)
			(vias allowed)
			(pads allowed)
			(copperpour not_allowed)
			(footprints allowed)
		)
		(placement
			(enabled no)
			(sheetname "")
		)
		(fill
			(thermal_gap 0.5)
			(thermal_bridge_width 0.5)
			(island_removal_mode 0)
		)
		(polygon
			(pts
				(arc
					(start 308.117494 -308.082188)
					(mid 308.113774 -308.091168)
					(end 308.104794 -308.094888)
				)
				(arc
					(start 306.631594 -308.094888)
					(mid 306.622614 -308.091168)
					(end 306.618894 -308.082188)
				)
				(arc
					(start 306.618894 -307.58765)
					(mid 306.622614 -307.57867)
					(end 306.631594 -307.57495)
				)
				(arc
					(start 308.104794 -307.57495)
					(mid 308.113774 -307.57867)
					(end 308.117494 -307.58765)
				)
			)
		)
	)
	(zone
		(layer "In1.Cu")
		(hatch none 0.5)
		(connect_pads
			(clearance 0)
		)
		(min_thickness 0.25)
		(keepout
			(tracks not_allowed)
			(vias allowed)
			(pads allowed)
			(copperpour not_allowed)
			(footprints allowed)
		)
		(placement
			(enabled no)
			(sheetname "")
		)
		(fill
			(thermal_gap 0.5)
			(thermal_bridge_width 0.5)
			(island_removal_mode 0)
		)
		(polygon
			(pts
				(arc
					(start 380.561088 -397.849344)
					(mid 380.180088 -397.849344)
					(end 380.561088 -397.849344)
				)
			)
		)
	)
	(zone
		(layer "In1.Cu")
		(hatch none 0.5)
		(connect_pads
			(clearance 0)
		)
		(min_thickness 0.25)
		(keepout
			(tracks not_allowed)
			(vias allowed)
			(pads allowed)
			(copperpour not_allowed)
			(footprints allowed)
		)
		(placement
			(enabled no)
			(sheetname "")
		)
		(fill
			(thermal_gap 0.5)
			(thermal_bridge_width 0.5)
			(island_removal_mode 0)
		)
		(polygon
			(pts
				(arc
					(start 285.485332 -210.33232)
					(mid 285.481612 -210.3413)
					(end 285.472632 -210.34502)
				)
				(arc
					(start 283.999432 -210.34502)
					(mid 283.990452 -210.3413)
					(end 283.986732 -210.33232)
				)
				(arc
					(start 283.986732 -209.837782)
					(mid 283.990452 -209.828802)
					(end 283.999432 -209.825082)
				)
				(arc
					(start 285.472632 -209.825082)
					(mid 285.481612 -209.828802)
					(end 285.485332 -209.837782)
				)
			)
		)
	)
	(zone
		(layer "In1.Cu")
		(hatch none 0.5)
		(connect_pads
			(clearance 0)
		)
		(min_thickness 0.25)
		(keepout
			(tracks not_allowed)
			(vias allowed)
			(pads allowed)
			(copperpour not_allowed)
			(footprints allowed)
		)
		(placement
			(enabled no)
			(sheetname "")
		)
		(fill
			(thermal_gap 0.5)
			(thermal_bridge_width 0.5)
			(island_removal_mode 0)
		)
		(polygon
			(pts
				(arc
					(start 424.761406 -201.83221)
					(mid 424.757686 -201.84119)
					(end 424.748706 -201.84491)
				)
				(arc
					(start 423.275506 -201.84491)
					(mid 423.266526 -201.84119)
					(end 423.262806 -201.83221)
				)
				(arc
					(start 423.262806 -201.337672)
					(mid 423.266526 -201.328692)
					(end 423.275506 -201.324972)
				)
				(arc
					(start 424.748706 -201.324972)
					(mid 424.757686 -201.328692)
					(end 424.761406 -201.337672)
				)
			)
		)
	)
	(zone
		(layer "In1.Cu")
		(hatch none 0.5)
		(connect_pads
			(clearance 0)
		)
		(min_thickness 0.25)
		(keepout
			(tracks not_allowed)
			(vias allowed)
			(pads allowed)
			(copperpour not_allowed)
			(footprints allowed)
		)
		(placement
			(enabled no)
			(sheetname "")
		)
		(fill
			(thermal_gap 0.5)
			(thermal_bridge_width 0.5)
			(island_removal_mode 0)
		)
		(polygon
			(pts
				(arc
					(start 293.029386 -315.73216)
					(mid 293.025666 -315.74114)
					(end 293.016686 -315.74486)
				)
				(arc
					(start 291.543486 -315.74486)
					(mid 291.534506 -315.74114)
					(end 291.530786 -315.73216)
				)
				(arc
					(start 291.530786 -315.237622)
					(mid 291.534506 -315.228642)
					(end 291.543486 -315.224922)
				)
				(arc
					(start 293.016686 -315.224922)
					(mid 293.025666 -315.228642)
					(end 293.029386 -315.237622)
				)
			)
		)
	)
	(zone
		(layer "In1.Cu")
		(hatch none 0.5)
		(connect_pads
			(clearance 0)
		)
		(min_thickness 0.25)
		(keepout
			(tracks not_allowed)
			(vias allowed)
			(pads allowed)
			(copperpour not_allowed)
			(footprints allowed)
		)
		(placement
			(enabled no)
			(sheetname "")
		)
		(fill
			(thermal_gap 0.5)
			(thermal_bridge_width 0.5)
			(island_removal_mode 0)
		)
		(polygon
			(pts
				(arc
					(start 277.941532 -254.53213)
					(mid 277.937812 -254.54111)
					(end 277.928832 -254.54483)
				)
				(arc
					(start 276.455632 -254.54483)
					(mid 276.446652 -254.54111)
					(end 276.442932 -254.53213)
				)
				(arc
					(start 276.442932 -254.037592)
					(mid 276.446652 -254.028612)
					(end 276.455632 -254.024892)
				)
				(arc
					(start 277.928832 -254.024892)
					(mid 277.937812 -254.028612)
					(end 277.941532 -254.037592)
				)
			)
		)
	)
	(zone
		(layer "In1.Cu")
		(hatch none 0.5)
		(connect_pads
			(clearance 0)
		)
		(min_thickness 0.25)
		(keepout
			(tracks not_allowed)
			(vias allowed)
			(pads allowed)
			(copperpour not_allowed)
			(footprints allowed)
		)
		(placement
			(enabled no)
			(sheetname "")
		)
		(fill
			(thermal_gap 0.5)
			(thermal_bridge_width 0.5)
			(island_removal_mode 0)
		)
		(polygon
			(pts
				(arc
					(start 313.460892 -394.385292)
					(mid 313.079892 -394.385292)
					(end 313.460892 -394.385292)
				)
			)
		)
	)
	(zone
		(layer "In1.Cu")
		(hatch none 0.5)
		(connect_pads
			(clearance 0)
		)
		(min_thickness 0.25)
		(keepout
			(tracks not_allowed)
			(vias allowed)
			(pads allowed)
			(copperpour not_allowed)
			(footprints allowed)
		)
		(placement
			(enabled no)
			(sheetname "")
		)
		(fill
			(thermal_gap 0.5)
			(thermal_bridge_width 0.5)
			(island_removal_mode 0)
		)
		(polygon
			(pts
				(arc
					(start 370.561362 -393.69238)
					(mid 370.180362 -393.69238)
					(end 370.561362 -393.69238)
				)
			)
		)
	)
	(zone
		(layer "In1.Cu")
		(hatch none 0.5)
		(connect_pads
			(clearance 0)
		)
		(min_thickness 0.25)
		(keepout
			(tracks not_allowed)
			(vias allowed)
			(pads allowed)
			(copperpour not_allowed)
			(footprints allowed)
		)
		(placement
			(enabled no)
			(sheetname "")
		)
		(fill
			(thermal_gap 0.5)
			(thermal_bridge_width 0.5)
			(island_removal_mode 0)
		)
		(polygon
			(pts
				(arc
					(start 373.690896 -391.822686)
					(mid 373.817896 -391.949686)
					(end 373.944896 -391.822686)
				)
				(arc
					(start 373.944896 -391.746486)
					(mid 373.817896 -391.619486)
					(end 373.690896 -391.746486)
				)
			)
		)
	)
	(zone
		(layer "In1.Cu")
		(hatch none 0.5)
		(connect_pads
			(clearance 0)
		)
		(min_thickness 0.25)
		(keepout
			(tracks not_allowed)
			(vias allowed)
			(pads allowed)
			(copperpour not_allowed)
			(footprints allowed)
		)
		(placement
			(enabled no)
			(sheetname "")
		)
		(fill
			(thermal_gap 0.5)
			(thermal_bridge_width 0.5)
			(island_removal_mode 0)
		)
		(polygon
			(pts
				(arc
					(start 48.533304 -229.882446)
					(mid 48.529584 -229.891426)
					(end 48.520604 -229.895146)
				)
				(arc
					(start 47.047404 -229.895146)
					(mid 47.038424 -229.891426)
					(end 47.034704 -229.882446)
				)
				(arc
					(start 47.034704 -229.387908)
					(mid 47.038424 -229.378928)
					(end 47.047404 -229.375208)
				)
				(arc
					(start 48.520604 -229.375208)
					(mid 48.529584 -229.378928)
					(end 48.533304 -229.387908)
				)
			)
		)
	)
	(zone
		(layer "In1.Cu")
		(hatch none 0.5)
		(connect_pads
			(clearance 0)
		)
		(min_thickness 0.25)
		(keepout
			(tracks not_allowed)
			(vias allowed)
			(pads allowed)
			(copperpour not_allowed)
			(footprints allowed)
		)
		(placement
			(enabled no)
			(sheetname "")
		)
		(fill
			(thermal_gap 0.5)
			(thermal_bridge_width 0.5)
			(island_removal_mode 0)
		)
		(polygon
			(pts
				(arc
					(start 424.761406 -292.782244)
					(mid 424.757686 -292.791224)
					(end 424.748706 -292.794944)
				)
				(arc
					(start 423.275506 -292.794944)
					(mid 423.266526 -292.791224)
					(end 423.262806 -292.782244)
				)
				(arc
					(start 423.262806 -292.287706)
					(mid 423.266526 -292.278726)
					(end 423.275506 -292.275006)
				)
				(arc
					(start 424.748706 -292.275006)
					(mid 424.757686 -292.278726)
					(end 424.761406 -292.287706)
				)
			)
		)
	)
	(zone
		(layer "In1.Cu")
		(hatch none 0.5)
		(connect_pads
			(clearance 0)
		)
		(min_thickness 0.25)
		(keepout
			(tracks not_allowed)
			(vias allowed)
			(pads allowed)
			(copperpour not_allowed)
			(footprints allowed)
		)
		(placement
			(enabled no)
			(sheetname "")
		)
		(fill
			(thermal_gap 0.5)
			(thermal_bridge_width 0.5)
			(island_removal_mode 0)
		)
		(polygon
			(pts
				(arc
					(start 308.117494 -297.032172)
					(mid 308.113774 -297.041152)
					(end 308.104794 -297.044872)
				)
				(arc
					(start 306.631594 -297.044872)
					(mid 306.622614 -297.041152)
					(end 306.618894 -297.032172)
				)
				(arc
					(start 306.618894 -296.537634)
					(mid 306.622614 -296.528654)
					(end 306.631594 -296.524934)
				)
				(arc
					(start 308.104794 -296.524934)
					(mid 308.113774 -296.528654)
					(end 308.117494 -296.537634)
				)
			)
		)
	)
	(zone
		(layer "In1.Cu")
		(hatch none 0.5)
		(connect_pads
			(clearance 0)
		)
		(min_thickness 0.25)
		(keepout
			(tracks not_allowed)
			(vias allowed)
			(pads allowed)
			(copperpour not_allowed)
			(footprints allowed)
		)
		(placement
			(enabled no)
			(sheetname "")
		)
		(fill
			(thermal_gap 0.5)
			(thermal_bridge_width 0.5)
			(island_removal_mode 0)
		)
		(polygon
			(pts
				(arc
					(start 439.849514 -275.782278)
					(mid 439.845794 -275.791258)
					(end 439.836814 -275.794978)
				)
				(arc
					(start 438.363614 -275.794978)
					(mid 438.354634 -275.791258)
					(end 438.350914 -275.782278)
				)
				(arc
					(start 438.350914 -275.28774)
					(mid 438.354634 -275.27876)
					(end 438.363614 -275.27504)
				)
				(arc
					(start 439.836814 -275.27504)
					(mid 439.845794 -275.27876)
					(end 439.849514 -275.28774)
				)
			)
		)
	)
	(zone
		(layer "In1.Cu")
		(hatch none 0.5)
		(connect_pads
			(clearance 0)
		)
		(min_thickness 0.25)
		(keepout
			(tracks not_allowed)
			(vias allowed)
			(pads allowed)
			(copperpour not_allowed)
			(footprints allowed)
		)
		(placement
			(enabled no)
			(sheetname "")
		)
		(fill
			(thermal_gap 0.5)
			(thermal_bridge_width 0.5)
			(island_removal_mode 0)
		)
		(polygon
			(pts
				(arc
					(start 417.217352 -217.982292)
					(mid 417.213632 -217.991272)
					(end 417.204652 -217.994992)
				)
				(arc
					(start 415.731452 -217.994992)
					(mid 415.722472 -217.991272)
					(end 415.718752 -217.982292)
				)
				(arc
					(start 415.718752 -217.487754)
					(mid 415.722472 -217.478774)
					(end 415.731452 -217.475054)
				)
				(arc
					(start 417.204652 -217.475054)
					(mid 417.213632 -217.478774)
					(end 417.217352 -217.487754)
				)
			)
		)
	)
	(zone
		(layer "In1.Cu")
		(hatch none 0.5)
		(connect_pads
			(clearance 0)
		)
		(min_thickness 0.25)
		(keepout
			(tracks not_allowed)
			(vias allowed)
			(pads allowed)
			(copperpour not_allowed)
			(footprints allowed)
		)
		(placement
			(enabled no)
			(sheetname "")
		)
		(fill
			(thermal_gap 0.5)
			(thermal_bridge_width 0.5)
			(island_removal_mode 0)
		)
		(polygon
			(pts
				(arc
					(start 270.397478 -292.782244)
					(mid 270.393758 -292.791224)
					(end 270.384778 -292.794944)
				)
				(arc
					(start 268.911578 -292.794944)
					(mid 268.902598 -292.791224)
					(end 268.898878 -292.782244)
				)
				(arc
					(start 268.898878 -292.287706)
					(mid 268.902598 -292.278726)
					(end 268.911578 -292.275006)
				)
				(arc
					(start 270.384778 -292.275006)
					(mid 270.393758 -292.278726)
					(end 270.397478 -292.287706)
				)
			)
		)
	)
	(zone
		(layer "In1.Cu")
		(hatch none 0.5)
		(connect_pads
			(clearance 0)
		)
		(min_thickness 0.25)
		(keepout
			(tracks not_allowed)
			(vias allowed)
			(pads allowed)
			(copperpour not_allowed)
			(footprints allowed)
		)
		(placement
			(enabled no)
			(sheetname "")
		)
		(fill
			(thermal_gap 0.5)
			(thermal_bridge_width 0.5)
			(island_removal_mode 0)
		)
		(polygon
			(pts
				(arc
					(start 298.560744 -390.65581)
					(mid 298.551508 -390.675734)
					(end 298.548298 -390.697466)
				)
				(arc
					(start 298.548298 -390.89203)
					(mid 298.570616 -390.945912)
					(end 298.624498 -390.96823)
				)
				(arc
					(start 299.310298 -390.96823)
					(mid 299.36418 -390.945912)
					(end 299.386498 -390.89203)
				)
				(arc
					(start 299.386498 -390.697466)
					(mid 299.38333 -390.675722)
					(end 299.374052 -390.65581)
				)
				(arc
					(start 299.181266 -390.359646)
					(mid 299.169044 -390.317962)
					(end 299.18152 -390.276334)
				)
				(arc
					(start 299.374052 -389.98271)
					(mid 299.383288 -389.962786)
					(end 299.386498 -389.941054)
				)
				(arc
					(start 299.386498 -389.74649)
					(mid 299.36418 -389.692608)
					(end 299.310298 -389.67029)
				)
				(arc
					(start 298.624498 -389.67029)
					(mid 298.570616 -389.692608)
					(end 298.548298 -389.74649)
				)
				(arc
					(start 298.548298 -389.942324)
					(mid 298.551466 -389.964068)
					(end 298.560744 -389.98398)
				)
				(arc
					(start 298.753276 -390.277604)
					(mid 298.765678 -390.31926)
					(end 298.753276 -390.360916)
				)
			)
		)
	)
	(zone
		(layer "In1.Cu")
		(hatch none 0.5)
		(connect_pads
			(clearance 0)
		)
		(min_thickness 0.25)
		(keepout
			(tracks not_allowed)
			(vias allowed)
			(pads allowed)
			(copperpour not_allowed)
			(footprints allowed)
		)
		(placement
			(enabled no)
			(sheetname "")
		)
		(fill
			(thermal_gap 0.5)
			(thermal_bridge_width 0.5)
			(island_removal_mode 0)
		)
		(polygon
			(pts
				(arc
					(start 126.670308 -383.92227)
					(mid 126.365508 -383.92227)
					(end 126.670308 -383.92227)
				)
			)
		)
	)
	(zone
		(layer "In1.Cu")
		(hatch none 0.5)
		(connect_pads
			(clearance 0)
		)
		(min_thickness 0.25)
		(keepout
			(tracks not_allowed)
			(vias allowed)
			(pads allowed)
			(copperpour not_allowed)
			(footprints allowed)
		)
		(placement
			(enabled no)
			(sheetname "")
		)
		(fill
			(thermal_gap 0.5)
			(thermal_bridge_width 0.5)
			(island_removal_mode 0)
		)
		(polygon
			(pts
				(arc
					(start 443.2935 -202.682094)
					(mid 443.28978 -202.691074)
					(end 443.2808 -202.694794)
				)
				(arc
					(start 441.8076 -202.694794)
					(mid 441.79862 -202.691074)
					(end 441.7949 -202.682094)
				)
				(arc
					(start 441.7949 -202.187556)
					(mid 441.79862 -202.178576)
					(end 441.8076 -202.174856)
				)
				(arc
					(start 443.2808 -202.174856)
					(mid 443.28978 -202.178576)
					(end 443.2935 -202.187556)
				)
			)
		)
	)
	(zone
		(layer "In1.Cu")
		(hatch none 0.5)
		(connect_pads
			(clearance 0)
		)
		(min_thickness 0.25)
		(keepout
			(tracks not_allowed)
			(vias allowed)
			(pads allowed)
			(copperpour not_allowed)
			(footprints allowed)
		)
		(placement
			(enabled no)
			(sheetname "")
		)
		(fill
			(thermal_gap 0.5)
			(thermal_bridge_width 0.5)
			(island_removal_mode 0)
		)
		(polygon
			(pts
				(arc
					(start 40.98925 -229.882446)
					(mid 40.98553 -229.891426)
					(end 40.97655 -229.895146)
				)
				(arc
					(start 39.50335 -229.895146)
					(mid 39.49437 -229.891426)
					(end 39.49065 -229.882446)
				)
				(arc
					(start 39.49065 -229.387908)
					(mid 39.49437 -229.378928)
					(end 39.50335 -229.375208)
				)
				(arc
					(start 40.97655 -229.375208)
					(mid 40.98553 -229.378928)
					(end 40.98925 -229.387908)
				)
			)
		)
	)
	(zone
		(layer "In1.Cu")
		(hatch none 0.5)
		(connect_pads
			(clearance 0)
		)
		(min_thickness 0.25)
		(keepout
			(tracks not_allowed)
			(vias allowed)
			(pads allowed)
			(copperpour not_allowed)
			(footprints allowed)
		)
		(placement
			(enabled no)
			(sheetname "")
		)
		(fill
			(thermal_gap 0.5)
			(thermal_bridge_width 0.5)
			(island_removal_mode 0)
		)
		(polygon
			(pts
				(arc
					(start 300.57344 -211.182204)
					(mid 300.56972 -211.191184)
					(end 300.56074 -211.194904)
				)
				(arc
					(start 299.08754 -211.194904)
					(mid 299.07856 -211.191184)
					(end 299.07484 -211.182204)
				)
				(arc
					(start 299.07484 -210.687666)
					(mid 299.07856 -210.678686)
					(end 299.08754 -210.674966)
				)
				(arc
					(start 300.56074 -210.674966)
					(mid 300.56972 -210.678686)
					(end 300.57344 -210.687666)
				)
			)
		)
	)
	(zone
		(layer "In1.Cu")
		(hatch none 0.5)
		(connect_pads
			(clearance 0)
		)
		(min_thickness 0.25)
		(keepout
			(tracks not_allowed)
			(vias allowed)
			(pads allowed)
			(copperpour not_allowed)
			(footprints allowed)
		)
		(placement
			(enabled no)
			(sheetname "")
		)
		(fill
			(thermal_gap 0.5)
			(thermal_bridge_width 0.5)
			(island_removal_mode 0)
		)
		(polygon
			(pts
				(arc
					(start 432.30546 -281.732228)
					(mid 432.30174 -281.741208)
					(end 432.29276 -281.744928)
				)
				(arc
					(start 430.81956 -281.744928)
					(mid 430.81058 -281.741208)
					(end 430.80686 -281.732228)
				)
				(arc
					(start 430.80686 -281.23769)
					(mid 430.81058 -281.22871)
					(end 430.81956 -281.22499)
				)
				(arc
					(start 432.29276 -281.22499)
					(mid 432.30174 -281.22871)
					(end 432.30546 -281.23769)
				)
			)
		)
	)
	(zone
		(layer "In1.Cu")
		(hatch none 0.5)
		(connect_pads
			(clearance 0)
		)
		(min_thickness 0.25)
		(keepout
			(tracks not_allowed)
			(vias allowed)
			(pads allowed)
			(copperpour not_allowed)
			(footprints allowed)
		)
		(placement
			(enabled no)
			(sheetname "")
		)
		(fill
			(thermal_gap 0.5)
			(thermal_bridge_width 0.5)
			(island_removal_mode 0)
		)
		(polygon
			(pts
				(arc
					(start 370.090954 -391.822686)
					(mid 370.217954 -391.949686)
					(end 370.344954 -391.822686)
				)
				(arc
					(start 370.344954 -391.746486)
					(mid 370.217954 -391.619486)
					(end 370.090954 -391.746486)
				)
			)
		)
	)
	(zone
		(layer "In1.Cu")
		(hatch none 0.5)
		(connect_pads
			(clearance 0)
		)
		(min_thickness 0.25)
		(keepout
			(tracks not_allowed)
			(vias allowed)
			(pads allowed)
			(copperpour not_allowed)
			(footprints allowed)
		)
		(placement
			(enabled no)
			(sheetname "")
		)
		(fill
			(thermal_gap 0.5)
			(thermal_bridge_width 0.5)
			(island_removal_mode 0)
		)
		(polygon
			(pts
				(arc
					(start 206.9973 -229.882446)
					(mid 206.99358 -229.891426)
					(end 206.9846 -229.895146)
				)
				(arc
					(start 205.5114 -229.895146)
					(mid 205.50242 -229.891426)
					(end 205.4987 -229.882446)
				)
				(arc
					(start 205.4987 -229.387908)
					(mid 205.50242 -229.378928)
					(end 205.5114 -229.375208)
				)
				(arc
					(start 206.9846 -229.375208)
					(mid 206.99358 -229.378928)
					(end 206.9973 -229.387908)
				)
			)
		)
	)
	(zone
		(layer "In1.Cu")
		(hatch none 0.5)
		(connect_pads
			(clearance 0)
		)
		(min_thickness 0.25)
		(keepout
			(tracks not_allowed)
			(vias allowed)
			(pads allowed)
			(copperpour not_allowed)
			(footprints allowed)
		)
		(placement
			(enabled no)
			(sheetname "")
		)
		(fill
			(thermal_gap 0.5)
			(thermal_bridge_width 0.5)
			(island_removal_mode 0)
		)
		(polygon
			(pts
				(arc
					(start 176.821338 -311.482486)
					(mid 176.817618 -311.491466)
					(end 176.808638 -311.495186)
				)
				(arc
					(start 175.335438 -311.495186)
					(mid 175.326458 -311.491466)
					(end 175.322738 -311.482486)
				)
				(arc
					(start 175.322738 -310.987948)
					(mid 175.326458 -310.978968)
					(end 175.335438 -310.975248)
				)
				(arc
					(start 176.808638 -310.975248)
					(mid 176.817618 -310.978968)
					(end 176.821338 -310.987948)
				)
			)
		)
	)
	(zone
		(layer "In1.Cu")
		(hatch none 0.5)
		(connect_pads
			(clearance 0)
		)
		(min_thickness 0.25)
		(keepout
			(tracks not_allowed)
			(vias allowed)
			(pads allowed)
			(copperpour not_allowed)
			(footprints allowed)
		)
		(placement
			(enabled no)
			(sheetname "")
		)
		(fill
			(thermal_gap 0.5)
			(thermal_bridge_width 0.5)
			(island_removal_mode 0)
		)
		(polygon
			(pts
				(arc
					(start 18.357342 -314.88253)
					(mid 18.353622 -314.89151)
					(end 18.344642 -314.89523)
				)
				(arc
					(start 16.871442 -314.89523)
					(mid 16.862462 -314.89151)
					(end 16.858742 -314.88253)
				)
				(arc
					(start 16.858742 -314.387992)
					(mid 16.862462 -314.379012)
					(end 16.871442 -314.375292)
				)
				(arc
					(start 18.344642 -314.375292)
					(mid 18.353622 -314.379012)
					(end 18.357342 -314.387992)
				)
			)
		)
	)
	(zone
		(layer "In1.Cu")
		(hatch none 0.5)
		(connect_pads
			(clearance 0)
		)
		(min_thickness 0.25)
		(keepout
			(tracks not_allowed)
			(vias allowed)
			(pads allowed)
			(copperpour not_allowed)
			(footprints allowed)
		)
		(placement
			(enabled no)
			(sheetname "")
		)
		(fill
			(thermal_gap 0.5)
			(thermal_bridge_width 0.5)
			(island_removal_mode 0)
		)
		(polygon
			(pts
				(arc
					(start 119.761 -389.467344)
					(mid 119.38 -389.467344)
					(end 119.761 -389.467344)
				)
			)
		)
	)
	(zone
		(layer "In1.Cu")
		(hatch none 0.5)
		(connect_pads
			(clearance 0)
		)
		(min_thickness 0.25)
		(keepout
			(tracks not_allowed)
			(vias allowed)
			(pads allowed)
			(copperpour not_allowed)
			(footprints allowed)
		)
		(placement
			(enabled no)
			(sheetname "")
		)
		(fill
			(thermal_gap 0.5)
			(thermal_bridge_width 0.5)
			(island_removal_mode 0)
		)
		(polygon
			(pts
				(arc
					(start 343.188798 -393.69238)
					(mid 342.807798 -393.69238)
					(end 343.188798 -393.69238)
				)
			)
		)
	)
	(zone
		(layer "In1.Cu")
		(hatch none 0.5)
		(connect_pads
			(clearance 0)
		)
		(min_thickness 0.25)
		(keepout
			(tracks not_allowed)
			(vias allowed)
			(pads allowed)
			(copperpour not_allowed)
			(footprints allowed)
		)
		(placement
			(enabled no)
			(sheetname "")
		)
		(fill
			(thermal_gap 0.5)
			(thermal_bridge_width 0.5)
			(island_removal_mode 0)
		)
		(polygon
			(pts
				(arc
					(start 172.72127 -235.832396)
					(mid 172.71755 -235.841376)
					(end 172.70857 -235.845096)
				)
				(arc
					(start 171.23537 -235.845096)
					(mid 171.22639 -235.841376)
					(end 171.22267 -235.832396)
				)
				(arc
					(start 171.22267 -235.337858)
					(mid 171.22639 -235.328878)
					(end 171.23537 -235.325158)
				)
				(arc
					(start 172.70857 -235.325158)
					(mid 172.71755 -235.328878)
					(end 172.72127 -235.337858)
				)
			)
		)
	)
	(zone
		(layer "In1.Cu")
		(hatch none 0.5)
		(connect_pads
			(clearance 0)
		)
		(min_thickness 0.25)
		(keepout
			(tracks not_allowed)
			(vias allowed)
			(pads allowed)
			(copperpour not_allowed)
			(footprints allowed)
		)
		(placement
			(enabled no)
			(sheetname "")
		)
		(fill
			(thermal_gap 0.5)
			(thermal_bridge_width 0.5)
			(island_removal_mode 0)
		)
		(polygon
			(pts
				(arc
					(start 454.937368 -208.632298)
					(mid 454.933648 -208.641278)
					(end 454.924668 -208.644998)
				)
				(arc
					(start 453.451468 -208.644998)
					(mid 453.442488 -208.641278)
					(end 453.438768 -208.632298)
				)
				(arc
					(start 453.438768 -208.13776)
					(mid 453.442488 -208.12878)
					(end 453.451468 -208.12506)
				)
				(arc
					(start 454.924668 -208.12506)
					(mid 454.933648 -208.12878)
					(end 454.937368 -208.13776)
				)
			)
		)
	)
	(zone
		(layer "In1.Cu")
		(hatch none 0.5)
		(connect_pads
			(clearance 0)
		)
		(min_thickness 0.25)
		(keepout
			(tracks not_allowed)
			(vias allowed)
			(pads allowed)
			(copperpour not_allowed)
			(footprints allowed)
		)
		(placement
			(enabled no)
			(sheetname "")
		)
		(fill
			(thermal_gap 0.5)
			(thermal_bridge_width 0.5)
			(island_removal_mode 0)
		)
		(polygon
			(pts
				(arc
					(start 265.87831 -243.234972)
					(mid 265.21791 -243.234972)
					(end 265.87831 -243.234972)
				)
			)
		)
	)
	(zone
		(layer "In1.Cu")
		(hatch none 0.5)
		(connect_pads
			(clearance 0)
		)
		(min_thickness 0.25)
		(keepout
			(tracks not_allowed)
			(vias allowed)
			(pads allowed)
			(copperpour not_allowed)
			(footprints allowed)
		)
		(placement
			(enabled no)
			(sheetname "")
		)
		(fill
			(thermal_gap 0.5)
			(thermal_bridge_width 0.5)
			(island_removal_mode 0)
		)
		(polygon
			(pts
				(arc
					(start 91.989148 -388.774432)
					(mid 91.608148 -388.774432)
					(end 91.989148 -388.774432)
				)
			)
		)
	)
	(zone
		(layer "In1.Cu")
		(hatch none 0.5)
		(connect_pads
			(clearance 0)
		)
		(min_thickness 0.25)
		(keepout
			(tracks not_allowed)
			(vias allowed)
			(pads allowed)
			(copperpour not_allowed)
			(footprints allowed)
		)
		(placement
			(enabled no)
			(sheetname "")
		)
		(fill
			(thermal_gap 0.5)
			(thermal_bridge_width 0.5)
			(island_removal_mode 0)
		)
		(polygon
			(pts
				(arc
					(start 420.661338 -226.482148)
					(mid 420.657618 -226.491128)
					(end 420.648638 -226.494848)
				)
				(arc
					(start 419.175438 -226.494848)
					(mid 419.166458 -226.491128)
					(end 419.162738 -226.482148)
				)
				(arc
					(start 419.162738 -225.98761)
					(mid 419.166458 -225.97863)
					(end 419.175438 -225.97491)
				)
				(arc
					(start 420.648638 -225.97491)
					(mid 420.657618 -225.97863)
					(end 420.661338 -225.98761)
				)
			)
		)
	)
	(zone
		(layer "In1.Cu")
		(hatch none 0.5)
		(connect_pads
			(clearance 0)
		)
		(min_thickness 0.25)
		(keepout
			(tracks not_allowed)
			(vias allowed)
			(pads allowed)
			(copperpour not_allowed)
			(footprints allowed)
		)
		(placement
			(enabled no)
			(sheetname "")
		)
		(fill
			(thermal_gap 0.5)
			(thermal_bridge_width 0.5)
			(island_removal_mode 0)
		)
		(polygon
			(pts
				(arc
					(start 199.4535 -229.882446)
					(mid 199.44978 -229.891426)
					(end 199.4408 -229.895146)
				)
				(arc
					(start 197.9676 -229.895146)
					(mid 197.95862 -229.891426)
					(end 197.9549 -229.882446)
				)
				(arc
					(start 197.9549 -229.387908)
					(mid 197.95862 -229.378928)
					(end 197.9676 -229.375208)
				)
				(arc
					(start 199.4408 -229.375208)
					(mid 199.44978 -229.378928)
					(end 199.4535 -229.387908)
				)
			)
		)
	)
	(zone
		(layer "In1.Cu")
		(hatch none 0.5)
		(connect_pads
			(clearance 0)
		)
		(min_thickness 0.25)
		(keepout
			(tracks not_allowed)
			(vias allowed)
			(pads allowed)
			(copperpour not_allowed)
			(footprints allowed)
		)
		(placement
			(enabled no)
			(sheetname "")
		)
		(fill
			(thermal_gap 0.5)
			(thermal_bridge_width 0.5)
			(island_removal_mode 0)
		)
		(polygon
			(pts
				(arc
					(start 30.001464 -238.382556)
					(mid 29.997744 -238.391536)
					(end 29.988764 -238.395256)
				)
				(arc
					(start 28.515564 -238.395256)
					(mid 28.506584 -238.391536)
					(end 28.502864 -238.382556)
				)
				(arc
					(start 28.502864 -237.888018)
					(mid 28.506584 -237.879038)
					(end 28.515564 -237.875318)
				)
				(arc
					(start 29.988764 -237.875318)
					(mid 29.997744 -237.879038)
					(end 30.001464 -237.888018)
				)
			)
		)
	)
	(zone
		(layer "In1.Cu")
		(hatch none 0.5)
		(connect_pads
			(clearance 0)
		)
		(min_thickness 0.25)
		(keepout
			(tracks not_allowed)
			(vias allowed)
			(pads allowed)
			(copperpour not_allowed)
			(footprints allowed)
		)
		(placement
			(enabled no)
			(sheetname "")
		)
		(fill
			(thermal_gap 0.5)
			(thermal_bridge_width 0.5)
			(island_removal_mode 0)
		)
		(polygon
			(pts
				(arc
					(start 424.761406 -263.03224)
					(mid 424.757686 -263.04122)
					(end 424.748706 -263.04494)
				)
				(arc
					(start 423.275506 -263.04494)
					(mid 423.266526 -263.04122)
					(end 423.262806 -263.03224)
				)
				(arc
					(start 423.262806 -262.537702)
					(mid 423.266526 -262.528722)
					(end 423.275506 -262.525002)
				)
				(arc
					(start 424.748706 -262.525002)
					(mid 424.757686 -262.528722)
					(end 424.761406 -262.537702)
				)
			)
		)
	)
	(zone
		(layer "In1.Cu")
		(hatch none 0.5)
		(connect_pads
			(clearance 0)
		)
		(min_thickness 0.25)
		(keepout
			(tracks not_allowed)
			(vias allowed)
			(pads allowed)
			(copperpour not_allowed)
			(footprints allowed)
		)
		(placement
			(enabled no)
			(sheetname "")
		)
		(fill
			(thermal_gap 0.5)
			(thermal_bridge_width 0.5)
			(island_removal_mode 0)
		)
		(polygon
			(pts
				(arc
					(start 176.821338 -239.23244)
					(mid 176.817618 -239.24142)
					(end 176.808638 -239.24514)
				)
				(arc
					(start 175.335438 -239.24514)
					(mid 175.326458 -239.24142)
					(end 175.322738 -239.23244)
				)
				(arc
					(start 175.322738 -238.737902)
					(mid 175.326458 -238.728922)
					(end 175.335438 -238.725202)
				)
				(arc
					(start 176.808638 -238.725202)
					(mid 176.817618 -238.728922)
					(end 176.821338 -238.737902)
				)
			)
		)
	)
	(zone
		(layer "In1.Cu")
		(hatch none 0.5)
		(connect_pads
			(clearance 0)
		)
		(min_thickness 0.25)
		(keepout
			(tracks not_allowed)
			(vias allowed)
			(pads allowed)
			(copperpour not_allowed)
			(footprints allowed)
		)
		(placement
			(enabled no)
			(sheetname "")
		)
		(fill
			(thermal_gap 0.5)
			(thermal_bridge_width 0.5)
			(island_removal_mode 0)
		)
		(polygon
			(pts
				(arc
					(start 206.5782 -210.085432)
					(mid 205.9178 -210.085432)
					(end 206.5782 -210.085432)
				)
			)
		)
	)
	(zone
		(layer "In1.Cu")
		(hatch none 0.5)
		(connect_pads
			(clearance 0)
		)
		(min_thickness 0.25)
		(keepout
			(tracks not_allowed)
			(vias allowed)
			(pads allowed)
			(copperpour not_allowed)
			(footprints allowed)
		)
		(placement
			(enabled no)
			(sheetname "")
		)
		(fill
			(thermal_gap 0.5)
			(thermal_bridge_width 0.5)
			(island_removal_mode 0)
		)
		(polygon
			(pts
				(arc
					(start 296.473372 -308.932326)
					(mid 296.469652 -308.941306)
					(end 296.460672 -308.945026)
				)
				(arc
					(start 294.987472 -308.945026)
					(mid 294.978492 -308.941306)
					(end 294.974772 -308.932326)
				)
				(arc
					(start 294.974772 -308.437788)
					(mid 294.978492 -308.428808)
					(end 294.987472 -308.425088)
				)
				(arc
					(start 296.460672 -308.425088)
					(mid 296.469652 -308.428808)
					(end 296.473372 -308.437788)
				)
			)
		)
	)
	(zone
		(layer "In1.Cu")
		(hatch none 0.5)
		(connect_pads
			(clearance 0)
		)
		(min_thickness 0.25)
		(keepout
			(tracks not_allowed)
			(vias allowed)
			(pads allowed)
			(copperpour not_allowed)
			(footprints allowed)
		)
		(placement
			(enabled no)
			(sheetname "")
		)
		(fill
			(thermal_gap 0.5)
			(thermal_bridge_width 0.5)
			(island_removal_mode 0)
		)
		(polygon
			(pts
				(arc
					(start 176.821338 -229.882446)
					(mid 176.817618 -229.891426)
					(end 176.808638 -229.895146)
				)
				(arc
					(start 175.335438 -229.895146)
					(mid 175.326458 -229.891426)
					(end 175.322738 -229.882446)
				)
				(arc
					(start 175.322738 -229.387908)
					(mid 175.326458 -229.378928)
					(end 175.335438 -229.375208)
				)
				(arc
					(start 176.808638 -229.375208)
					(mid 176.817618 -229.378928)
					(end 176.821338 -229.387908)
				)
			)
		)
	)
	(zone
		(layer "In1.Cu")
		(hatch none 0.5)
		(connect_pads
			(clearance 0)
		)
		(min_thickness 0.25)
		(keepout
			(tracks not_allowed)
			(vias allowed)
			(pads allowed)
			(copperpour not_allowed)
			(footprints allowed)
		)
		(placement
			(enabled no)
			(sheetname "")
		)
		(fill
			(thermal_gap 0.5)
			(thermal_bridge_width 0.5)
			(island_removal_mode 0)
		)
		(polygon
			(pts
				(arc
					(start 417.217352 -208.632298)
					(mid 417.213632 -208.641278)
					(end 417.204652 -208.644998)
				)
				(arc
					(start 415.731452 -208.644998)
					(mid 415.722472 -208.641278)
					(end 415.718752 -208.632298)
				)
				(arc
					(start 415.718752 -208.13776)
					(mid 415.722472 -208.12878)
					(end 415.731452 -208.12506)
				)
				(arc
					(start 417.204652 -208.12506)
					(mid 417.213632 -208.12878)
					(end 417.217352 -208.13776)
				)
			)
		)
	)
	(zone
		(layer "In1.Cu")
		(hatch none 0.5)
		(connect_pads
			(clearance 0)
		)
		(min_thickness 0.25)
		(keepout
			(tracks not_allowed)
			(vias allowed)
			(pads allowed)
			(copperpour not_allowed)
			(footprints allowed)
		)
		(placement
			(enabled no)
			(sheetname "")
		)
		(fill
			(thermal_gap 0.5)
			(thermal_bridge_width 0.5)
			(island_removal_mode 0)
		)
		(polygon
			(pts
				(arc
					(start 417.217352 -219.682314)
					(mid 417.213632 -219.691294)
					(end 417.204652 -219.695014)
				)
				(arc
					(start 415.731452 -219.695014)
					(mid 415.722472 -219.691294)
					(end 415.718752 -219.682314)
				)
				(arc
					(start 415.718752 -219.187776)
					(mid 415.722472 -219.178796)
					(end 415.731452 -219.175076)
				)
				(arc
					(start 417.204652 -219.175076)
					(mid 417.213632 -219.178796)
					(end 417.217352 -219.187776)
				)
			)
		)
	)
	(zone
		(layer "In1.Cu")
		(hatch none 0.5)
		(connect_pads
			(clearance 0)
		)
		(min_thickness 0.25)
		(keepout
			(tracks not_allowed)
			(vias allowed)
			(pads allowed)
			(copperpour not_allowed)
			(footprints allowed)
		)
		(placement
			(enabled no)
			(sheetname "")
		)
		(fill
			(thermal_gap 0.5)
			(thermal_bridge_width 0.5)
			(island_removal_mode 0)
		)
		(polygon
			(pts
				(arc
					(start 281.385264 -253.682246)
					(mid 281.381544 -253.691226)
					(end 281.372564 -253.694946)
				)
				(arc
					(start 279.899364 -253.694946)
					(mid 279.890384 -253.691226)
					(end 279.886664 -253.682246)
				)
				(arc
					(start 279.886664 -253.187708)
					(mid 279.890384 -253.178728)
					(end 279.899364 -253.175008)
				)
				(arc
					(start 281.372564 -253.175008)
					(mid 281.381544 -253.178728)
					(end 281.385264 -253.187708)
				)
			)
		)
	)
	(zone
		(layer "In1.Cu")
		(hatch none 0.5)
		(connect_pads
			(clearance 0)
		)
		(min_thickness 0.25)
		(keepout
			(tracks not_allowed)
			(vias allowed)
			(pads allowed)
			(copperpour not_allowed)
			(footprints allowed)
		)
		(placement
			(enabled no)
			(sheetname "")
		)
		(fill
			(thermal_gap 0.5)
			(thermal_bridge_width 0.5)
			(island_removal_mode 0)
		)
		(polygon
			(pts
				(arc
					(start 180.265324 -277.482554)
					(mid 180.261604 -277.491534)
					(end 180.252624 -277.495254)
				)
				(arc
					(start 178.779424 -277.495254)
					(mid 178.770444 -277.491534)
					(end 178.766724 -277.482554)
				)
				(arc
					(start 178.766724 -276.988016)
					(mid 178.770444 -276.979036)
					(end 178.779424 -276.975316)
				)
				(arc
					(start 180.252624 -276.975316)
					(mid 180.261604 -276.979036)
					(end 180.265324 -276.988016)
				)
			)
		)
	)
	(zone
		(layer "In1.Cu")
		(hatch none 0.5)
		(connect_pads
			(clearance 0)
		)
		(min_thickness 0.25)
		(keepout
			(tracks not_allowed)
			(vias allowed)
			(pads allowed)
			(copperpour not_allowed)
			(footprints allowed)
		)
		(placement
			(enabled no)
			(sheetname "")
		)
		(fill
			(thermal_gap 0.5)
			(thermal_bridge_width 0.5)
			(island_removal_mode 0)
		)
		(polygon
			(pts
				(arc
					(start 277.941532 -268.132306)
					(mid 277.937812 -268.141286)
					(end 277.928832 -268.145006)
				)
				(arc
					(start 276.455632 -268.145006)
					(mid 276.446652 -268.141286)
					(end 276.442932 -268.132306)
				)
				(arc
					(start 276.442932 -267.637768)
					(mid 276.446652 -267.628788)
					(end 276.455632 -267.625068)
				)
				(arc
					(start 277.928832 -267.625068)
					(mid 277.937812 -267.628788)
					(end 277.941532 -267.637768)
				)
			)
		)
	)
	(zone
		(layer "In1.Cu")
		(hatch none 0.5)
		(connect_pads
			(clearance 0)
		)
		(min_thickness 0.25)
		(keepout
			(tracks not_allowed)
			(vias allowed)
			(pads allowed)
			(copperpour not_allowed)
			(footprints allowed)
		)
		(placement
			(enabled no)
			(sheetname "")
		)
		(fill
			(thermal_gap 0.5)
			(thermal_bridge_width 0.5)
			(island_removal_mode 0)
		)
		(polygon
			(pts
				(arc
					(start 304.017426 -200.132188)
					(mid 304.013706 -200.141168)
					(end 304.004726 -200.144888)
				)
				(arc
					(start 302.531526 -200.144888)
					(mid 302.522546 -200.141168)
					(end 302.518826 -200.132188)
				)
				(arc
					(start 302.518826 -199.63765)
					(mid 302.522546 -199.62867)
					(end 302.531526 -199.62495)
				)
				(arc
					(start 304.004726 -199.62495)
					(mid 304.013706 -199.62867)
					(end 304.017426 -199.63765)
				)
			)
		)
	)
	(zone
		(layer "In1.Cu")
		(hatch none 0.5)
		(connect_pads
			(clearance 0)
		)
		(min_thickness 0.25)
		(keepout
			(tracks not_allowed)
			(vias allowed)
			(pads allowed)
			(copperpour not_allowed)
			(footprints allowed)
		)
		(placement
			(enabled no)
			(sheetname "")
		)
		(fill
			(thermal_gap 0.5)
			(thermal_bridge_width 0.5)
			(island_removal_mode 0)
		)
		(polygon
			(pts
				(arc
					(start 191.909446 -244.332506)
					(mid 191.905726 -244.341486)
					(end 191.896746 -244.345206)
				)
				(arc
					(start 190.423546 -244.345206)
					(mid 190.414566 -244.341486)
					(end 190.410846 -244.332506)
				)
				(arc
					(start 190.410846 -243.837968)
					(mid 190.414566 -243.828988)
					(end 190.423546 -243.825268)
				)
				(arc
					(start 191.896746 -243.825268)
					(mid 191.905726 -243.828988)
					(end 191.909446 -243.837968)
				)
			)
		)
	)
	(zone
		(layer "In1.Cu")
		(hatch none 0.5)
		(connect_pads
			(clearance 0)
		)
		(min_thickness 0.25)
		(keepout
			(tracks not_allowed)
			(vias allowed)
			(pads allowed)
			(copperpour not_allowed)
			(footprints allowed)
		)
		(placement
			(enabled no)
			(sheetname "")
		)
		(fill
			(thermal_gap 0.5)
			(thermal_bridge_width 0.5)
			(island_removal_mode 0)
		)
		(polygon
			(pts
				(arc
					(start 33.445196 -253.6825)
					(mid 33.441476 -253.69148)
					(end 33.432496 -253.6952)
				)
				(arc
					(start 31.959296 -253.6952)
					(mid 31.950316 -253.69148)
					(end 31.946596 -253.6825)
				)
				(arc
					(start 31.946596 -253.187962)
					(mid 31.950316 -253.178982)
					(end 31.959296 -253.175262)
				)
				(arc
					(start 33.432496 -253.175262)
					(mid 33.441476 -253.178982)
					(end 33.445196 -253.187962)
				)
			)
		)
	)
	(zone
		(layer "In1.Cu")
		(hatch none 0.5)
		(connect_pads
			(clearance 0)
		)
		(min_thickness 0.25)
		(keepout
			(tracks not_allowed)
			(vias allowed)
			(pads allowed)
			(copperpour not_allowed)
			(footprints allowed)
		)
		(placement
			(enabled no)
			(sheetname "")
		)
		(fill
			(thermal_gap 0.5)
			(thermal_bridge_width 0.5)
			(island_removal_mode 0)
		)
		(polygon
			(pts
				(arc
					(start 405.598122 -399.143474)
					(mid 405.293322 -399.143474)
					(end 405.598122 -399.143474)
				)
			)
		)
	)
	(zone
		(layer "In1.Cu")
		(hatch none 0.5)
		(connect_pads
			(clearance 0)
		)
		(min_thickness 0.25)
		(keepout
			(tracks not_allowed)
			(vias allowed)
			(pads allowed)
			(copperpour not_allowed)
			(footprints allowed)
		)
		(placement
			(enabled no)
			(sheetname "")
		)
		(fill
			(thermal_gap 0.5)
			(thermal_bridge_width 0.5)
			(island_removal_mode 0)
		)
		(polygon
			(pts
				(arc
					(start 206.5782 -295.085262)
					(mid 205.9178 -295.085262)
					(end 206.5782 -295.085262)
				)
			)
		)
	)
	(zone
		(layer "In1.Cu")
		(hatch none 0.5)
		(connect_pads
			(clearance 0)
		)
		(min_thickness 0.25)
		(keepout
			(tracks not_allowed)
			(vias allowed)
			(pads allowed)
			(copperpour not_allowed)
			(footprints allowed)
		)
		(placement
			(enabled no)
			(sheetname "")
		)
		(fill
			(thermal_gap 0.5)
			(thermal_bridge_width 0.5)
			(island_removal_mode 0)
		)
		(polygon
			(pts
				(arc
					(start 165.177216 -248.582434)
					(mid 165.173496 -248.591414)
					(end 165.164516 -248.595134)
				)
				(arc
					(start 163.691316 -248.595134)
					(mid 163.682336 -248.591414)
					(end 163.678616 -248.582434)
				)
				(arc
					(start 163.678616 -248.087896)
					(mid 163.682336 -248.078916)
					(end 163.691316 -248.075196)
				)
				(arc
					(start 165.164516 -248.075196)
					(mid 165.173496 -248.078916)
					(end 165.177216 -248.087896)
				)
			)
		)
	)
	(zone
		(layer "In1.Cu")
		(hatch none 0.5)
		(connect_pads
			(clearance 0)
		)
		(min_thickness 0.25)
		(keepout
			(tracks not_allowed)
			(vias allowed)
			(pads allowed)
			(copperpour not_allowed)
			(footprints allowed)
		)
		(placement
			(enabled no)
			(sheetname "")
		)
		(fill
			(thermal_gap 0.5)
			(thermal_bridge_width 0.5)
			(island_removal_mode 0)
		)
		(polygon
			(pts
				(arc
					(start 345.98864 -394.385292)
					(mid 345.60764 -394.385292)
					(end 345.98864 -394.385292)
				)
			)
		)
	)
	(zone
		(layer "In1.Cu")
		(hatch none 0.5)
		(connect_pads
			(clearance 0)
		)
		(min_thickness 0.25)
		(keepout
			(tracks not_allowed)
			(vias allowed)
			(pads allowed)
			(copperpour not_allowed)
			(footprints allowed)
		)
		(placement
			(enabled no)
			(sheetname "")
		)
		(fill
			(thermal_gap 0.5)
			(thermal_bridge_width 0.5)
			(island_removal_mode 0)
		)
		(polygon
			(pts
				(arc
					(start 58.26125 -388.774432)
					(mid 57.88025 -388.774432)
					(end 58.26125 -388.774432)
				)
			)
		)
	)
	(zone
		(layer "In1.Cu")
		(hatch none 0.5)
		(connect_pads
			(clearance 0)
		)
		(min_thickness 0.25)
		(keepout
			(tracks not_allowed)
			(vias allowed)
			(pads allowed)
			(copperpour not_allowed)
			(footprints allowed)
		)
		(placement
			(enabled no)
			(sheetname "")
		)
		(fill
			(thermal_gap 0.5)
			(thermal_bridge_width 0.5)
			(island_removal_mode 0)
		)
		(polygon
			(pts
				(arc
					(start 25.901396 -288.53257)
					(mid 25.897676 -288.54155)
					(end 25.888696 -288.54527)
				)
				(arc
					(start 24.415496 -288.54527)
					(mid 24.406516 -288.54155)
					(end 24.402796 -288.53257)
				)
				(arc
					(start 24.402796 -288.038032)
					(mid 24.406516 -288.029052)
					(end 24.415496 -288.025332)
				)
				(arc
					(start 25.888696 -288.025332)
					(mid 25.897676 -288.029052)
					(end 25.901396 -288.038032)
				)
			)
		)
	)
	(zone
		(layer "In1.Cu")
		(hatch none 0.5)
		(connect_pads
			(clearance 0)
		)
		(min_thickness 0.25)
		(keepout
			(tracks not_allowed)
			(vias allowed)
			(pads allowed)
			(copperpour not_allowed)
			(footprints allowed)
		)
		(placement
			(enabled no)
			(sheetname "")
		)
		(fill
			(thermal_gap 0.5)
			(thermal_bridge_width 0.5)
			(island_removal_mode 0)
		)
		(polygon
			(pts
				(arc
					(start 296.473372 -248.58218)
					(mid 296.469652 -248.59116)
					(end 296.460672 -248.59488)
				)
				(arc
					(start 294.987472 -248.59488)
					(mid 294.978492 -248.59116)
					(end 294.974772 -248.58218)
				)
				(arc
					(start 294.974772 -248.087642)
					(mid 294.978492 -248.078662)
					(end 294.987472 -248.074942)
				)
				(arc
					(start 296.460672 -248.074942)
					(mid 296.469652 -248.078662)
					(end 296.473372 -248.087642)
				)
			)
		)
	)
	(zone
		(layer "In1.Cu")
		(hatch none 0.5)
		(connect_pads
			(clearance 0)
		)
		(min_thickness 0.25)
		(keepout
			(tracks not_allowed)
			(vias allowed)
			(pads allowed)
			(copperpour not_allowed)
			(footprints allowed)
		)
		(placement
			(enabled no)
			(sheetname "")
		)
		(fill
			(thermal_gap 0.5)
			(thermal_bridge_width 0.5)
			(island_removal_mode 0)
		)
		(polygon
			(pts
				(arc
					(start 18.357342 -314.032392)
					(mid 18.353622 -314.041372)
					(end 18.344642 -314.045092)
				)
				(arc
					(start 16.871442 -314.045092)
					(mid 16.862462 -314.041372)
					(end 16.858742 -314.032392)
				)
				(arc
					(start 16.858742 -313.537854)
					(mid 16.862462 -313.528874)
					(end 16.871442 -313.525154)
				)
				(arc
					(start 18.344642 -313.525154)
					(mid 18.353622 -313.528874)
					(end 18.357342 -313.537854)
				)
			)
		)
	)
	(zone
		(layer "In1.Cu")
		(hatch none 0.5)
		(connect_pads
			(clearance 0)
		)
		(min_thickness 0.25)
		(keepout
			(tracks not_allowed)
			(vias allowed)
			(pads allowed)
			(copperpour not_allowed)
			(footprints allowed)
		)
		(placement
			(enabled no)
			(sheetname "")
		)
		(fill
			(thermal_gap 0.5)
			(thermal_bridge_width 0.5)
			(island_removal_mode 0)
		)
		(polygon
			(pts
				(arc
					(start 319.061084 -393.69238)
					(mid 318.680084 -393.69238)
					(end 319.061084 -393.69238)
				)
			)
		)
	)
	(zone
		(layer "In1.Cu")
		(hatch none 0.5)
		(connect_pads
			(clearance 0)
		)
		(min_thickness 0.25)
		(keepout
			(tracks not_allowed)
			(vias allowed)
			(pads allowed)
			(copperpour not_allowed)
			(footprints allowed)
		)
		(placement
			(enabled no)
			(sheetname "")
		)
		(fill
			(thermal_gap 0.5)
			(thermal_bridge_width 0.5)
			(island_removal_mode 0)
		)
		(polygon
			(pts
				(arc
					(start 95.58909 -388.774432)
					(mid 95.20809 -388.774432)
					(end 95.58909 -388.774432)
				)
			)
		)
	)
	(zone
		(layer "In1.Cu")
		(hatch none 0.5)
		(connect_pads
			(clearance 0)
		)
		(min_thickness 0.25)
		(keepout
			(tracks not_allowed)
			(vias allowed)
			(pads allowed)
			(copperpour not_allowed)
			(footprints allowed)
		)
		(placement
			(enabled no)
			(sheetname "")
		)
		(fill
			(thermal_gap 0.5)
			(thermal_bridge_width 0.5)
			(island_removal_mode 0)
		)
		(polygon
			(pts
				(arc
					(start 206.5782 -228.78542)
					(mid 205.9178 -228.78542)
					(end 206.5782 -228.78542)
				)
			)
		)
	)
	(zone
		(layer "In1.Cu")
		(hatch none 0.5)
		(connect_pads
			(clearance 0)
		)
		(min_thickness 0.25)
		(keepout
			(tracks not_allowed)
			(vias allowed)
			(pads allowed)
			(copperpour not_allowed)
			(footprints allowed)
		)
		(placement
			(enabled no)
			(sheetname "")
		)
		(fill
			(thermal_gap 0.5)
			(thermal_bridge_width 0.5)
			(island_removal_mode 0)
		)
		(polygon
			(pts
				(arc
					(start 195.353432 -226.482402)
					(mid 195.349712 -226.491382)
					(end 195.340732 -226.495102)
				)
				(arc
					(start 193.867532 -226.495102)
					(mid 193.858552 -226.491382)
					(end 193.854832 -226.482402)
				)
				(arc
					(start 193.854832 -225.987864)
					(mid 193.858552 -225.978884)
					(end 193.867532 -225.975164)
				)
				(arc
					(start 195.340732 -225.975164)
					(mid 195.349712 -225.978884)
					(end 195.353432 -225.987864)
				)
			)
		)
	)
	(zone
		(layer "In1.Cu")
		(hatch none 0.5)
		(connect_pads
			(clearance 0)
		)
		(min_thickness 0.25)
		(keepout
			(tracks not_allowed)
			(vias allowed)
			(pads allowed)
			(copperpour not_allowed)
			(footprints allowed)
		)
		(placement
			(enabled no)
			(sheetname "")
		)
		(fill
			(thermal_gap 0.5)
			(thermal_bridge_width 0.5)
			(island_removal_mode 0)
		)
		(polygon
			(pts
				(arc
					(start 83.69808 -390.761474)
					(mid 83.39328 -390.761474)
					(end 83.69808 -390.761474)
				)
			)
		)
	)
	(zone
		(layer "In1.Cu")
		(hatch none 0.5)
		(connect_pads
			(clearance 0)
		)
		(min_thickness 0.25)
		(keepout
			(tracks not_allowed)
			(vias allowed)
			(pads allowed)
			(copperpour not_allowed)
			(footprints allowed)
		)
		(placement
			(enabled no)
			(sheetname "")
		)
		(fill
			(thermal_gap 0.5)
			(thermal_bridge_width 0.5)
			(island_removal_mode 0)
		)
		(polygon
			(pts
				(arc
					(start 273.841464 -253.682246)
					(mid 273.837744 -253.691226)
					(end 273.828764 -253.694946)
				)
				(arc
					(start 272.355564 -253.694946)
					(mid 272.346584 -253.691226)
					(end 272.342864 -253.682246)
				)
				(arc
					(start 272.342864 -253.187708)
					(mid 272.346584 -253.178728)
					(end 272.355564 -253.175008)
				)
				(arc
					(start 273.828764 -253.175008)
					(mid 273.837744 -253.178728)
					(end 273.841464 -253.187708)
				)
			)
		)
	)
	(zone
		(layer "In1.Cu")
		(hatch none 0.5)
		(connect_pads
			(clearance 0)
		)
		(min_thickness 0.25)
		(keepout
			(tracks not_allowed)
			(vias allowed)
			(pads allowed)
			(copperpour not_allowed)
			(footprints allowed)
		)
		(placement
			(enabled no)
			(sheetname "")
		)
		(fill
			(thermal_gap 0.5)
			(thermal_bridge_width 0.5)
			(island_removal_mode 0)
		)
		(polygon
			(pts
				(arc
					(start 120.67032 -383.92227)
					(mid 120.36552 -383.92227)
					(end 120.67032 -383.92227)
				)
			)
		)
	)
	(zone
		(layer "In1.Cu")
		(hatch none 0.5)
		(connect_pads
			(clearance 0)
		)
		(min_thickness 0.25)
		(keepout
			(tracks not_allowed)
			(vias allowed)
			(pads allowed)
			(copperpour not_allowed)
			(footprints allowed)
		)
		(placement
			(enabled no)
			(sheetname "")
		)
		(fill
			(thermal_gap 0.5)
			(thermal_bridge_width 0.5)
			(island_removal_mode 0)
		)
		(polygon
			(pts
				(arc
					(start 420.661338 -280.88209)
					(mid 420.657618 -280.89107)
					(end 420.648638 -280.89479)
				)
				(arc
					(start 419.175438 -280.89479)
					(mid 419.166458 -280.89107)
					(end 419.162738 -280.88209)
				)
				(arc
					(start 419.162738 -280.387552)
					(mid 419.166458 -280.378572)
					(end 419.175438 -280.374852)
				)
				(arc
					(start 420.648638 -280.374852)
					(mid 420.657618 -280.378572)
					(end 420.661338 -280.387552)
				)
			)
		)
	)
	(zone
		(layer "In1.Cu")
		(hatch none 0.5)
		(connect_pads
			(clearance 0)
		)
		(min_thickness 0.25)
		(keepout
			(tracks not_allowed)
			(vias allowed)
			(pads allowed)
			(copperpour not_allowed)
			(footprints allowed)
		)
		(placement
			(enabled no)
			(sheetname "")
		)
		(fill
			(thermal_gap 0.5)
			(thermal_bridge_width 0.5)
			(island_removal_mode 0)
		)
		(polygon
			(pts
				(arc
					(start 307.460904 -394.385292)
					(mid 307.079904 -394.385292)
					(end 307.460904 -394.385292)
				)
			)
		)
	)
	(zone
		(layer "In1.Cu")
		(hatch none 0.5)
		(connect_pads
			(clearance 0)
		)
		(min_thickness 0.25)
		(keepout
			(tracks not_allowed)
			(vias allowed)
			(pads allowed)
			(copperpour not_allowed)
			(footprints allowed)
		)
		(placement
			(enabled no)
			(sheetname "")
		)
		(fill
			(thermal_gap 0.5)
			(thermal_bridge_width 0.5)
			(island_removal_mode 0)
		)
		(polygon
			(pts
				(arc
					(start 285.485332 -313.182254)
					(mid 285.481612 -313.191234)
					(end 285.472632 -313.194954)
				)
				(arc
					(start 283.999432 -313.194954)
					(mid 283.990452 -313.191234)
					(end 283.986732 -313.182254)
				)
				(arc
					(start 283.986732 -312.687716)
					(mid 283.990452 -312.678736)
					(end 283.999432 -312.675016)
				)
				(arc
					(start 285.472632 -312.675016)
					(mid 285.481612 -312.678736)
					(end 285.485332 -312.687716)
				)
			)
		)
	)
	(zone
		(layer "In1.Cu")
		(hatch none 0.5)
		(connect_pads
			(clearance 0)
		)
		(min_thickness 0.25)
		(keepout
			(tracks not_allowed)
			(vias allowed)
			(pads allowed)
			(copperpour not_allowed)
			(footprints allowed)
		)
		(placement
			(enabled no)
			(sheetname "")
		)
		(fill
			(thermal_gap 0.5)
			(thermal_bridge_width 0.5)
			(island_removal_mode 0)
		)
		(polygon
			(pts
				(arc
					(start 114.561366 -385.31038)
					(mid 114.180366 -385.31038)
					(end 114.561366 -385.31038)
				)
			)
		)
	)
	(zone
		(layer "In1.Cu")
		(hatch none 0.5)
		(connect_pads
			(clearance 0)
		)
		(min_thickness 0.25)
		(keepout
			(tracks not_allowed)
			(vias allowed)
			(pads allowed)
			(copperpour not_allowed)
			(footprints allowed)
		)
		(placement
			(enabled no)
			(sheetname "")
		)
		(fill
			(thermal_gap 0.5)
			(thermal_bridge_width 0.5)
			(island_removal_mode 0)
		)
		(polygon
			(pts
				(arc
					(start 435.749446 -218.832176)
					(mid 435.745726 -218.841156)
					(end 435.736746 -218.844876)
				)
				(arc
					(start 434.263546 -218.844876)
					(mid 434.254566 -218.841156)
					(end 434.250846 -218.832176)
				)
				(arc
					(start 434.250846 -218.337638)
					(mid 434.254566 -218.328658)
					(end 434.263546 -218.324938)
				)
				(arc
					(start 435.736746 -218.324938)
					(mid 435.745726 -218.328658)
					(end 435.749446 -218.337638)
				)
			)
		)
	)
	(zone
		(layer "In1.Cu")
		(hatch none 0.5)
		(connect_pads
			(clearance 0)
		)
		(min_thickness 0.25)
		(keepout
			(tracks not_allowed)
			(vias allowed)
			(pads allowed)
			(copperpour not_allowed)
			(footprints allowed)
		)
		(placement
			(enabled no)
			(sheetname "")
		)
		(fill
			(thermal_gap 0.5)
			(thermal_bridge_width 0.5)
			(island_removal_mode 0)
		)
		(polygon
			(pts
				(arc
					(start 447.393568 -217.982292)
					(mid 447.389848 -217.991272)
					(end 447.380868 -217.994992)
				)
				(arc
					(start 445.907668 -217.994992)
					(mid 445.898688 -217.991272)
					(end 445.894968 -217.982292)
				)
				(arc
					(start 445.894968 -217.487754)
					(mid 445.898688 -217.478774)
					(end 445.907668 -217.475054)
				)
				(arc
					(start 447.380868 -217.475054)
					(mid 447.389848 -217.478774)
					(end 447.393568 -217.487754)
				)
			)
		)
	)
	(zone
		(layer "In1.Cu")
		(hatch none 0.5)
		(connect_pads
			(clearance 0)
		)
		(min_thickness 0.25)
		(keepout
			(tracks not_allowed)
			(vias allowed)
			(pads allowed)
			(copperpour not_allowed)
			(footprints allowed)
		)
		(placement
			(enabled no)
			(sheetname "")
		)
		(fill
			(thermal_gap 0.5)
			(thermal_bridge_width 0.5)
			(island_removal_mode 0)
		)
		(polygon
			(pts
				(arc
					(start 293.029386 -208.632298)
					(mid 293.025666 -208.641278)
					(end 293.016686 -208.644998)
				)
				(arc
					(start 291.543486 -208.644998)
					(mid 291.534506 -208.641278)
					(end 291.530786 -208.632298)
				)
				(arc
					(start 291.530786 -208.13776)
					(mid 291.534506 -208.12878)
					(end 291.543486 -208.12506)
				)
				(arc
					(start 293.016686 -208.12506)
					(mid 293.025666 -208.12878)
					(end 293.029386 -208.13776)
				)
			)
		)
	)
	(zone
		(layer "In1.Cu")
		(hatch none 0.5)
		(connect_pads
			(clearance 0)
		)
		(min_thickness 0.25)
		(keepout
			(tracks not_allowed)
			(vias allowed)
			(pads allowed)
			(copperpour not_allowed)
			(footprints allowed)
		)
		(placement
			(enabled no)
			(sheetname "")
		)
		(fill
			(thermal_gap 0.5)
			(thermal_bridge_width 0.5)
			(island_removal_mode 0)
		)
		(polygon
			(pts
				(arc
					(start 266.29741 -267.282168)
					(mid 266.29369 -267.291148)
					(end 266.28471 -267.294868)
				)
				(arc
					(start 264.81151 -267.294868)
					(mid 264.80253 -267.291148)
					(end 264.79881 -267.282168)
				)
				(arc
					(start 264.79881 -266.78763)
					(mid 264.80253 -266.77865)
					(end 264.81151 -266.77493)
				)
				(arc
					(start 266.28471 -266.77493)
					(mid 266.29369 -266.77865)
					(end 266.29741 -266.78763)
				)
			)
		)
	)
	(zone
		(layer "In1.Cu")
		(hatch none 0.5)
		(connect_pads
			(clearance 0)
		)
		(min_thickness 0.25)
		(keepout
			(tracks not_allowed)
			(vias allowed)
			(pads allowed)
			(copperpour not_allowed)
			(footprints allowed)
		)
		(placement
			(enabled no)
			(sheetname "")
		)
		(fill
			(thermal_gap 0.5)
			(thermal_bridge_width 0.5)
			(island_removal_mode 0)
		)
		(polygon
			(pts
				(arc
					(start 288.929318 -206.082138)
					(mid 288.925598 -206.091118)
					(end 288.916618 -206.094838)
				)
				(arc
					(start 287.443418 -206.094838)
					(mid 287.434438 -206.091118)
					(end 287.430718 -206.082138)
				)
				(arc
					(start 287.430718 -205.5876)
					(mid 287.434438 -205.57862)
					(end 287.443418 -205.5749)
				)
				(arc
					(start 288.916618 -205.5749)
					(mid 288.925598 -205.57862)
					(end 288.929318 -205.5876)
				)
			)
		)
	)
	(zone
		(layer "In1.Cu")
		(hatch none 0.5)
		(connect_pads
			(clearance 0)
		)
		(min_thickness 0.25)
		(keepout
			(tracks not_allowed)
			(vias allowed)
			(pads allowed)
			(copperpour not_allowed)
			(footprints allowed)
		)
		(placement
			(enabled no)
			(sheetname "")
		)
		(fill
			(thermal_gap 0.5)
			(thermal_bridge_width 0.5)
			(island_removal_mode 0)
		)
		(polygon
			(pts
				(arc
					(start 25.901396 -316.582552)
					(mid 25.897676 -316.591532)
					(end 25.888696 -316.595252)
				)
				(arc
					(start 24.415496 -316.595252)
					(mid 24.406516 -316.591532)
					(end 24.402796 -316.582552)
				)
				(arc
					(start 24.402796 -316.088014)
					(mid 24.406516 -316.079034)
					(end 24.415496 -316.075314)
				)
				(arc
					(start 25.888696 -316.075314)
					(mid 25.897676 -316.079034)
					(end 25.901396 -316.088014)
				)
			)
		)
	)
	(zone
		(layer "In1.Cu")
		(hatch none 0.5)
		(connect_pads
			(clearance 0)
		)
		(min_thickness 0.25)
		(keepout
			(tracks not_allowed)
			(vias allowed)
			(pads allowed)
			(copperpour not_allowed)
			(footprints allowed)
		)
		(placement
			(enabled no)
			(sheetname "")
		)
		(fill
			(thermal_gap 0.5)
			(thermal_bridge_width 0.5)
			(island_removal_mode 0)
		)
		(polygon
			(pts
				(arc
					(start 187.809378 -277.482554)
					(mid 187.805658 -277.491534)
					(end 187.796678 -277.495254)
				)
				(arc
					(start 186.323478 -277.495254)
					(mid 186.314498 -277.491534)
					(end 186.310778 -277.482554)
				)
				(arc
					(start 186.310778 -276.988016)
					(mid 186.314498 -276.979036)
					(end 186.323478 -276.975316)
				)
				(arc
					(start 187.796678 -276.975316)
					(mid 187.805658 -276.979036)
					(end 187.809378 -276.988016)
				)
			)
		)
	)
	(zone
		(layer "In1.Cu")
		(hatch none 0.5)
		(connect_pads
			(clearance 0)
		)
		(min_thickness 0.25)
		(keepout
			(tracks not_allowed)
			(vias allowed)
			(pads allowed)
			(copperpour not_allowed)
			(footprints allowed)
		)
		(placement
			(enabled no)
			(sheetname "")
		)
		(fill
			(thermal_gap 0.5)
			(thermal_bridge_width 0.5)
			(island_removal_mode 0)
		)
		(polygon
			(pts
				(arc
					(start 53.861208 -386.003292)
					(mid 53.480208 -386.003292)
					(end 53.861208 -386.003292)
				)
			)
		)
	)
	(zone
		(layer "In1.Cu")
		(hatch none 0.5)
		(connect_pads
			(clearance 0)
		)
		(min_thickness 0.25)
		(keepout
			(tracks not_allowed)
			(vias allowed)
			(pads allowed)
			(copperpour not_allowed)
			(footprints allowed)
		)
		(placement
			(enabled no)
			(sheetname "")
		)
		(fill
			(thermal_gap 0.5)
			(thermal_bridge_width 0.5)
			(island_removal_mode 0)
		)
		(polygon
			(pts
				(arc
					(start 130.891026 -391.319258)
					(mid 131.018026 -391.446258)
					(end 131.145026 -391.319258)
				)
				(arc
					(start 131.145026 -391.243058)
					(mid 131.018026 -391.116058)
					(end 130.891026 -391.243058)
				)
			)
		)
	)
	(zone
		(layer "In1.Cu")
		(hatch none 0.5)
		(connect_pads
			(clearance 0)
		)
		(min_thickness 0.25)
		(keepout
			(tracks not_allowed)
			(vias allowed)
			(pads allowed)
			(copperpour not_allowed)
			(footprints allowed)
		)
		(placement
			(enabled no)
			(sheetname "")
		)
		(fill
			(thermal_gap 0.5)
			(thermal_bridge_width 0.5)
			(island_removal_mode 0)
		)
		(polygon
			(pts
				(arc
					(start 319.17005 -399.143474)
					(mid 318.86525 -399.143474)
					(end 319.17005 -399.143474)
				)
			)
		)
	)
	(zone
		(layer "In1.Cu")
		(hatch none 0.5)
		(connect_pads
			(clearance 0)
		)
		(min_thickness 0.25)
		(keepout
			(tracks not_allowed)
			(vias allowed)
			(pads allowed)
			(copperpour not_allowed)
			(footprints allowed)
		)
		(placement
			(enabled no)
			(sheetname "")
		)
		(fill
			(thermal_gap 0.5)
			(thermal_bridge_width 0.5)
			(island_removal_mode 0)
		)
		(polygon
			(pts
				(arc
					(start 305.060858 -394.385292)
					(mid 304.679858 -394.385292)
					(end 305.060858 -394.385292)
				)
			)
		)
	)
	(zone
		(layer "In1.Cu")
		(hatch none 0.5)
		(connect_pads
			(clearance 0)
		)
		(min_thickness 0.25)
		(keepout
			(tracks not_allowed)
			(vias allowed)
			(pads allowed)
			(copperpour not_allowed)
			(footprints allowed)
		)
		(placement
			(enabled no)
			(sheetname "")
		)
		(fill
			(thermal_gap 0.5)
			(thermal_bridge_width 0.5)
			(island_removal_mode 0)
		)
		(polygon
			(pts
				(arc
					(start 443.2935 -305.532282)
					(mid 443.28978 -305.541262)
					(end 443.2808 -305.544982)
				)
				(arc
					(start 441.8076 -305.544982)
					(mid 441.79862 -305.541262)
					(end 441.7949 -305.532282)
				)
				(arc
					(start 441.7949 -305.037744)
					(mid 441.79862 -305.028764)
					(end 441.8076 -305.025044)
				)
				(arc
					(start 443.2808 -305.025044)
					(mid 443.28978 -305.028764)
					(end 443.2935 -305.037744)
				)
			)
		)
	)
	(zone
		(layer "In1.Cu")
		(hatch none 0.5)
		(connect_pads
			(clearance 0)
		)
		(min_thickness 0.25)
		(keepout
			(tracks not_allowed)
			(vias allowed)
			(pads allowed)
			(copperpour not_allowed)
			(footprints allowed)
		)
		(placement
			(enabled no)
			(sheetname "")
		)
		(fill
			(thermal_gap 0.5)
			(thermal_bridge_width 0.5)
			(island_removal_mode 0)
		)
		(polygon
			(pts
				(arc
					(start 265.87831 -263.634982)
					(mid 265.21791 -263.634982)
					(end 265.87831 -263.634982)
				)
			)
		)
	)
	(zone
		(layer "In1.Cu")
		(hatch none 0.5)
		(connect_pads
			(clearance 0)
		)
		(min_thickness 0.25)
		(keepout
			(tracks not_allowed)
			(vias allowed)
			(pads allowed)
			(copperpour not_allowed)
			(footprints allowed)
		)
		(placement
			(enabled no)
			(sheetname "")
		)
		(fill
			(thermal_gap 0.5)
			(thermal_bridge_width 0.5)
			(island_removal_mode 0)
		)
		(polygon
			(pts
				(arc
					(start 344.497914 -392.30427)
					(mid 344.193114 -392.30427)
					(end 344.497914 -392.30427)
				)
			)
		)
	)
	(zone
		(layer "In1.Cu")
		(hatch none 0.5)
		(connect_pads
			(clearance 0)
		)
		(min_thickness 0.25)
		(keepout
			(tracks not_allowed)
			(vias allowed)
			(pads allowed)
			(copperpour not_allowed)
			(footprints allowed)
		)
		(placement
			(enabled no)
			(sheetname "")
		)
		(fill
			(thermal_gap 0.5)
			(thermal_bridge_width 0.5)
			(island_removal_mode 0)
		)
		(polygon
			(pts
				(arc
					(start 122.161046 -386.003292)
					(mid 121.780046 -386.003292)
					(end 122.161046 -386.003292)
				)
			)
		)
	)
	(zone
		(layer "In1.Cu")
		(hatch none 0.5)
		(connect_pads
			(clearance 0)
		)
		(min_thickness 0.25)
		(keepout
			(tracks not_allowed)
			(vias allowed)
			(pads allowed)
			(copperpour not_allowed)
			(footprints allowed)
		)
		(placement
			(enabled no)
			(sheetname "")
		)
		(fill
			(thermal_gap 0.5)
			(thermal_bridge_width 0.5)
			(island_removal_mode 0)
		)
		(polygon
			(pts
				(arc
					(start 18.357342 -224.78238)
					(mid 18.353622 -224.79136)
					(end 18.344642 -224.79508)
				)
				(arc
					(start 16.871442 -224.79508)
					(mid 16.862462 -224.79136)
					(end 16.858742 -224.78238)
				)
				(arc
					(start 16.858742 -224.287842)
					(mid 16.862462 -224.278862)
					(end 16.871442 -224.275142)
				)
				(arc
					(start 18.344642 -224.275142)
					(mid 18.353622 -224.278862)
					(end 18.357342 -224.287842)
				)
			)
		)
	)
	(zone
		(layer "In1.Cu")
		(hatch none 0.5)
		(connect_pads
			(clearance 0)
		)
		(min_thickness 0.25)
		(keepout
			(tracks not_allowed)
			(vias allowed)
			(pads allowed)
			(copperpour not_allowed)
			(footprints allowed)
		)
		(placement
			(enabled no)
			(sheetname "")
		)
		(fill
			(thermal_gap 0.5)
			(thermal_bridge_width 0.5)
			(island_removal_mode 0)
		)
		(polygon
			(pts
				(arc
					(start 60.177426 -254.532384)
					(mid 60.173706 -254.541364)
					(end 60.164726 -254.545084)
				)
				(arc
					(start 58.691526 -254.545084)
					(mid 58.682546 -254.541364)
					(end 58.678826 -254.532384)
				)
				(arc
					(start 58.678826 -254.037846)
					(mid 58.682546 -254.028866)
					(end 58.691526 -254.025146)
				)
				(arc
					(start 60.164726 -254.025146)
					(mid 60.173706 -254.028866)
					(end 60.177426 -254.037846)
				)
			)
		)
	)
	(zone
		(layer "In1.Cu")
		(hatch none 0.5)
		(connect_pads
			(clearance 0)
		)
		(min_thickness 0.25)
		(keepout
			(tracks not_allowed)
			(vias allowed)
			(pads allowed)
			(copperpour not_allowed)
			(footprints allowed)
		)
		(placement
			(enabled no)
			(sheetname "")
		)
		(fill
			(thermal_gap 0.5)
			(thermal_bridge_width 0.5)
			(island_removal_mode 0)
		)
		(polygon
			(pts
				(arc
					(start 304.017426 -301.2821)
					(mid 304.013706 -301.29108)
					(end 304.004726 -301.2948)
				)
				(arc
					(start 302.531526 -301.2948)
					(mid 302.522546 -301.29108)
					(end 302.518826 -301.2821)
				)
				(arc
					(start 302.518826 -300.787562)
					(mid 302.522546 -300.778582)
					(end 302.531526 -300.774862)
				)
				(arc
					(start 304.004726 -300.774862)
					(mid 304.013706 -300.778582)
					(end 304.017426 -300.787562)
				)
			)
		)
	)
	(zone
		(layer "In1.Cu")
		(hatch none 0.5)
		(connect_pads
			(clearance 0)
		)
		(min_thickness 0.25)
		(keepout
			(tracks not_allowed)
			(vias allowed)
			(pads allowed)
			(copperpour not_allowed)
			(footprints allowed)
		)
		(placement
			(enabled no)
			(sheetname "")
		)
		(fill
			(thermal_gap 0.5)
			(thermal_bridge_width 0.5)
			(island_removal_mode 0)
		)
		(polygon
			(pts
				(arc
					(start 447.393568 -280.032206)
					(mid 447.389848 -280.041186)
					(end 447.380868 -280.044906)
				)
				(arc
					(start 445.907668 -280.044906)
					(mid 445.898688 -280.041186)
					(end 445.894968 -280.032206)
				)
				(arc
					(start 445.894968 -279.537668)
					(mid 445.898688 -279.528688)
					(end 445.907668 -279.524968)
				)
				(arc
					(start 447.380868 -279.524968)
					(mid 447.389848 -279.528688)
					(end 447.393568 -279.537668)
				)
			)
		)
	)
	(zone
		(layer "In1.Cu")
		(hatch none 0.5)
		(connect_pads
			(clearance 0)
		)
		(min_thickness 0.25)
		(keepout
			(tracks not_allowed)
			(vias allowed)
			(pads allowed)
			(copperpour not_allowed)
			(footprints allowed)
		)
		(placement
			(enabled no)
			(sheetname "")
		)
		(fill
			(thermal_gap 0.5)
			(thermal_bridge_width 0.5)
			(island_removal_mode 0)
		)
		(polygon
			(pts
				(arc
					(start 102.995222 -28.613354)
					(mid 103.01754 -28.559472)
					(end 103.071422 -28.537154)
				)
				(arc
					(start 103.300022 -28.537154)
					(mid 103.353904 -28.559472)
					(end 103.376222 -28.613354)
				)
				(arc
					(start 103.376222 -28.765754)
					(mid 103.353904 -28.819636)
					(end 103.300022 -28.841954)
				)
				(arc
					(start 103.071422 -28.841954)
					(mid 103.01754 -28.819636)
					(end 102.995222 -28.765754)
				)
			)
		)
	)
	(zone
		(layer "In1.Cu")
		(hatch none 0.5)
		(connect_pads
			(clearance 0)
		)
		(min_thickness 0.25)
		(keepout
			(tracks not_allowed)
			(vias allowed)
			(pads allowed)
			(copperpour not_allowed)
			(footprints allowed)
		)
		(placement
			(enabled no)
			(sheetname "")
		)
		(fill
			(thermal_gap 0.5)
			(thermal_bridge_width 0.5)
			(island_removal_mode 0)
		)
		(polygon
			(pts
				(arc
					(start 447.393568 -285.982156)
					(mid 447.389848 -285.991136)
					(end 447.380868 -285.994856)
				)
				(arc
					(start 445.907668 -285.994856)
					(mid 445.898688 -285.991136)
					(end 445.894968 -285.982156)
				)
				(arc
					(start 445.894968 -285.487618)
					(mid 445.898688 -285.478638)
					(end 445.907668 -285.474918)
				)
				(arc
					(start 447.380868 -285.474918)
					(mid 447.389848 -285.478638)
					(end 447.393568 -285.487618)
				)
			)
		)
	)
	(zone
		(layer "In1.Cu")
		(hatch none 0.5)
		(connect_pads
			(clearance 0)
		)
		(min_thickness 0.25)
		(keepout
			(tracks not_allowed)
			(vias allowed)
			(pads allowed)
			(copperpour not_allowed)
			(footprints allowed)
		)
		(placement
			(enabled no)
			(sheetname "")
		)
		(fill
			(thermal_gap 0.5)
			(thermal_bridge_width 0.5)
			(island_removal_mode 0)
		)
		(polygon
			(pts
				(arc
					(start 40.98925 -265.5824)
					(mid 40.98553 -265.59138)
					(end 40.97655 -265.5951)
				)
				(arc
					(start 39.50335 -265.5951)
					(mid 39.49437 -265.59138)
					(end 39.49065 -265.5824)
				)
				(arc
					(start 39.49065 -265.087862)
					(mid 39.49437 -265.078882)
					(end 39.50335 -265.075162)
				)
				(arc
					(start 40.97655 -265.075162)
					(mid 40.98553 -265.078882)
					(end 40.98925 -265.087862)
				)
			)
		)
	)
	(zone
		(layer "In1.Cu")
		(hatch none 0.5)
		(connect_pads
			(clearance 0)
		)
		(min_thickness 0.25)
		(keepout
			(tracks not_allowed)
			(vias allowed)
			(pads allowed)
			(copperpour not_allowed)
			(footprints allowed)
		)
		(placement
			(enabled no)
			(sheetname "")
		)
		(fill
			(thermal_gap 0.5)
			(thermal_bridge_width 0.5)
			(island_removal_mode 0)
		)
		(polygon
			(pts
				(arc
					(start 30.001464 -220.532452)
					(mid 29.997744 -220.541432)
					(end 29.988764 -220.545152)
				)
				(arc
					(start 28.515564 -220.545152)
					(mid 28.506584 -220.541432)
					(end 28.502864 -220.532452)
				)
				(arc
					(start 28.502864 -220.037914)
					(mid 28.506584 -220.028934)
					(end 28.515564 -220.025214)
				)
				(arc
					(start 29.988764 -220.025214)
					(mid 29.997744 -220.028934)
					(end 30.001464 -220.037914)
				)
			)
		)
	)
	(zone
		(layer "In1.Cu")
		(hatch none 0.5)
		(connect_pads
			(clearance 0)
		)
		(min_thickness 0.25)
		(keepout
			(tracks not_allowed)
			(vias allowed)
			(pads allowed)
			(copperpour not_allowed)
			(footprints allowed)
		)
		(placement
			(enabled no)
			(sheetname "")
		)
		(fill
			(thermal_gap 0.5)
			(thermal_bridge_width 0.5)
			(island_removal_mode 0)
		)
		(polygon
			(pts
				(arc
					(start 135.95985 -35.762438)
					(mid 135.905968 -35.74012)
					(end 135.88365 -35.686238)
				)
				(arc
					(start 135.88365 -35.260788)
					(mid 135.905968 -35.206906)
					(end 135.95985 -35.184588)
				)
				(arc
					(start 137.12825 -35.184588)
					(mid 137.182132 -35.206906)
					(end 137.20445 -35.260788)
				)
				(arc
					(start 137.20445 -35.686238)
					(mid 137.182132 -35.74012)
					(end 137.12825 -35.762438)
				)
			)
		)
	)
	(zone
		(layer "In1.Cu")
		(hatch none 0.5)
		(connect_pads
			(clearance 0)
		)
		(min_thickness 0.25)
		(keepout
			(tracks not_allowed)
			(vias allowed)
			(pads allowed)
			(copperpour not_allowed)
			(footprints allowed)
		)
		(placement
			(enabled no)
			(sheetname "")
		)
		(fill
			(thermal_gap 0.5)
			(thermal_bridge_width 0.5)
			(island_removal_mode 0)
		)
		(polygon
			(pts
				(arc
					(start 45.089318 -276.632416)
					(mid 45.085598 -276.641396)
					(end 45.076618 -276.645116)
				)
				(arc
					(start 43.603418 -276.645116)
					(mid 43.594438 -276.641396)
					(end 43.590718 -276.632416)
				)
				(arc
					(start 43.590718 -276.137878)
					(mid 43.594438 -276.128898)
					(end 43.603418 -276.125178)
				)
				(arc
					(start 45.076618 -276.125178)
					(mid 45.085598 -276.128898)
					(end 45.089318 -276.137878)
				)
			)
		)
	)
	(zone
		(layer "In1.Cu")
		(hatch none 0.5)
		(connect_pads
			(clearance 0)
		)
		(min_thickness 0.25)
		(keepout
			(tracks not_allowed)
			(vias allowed)
			(pads allowed)
			(copperpour not_allowed)
			(footprints allowed)
		)
		(placement
			(enabled no)
			(sheetname "")
		)
		(fill
			(thermal_gap 0.5)
			(thermal_bridge_width 0.5)
			(island_removal_mode 0)
		)
		(polygon
			(pts
				(arc
					(start 424.761406 -311.482232)
					(mid 424.757686 -311.491212)
					(end 424.748706 -311.494932)
				)
				(arc
					(start 423.275506 -311.494932)
					(mid 423.266526 -311.491212)
					(end 423.262806 -311.482232)
				)
				(arc
					(start 423.262806 -310.987694)
					(mid 423.266526 -310.978714)
					(end 423.275506 -310.974994)
				)
				(arc
					(start 424.748706 -310.974994)
					(mid 424.757686 -310.978714)
					(end 424.761406 -310.987694)
				)
			)
		)
	)
	(zone
		(layer "In1.Cu")
		(hatch none 0.5)
		(connect_pads
			(clearance 0)
		)
		(min_thickness 0.25)
		(keepout
			(tracks not_allowed)
			(vias allowed)
			(pads allowed)
			(copperpour not_allowed)
			(footprints allowed)
		)
		(placement
			(enabled no)
			(sheetname "")
		)
		(fill
			(thermal_gap 0.5)
			(thermal_bridge_width 0.5)
			(island_removal_mode 0)
		)
		(polygon
			(pts
				(arc
					(start 439.849514 -295.33215)
					(mid 439.845794 -295.34113)
					(end 439.836814 -295.34485)
				)
				(arc
					(start 438.363614 -295.34485)
					(mid 438.354634 -295.34113)
					(end 438.350914 -295.33215)
				)
				(arc
					(start 438.350914 -294.837612)
					(mid 438.354634 -294.828632)
					(end 438.363614 -294.824912)
				)
				(arc
					(start 439.836814 -294.824912)
					(mid 439.845794 -294.828632)
					(end 439.849514 -294.837612)
				)
			)
		)
	)
	(zone
		(layer "In1.Cu")
		(hatch none 0.5)
		(connect_pads
			(clearance 0)
		)
		(min_thickness 0.25)
		(keepout
			(tracks not_allowed)
			(vias allowed)
			(pads allowed)
			(copperpour not_allowed)
			(footprints allowed)
		)
		(placement
			(enabled no)
			(sheetname "")
		)
		(fill
			(thermal_gap 0.5)
			(thermal_bridge_width 0.5)
			(island_removal_mode 0)
		)
		(polygon
			(pts
				(arc
					(start 195.353432 -301.282354)
					(mid 195.349712 -301.291334)
					(end 195.340732 -301.295054)
				)
				(arc
					(start 193.867532 -301.295054)
					(mid 193.858552 -301.291334)
					(end 193.854832 -301.282354)
				)
				(arc
					(start 193.854832 -300.787816)
					(mid 193.858552 -300.778836)
					(end 193.867532 -300.775116)
				)
				(arc
					(start 195.340732 -300.775116)
					(mid 195.349712 -300.778836)
					(end 195.353432 -300.787816)
				)
			)
		)
	)
	(zone
		(layer "In1.Cu")
		(hatch none 0.5)
		(connect_pads
			(clearance 0)
		)
		(min_thickness 0.25)
		(keepout
			(tracks not_allowed)
			(vias allowed)
			(pads allowed)
			(copperpour not_allowed)
			(footprints allowed)
		)
		(placement
			(enabled no)
			(sheetname "")
		)
		(fill
			(thermal_gap 0.5)
			(thermal_bridge_width 0.5)
			(island_removal_mode 0)
		)
		(polygon
			(pts
				(arc
					(start 40.98925 -234.132374)
					(mid 40.98553 -234.141354)
					(end 40.97655 -234.145074)
				)
				(arc
					(start 39.50335 -234.145074)
					(mid 39.49437 -234.141354)
					(end 39.49065 -234.132374)
				)
				(arc
					(start 39.49065 -233.637836)
					(mid 39.49437 -233.628856)
					(end 39.50335 -233.625136)
				)
				(arc
					(start 40.97655 -233.625136)
					(mid 40.98553 -233.628856)
					(end 40.98925 -233.637836)
				)
			)
		)
	)
	(zone
		(layer "In1.Cu")
		(hatch none 0.5)
		(connect_pads
			(clearance 0)
		)
		(min_thickness 0.25)
		(keepout
			(tracks not_allowed)
			(vias allowed)
			(pads allowed)
			(copperpour not_allowed)
			(footprints allowed)
		)
		(placement
			(enabled no)
			(sheetname "")
		)
		(fill
			(thermal_gap 0.5)
			(thermal_bridge_width 0.5)
			(island_removal_mode 0)
		)
		(polygon
			(pts
				(arc
					(start 296.473372 -209.482182)
					(mid 296.469652 -209.491162)
					(end 296.460672 -209.494882)
				)
				(arc
					(start 294.987472 -209.494882)
					(mid 294.978492 -209.491162)
					(end 294.974772 -209.482182)
				)
				(arc
					(start 294.974772 -208.987644)
					(mid 294.978492 -208.978664)
					(end 294.987472 -208.974944)
				)
				(arc
					(start 296.460672 -208.974944)
					(mid 296.469652 -208.978664)
					(end 296.473372 -208.987644)
				)
			)
		)
	)
	(zone
		(layer "In1.Cu")
		(hatch none 0.5)
		(connect_pads
			(clearance 0)
		)
		(min_thickness 0.25)
		(keepout
			(tracks not_allowed)
			(vias allowed)
			(pads allowed)
			(copperpour not_allowed)
			(footprints allowed)
		)
		(placement
			(enabled no)
			(sheetname "")
		)
		(fill
			(thermal_gap 0.5)
			(thermal_bridge_width 0.5)
			(island_removal_mode 0)
		)
		(polygon
			(pts
				(arc
					(start 65.570354 -383.92227)
					(mid 65.265554 -383.92227)
					(end 65.570354 -383.92227)
				)
			)
		)
	)
	(zone
		(layer "In1.Cu")
		(hatch none 0.5)
		(connect_pads
			(clearance 0)
		)
		(min_thickness 0.25)
		(keepout
			(tracks not_allowed)
			(vias allowed)
			(pads allowed)
			(copperpour not_allowed)
			(footprints allowed)
		)
		(placement
			(enabled no)
			(sheetname "")
		)
		(fill
			(thermal_gap 0.5)
			(thermal_bridge_width 0.5)
			(island_removal_mode 0)
		)
		(polygon
			(pts
				(arc
					(start 304.017426 -215.432132)
					(mid 304.013706 -215.441112)
					(end 304.004726 -215.444832)
				)
				(arc
					(start 302.531526 -215.444832)
					(mid 302.522546 -215.441112)
					(end 302.518826 -215.432132)
				)
				(arc
					(start 302.518826 -214.937594)
					(mid 302.522546 -214.928614)
					(end 302.531526 -214.924894)
				)
				(arc
					(start 304.004726 -214.924894)
					(mid 304.013706 -214.928614)
					(end 304.017426 -214.937594)
				)
			)
		)
	)
	(zone
		(layer "In1.Cu")
		(hatch none 0.5)
		(connect_pads
			(clearance 0)
		)
		(min_thickness 0.25)
		(keepout
			(tracks not_allowed)
			(vias allowed)
			(pads allowed)
			(copperpour not_allowed)
			(footprints allowed)
		)
		(placement
			(enabled no)
			(sheetname "")
		)
		(fill
			(thermal_gap 0.5)
			(thermal_bridge_width 0.5)
			(island_removal_mode 0)
		)
		(polygon
			(pts
				(arc
					(start 385.690872 -391.822686)
					(mid 385.817872 -391.949686)
					(end 385.944872 -391.822686)
				)
				(arc
					(start 385.944872 -391.746486)
					(mid 385.817872 -391.619486)
					(end 385.690872 -391.746486)
				)
			)
		)
	)
	(zone
		(layer "In1.Cu")
		(hatch none 0.5)
		(connect_pads
			(clearance 0)
		)
		(min_thickness 0.25)
		(keepout
			(tracks not_allowed)
			(vias allowed)
			(pads allowed)
			(copperpour not_allowed)
			(footprints allowed)
		)
		(placement
			(enabled no)
			(sheetname "")
		)
		(fill
			(thermal_gap 0.5)
			(thermal_bridge_width 0.5)
			(island_removal_mode 0)
		)
		(polygon
			(pts
				(arc
					(start 270.397478 -263.03224)
					(mid 270.393758 -263.04122)
					(end 270.384778 -263.04494)
				)
				(arc
					(start 268.911578 -263.04494)
					(mid 268.902598 -263.04122)
					(end 268.898878 -263.03224)
				)
				(arc
					(start 268.898878 -262.537702)
					(mid 268.902598 -262.528722)
					(end 268.911578 -262.525002)
				)
				(arc
					(start 270.384778 -262.525002)
					(mid 270.393758 -262.528722)
					(end 270.397478 -262.537702)
				)
			)
		)
	)
	(zone
		(layer "In1.Cu")
		(hatch none 0.5)
		(connect_pads
			(clearance 0)
		)
		(min_thickness 0.25)
		(keepout
			(tracks not_allowed)
			(vias allowed)
			(pads allowed)
			(copperpour not_allowed)
			(footprints allowed)
		)
		(placement
			(enabled no)
			(sheetname "")
		)
		(fill
			(thermal_gap 0.5)
			(thermal_bridge_width 0.5)
			(island_removal_mode 0)
		)
		(polygon
			(pts
				(arc
					(start 184.365392 -206.93253)
					(mid 184.361672 -206.94151)
					(end 184.352692 -206.94523)
				)
				(arc
					(start 182.879492 -206.94523)
					(mid 182.870512 -206.94151)
					(end 182.866792 -206.93253)
				)
				(arc
					(start 182.866792 -206.437992)
					(mid 182.870512 -206.429012)
					(end 182.879492 -206.425292)
				)
				(arc
					(start 184.352692 -206.425292)
					(mid 184.361672 -206.429012)
					(end 184.365392 -206.437992)
				)
			)
		)
	)
	(zone
		(layer "In1.Cu")
		(hatch none 0.5)
		(connect_pads
			(clearance 0)
		)
		(min_thickness 0.25)
		(keepout
			(tracks not_allowed)
			(vias allowed)
			(pads allowed)
			(copperpour not_allowed)
			(footprints allowed)
		)
		(placement
			(enabled no)
			(sheetname "")
		)
		(fill
			(thermal_gap 0.5)
			(thermal_bridge_width 0.5)
			(island_removal_mode 0)
		)
		(polygon
			(pts
				(arc
					(start 52.261262 -385.31038)
					(mid 51.880262 -385.31038)
					(end 52.261262 -385.31038)
				)
			)
		)
	)
	(zone
		(layer "In1.Cu")
		(hatch none 0.5)
		(connect_pads
			(clearance 0)
		)
		(min_thickness 0.25)
		(keepout
			(tracks not_allowed)
			(vias allowed)
			(pads allowed)
			(copperpour not_allowed)
			(footprints allowed)
		)
		(placement
			(enabled no)
			(sheetname "")
		)
		(fill
			(thermal_gap 0.5)
			(thermal_bridge_width 0.5)
			(island_removal_mode 0)
		)
		(polygon
			(pts
				(arc
					(start 308.261004 -393.69238)
					(mid 307.880004 -393.69238)
					(end 308.261004 -393.69238)
				)
			)
		)
	)
	(zone
		(layer "In1.Cu")
		(hatch none 0.5)
		(connect_pads
			(clearance 0)
		)
		(min_thickness 0.25)
		(keepout
			(tracks not_allowed)
			(vias allowed)
			(pads allowed)
			(copperpour not_allowed)
			(footprints allowed)
		)
		(placement
			(enabled no)
			(sheetname "")
		)
		(fill
			(thermal_gap 0.5)
			(thermal_bridge_width 0.5)
			(island_removal_mode 0)
		)
		(polygon
			(pts
				(arc
					(start 149.488906 -388.774432)
					(mid 149.107906 -388.774432)
					(end 149.488906 -388.774432)
				)
			)
		)
	)
	(zone
		(layer "In1.Cu")
		(hatch none 0.5)
		(connect_pads
			(clearance 0)
		)
		(min_thickness 0.25)
		(keepout
			(tracks not_allowed)
			(vias allowed)
			(pads allowed)
			(copperpour not_allowed)
			(footprints allowed)
		)
		(placement
			(enabled no)
			(sheetname "")
		)
		(fill
			(thermal_gap 0.5)
			(thermal_bridge_width 0.5)
			(island_removal_mode 0)
		)
		(polygon
			(pts
				(arc
					(start 195.353432 -308.93258)
					(mid 195.349712 -308.94156)
					(end 195.340732 -308.94528)
				)
				(arc
					(start 193.867532 -308.94528)
					(mid 193.858552 -308.94156)
					(end 193.854832 -308.93258)
				)
				(arc
					(start 193.854832 -308.438042)
					(mid 193.858552 -308.429062)
					(end 193.867532 -308.425342)
				)
				(arc
					(start 195.340732 -308.425342)
					(mid 195.349712 -308.429062)
					(end 195.353432 -308.438042)
				)
			)
		)
	)
	(zone
		(layer "In1.Cu")
		(hatch none 0.5)
		(connect_pads
			(clearance 0)
		)
		(min_thickness 0.25)
		(keepout
			(tracks not_allowed)
			(vias allowed)
			(pads allowed)
			(copperpour not_allowed)
			(footprints allowed)
		)
		(placement
			(enabled no)
			(sheetname "")
		)
		(fill
			(thermal_gap 0.5)
			(thermal_bridge_width 0.5)
			(island_removal_mode 0)
		)
		(polygon
			(pts
				(arc
					(start 206.9973 -201.832464)
					(mid 206.99358 -201.841444)
					(end 206.9846 -201.845164)
				)
				(arc
					(start 205.5114 -201.845164)
					(mid 205.50242 -201.841444)
					(end 205.4987 -201.832464)
				)
				(arc
					(start 205.4987 -201.337926)
					(mid 205.50242 -201.328946)
					(end 205.5114 -201.325226)
				)
				(arc
					(start 206.9846 -201.325226)
					(mid 206.99358 -201.328946)
					(end 206.9973 -201.337926)
				)
			)
		)
	)
	(zone
		(layer "In1.Cu")
		(hatch none 0.5)
		(connect_pads
			(clearance 0)
		)
		(min_thickness 0.25)
		(keepout
			(tracks not_allowed)
			(vias allowed)
			(pads allowed)
			(copperpour not_allowed)
			(footprints allowed)
		)
		(placement
			(enabled no)
			(sheetname "")
		)
		(fill
			(thermal_gap 0.5)
			(thermal_bridge_width 0.5)
			(island_removal_mode 0)
		)
		(polygon
			(pts
				(arc
					(start 293.029386 -240.932208)
					(mid 293.025666 -240.941188)
					(end 293.016686 -240.944908)
				)
				(arc
					(start 291.543486 -240.944908)
					(mid 291.534506 -240.941188)
					(end 291.530786 -240.932208)
				)
				(arc
					(start 291.530786 -240.43767)
					(mid 291.534506 -240.42869)
					(end 291.543486 -240.42497)
				)
				(arc
					(start 293.016686 -240.42497)
					(mid 293.025666 -240.42869)
					(end 293.029386 -240.43767)
				)
			)
		)
	)
	(zone
		(layer "In1.Cu")
		(hatch none 0.5)
		(connect_pads
			(clearance 0)
		)
		(min_thickness 0.25)
		(keepout
			(tracks not_allowed)
			(vias allowed)
			(pads allowed)
			(copperpour not_allowed)
			(footprints allowed)
		)
		(placement
			(enabled no)
			(sheetname "")
		)
		(fill
			(thermal_gap 0.5)
			(thermal_bridge_width 0.5)
			(island_removal_mode 0)
		)
		(polygon
			(pts
				(arc
					(start 199.4535 -206.93253)
					(mid 199.44978 -206.94151)
					(end 199.4408 -206.94523)
				)
				(arc
					(start 197.9676 -206.94523)
					(mid 197.95862 -206.94151)
					(end 197.9549 -206.93253)
				)
				(arc
					(start 197.9549 -206.437992)
					(mid 197.95862 -206.429012)
					(end 197.9676 -206.425292)
				)
				(arc
					(start 199.4408 -206.425292)
					(mid 199.44978 -206.429012)
					(end 199.4535 -206.437992)
				)
			)
		)
	)
	(zone
		(layer "In1.Cu")
		(hatch none 0.5)
		(connect_pads
			(clearance 0)
		)
		(min_thickness 0.25)
		(keepout
			(tracks not_allowed)
			(vias allowed)
			(pads allowed)
			(copperpour not_allowed)
			(footprints allowed)
		)
		(placement
			(enabled no)
			(sheetname "")
		)
		(fill
			(thermal_gap 0.5)
			(thermal_bridge_width 0.5)
			(island_removal_mode 0)
		)
		(polygon
			(pts
				(arc
					(start 428.205392 -201.83221)
					(mid 428.201672 -201.84119)
					(end 428.192692 -201.84491)
				)
				(arc
					(start 426.719492 -201.84491)
					(mid 426.710512 -201.84119)
					(end 426.706792 -201.83221)
				)
				(arc
					(start 426.706792 -201.337672)
					(mid 426.710512 -201.328692)
					(end 426.719492 -201.324972)
				)
				(arc
					(start 428.192692 -201.324972)
					(mid 428.201672 -201.328692)
					(end 428.205392 -201.337672)
				)
			)
		)
	)
	(zone
		(layer "In1.Cu")
		(hatch none 0.5)
		(connect_pads
			(clearance 0)
		)
		(min_thickness 0.25)
		(keepout
			(tracks not_allowed)
			(vias allowed)
			(pads allowed)
			(copperpour not_allowed)
			(footprints allowed)
		)
		(placement
			(enabled no)
			(sheetname "")
		)
		(fill
			(thermal_gap 0.5)
			(thermal_bridge_width 0.5)
			(island_removal_mode 0)
		)
		(polygon
			(pts
				(arc
					(start 18.357342 -316.582552)
					(mid 18.353622 -316.591532)
					(end 18.344642 -316.595252)
				)
				(arc
					(start 16.871442 -316.595252)
					(mid 16.862462 -316.591532)
					(end 16.858742 -316.582552)
				)
				(arc
					(start 16.858742 -316.088014)
					(mid 16.862462 -316.079034)
					(end 16.871442 -316.075314)
				)
				(arc
					(start 18.344642 -316.075314)
					(mid 18.353622 -316.079034)
					(end 18.357342 -316.088014)
				)
			)
		)
	)
	(zone
		(layer "In1.Cu")
		(hatch none 0.5)
		(connect_pads
			(clearance 0)
		)
		(min_thickness 0.25)
		(keepout
			(tracks not_allowed)
			(vias allowed)
			(pads allowed)
			(copperpour not_allowed)
			(footprints allowed)
		)
		(placement
			(enabled no)
			(sheetname "")
		)
		(fill
			(thermal_gap 0.5)
			(thermal_bridge_width 0.5)
			(island_removal_mode 0)
		)
		(polygon
			(pts
				(arc
					(start 33.445196 -241.782346)
					(mid 33.441476 -241.791326)
					(end 33.432496 -241.795046)
				)
				(arc
					(start 31.959296 -241.795046)
					(mid 31.950316 -241.791326)
					(end 31.946596 -241.782346)
				)
				(arc
					(start 31.946596 -241.287808)
					(mid 31.950316 -241.278828)
					(end 31.959296 -241.275108)
				)
				(arc
					(start 33.432496 -241.275108)
					(mid 33.441476 -241.278828)
					(end 33.445196 -241.287808)
				)
			)
		)
	)
	(zone
		(layer "In1.Cu")
		(hatch none 0.5)
		(connect_pads
			(clearance 0)
		)
		(min_thickness 0.25)
		(keepout
			(tracks not_allowed)
			(vias allowed)
			(pads allowed)
			(copperpour not_allowed)
			(footprints allowed)
		)
		(placement
			(enabled no)
			(sheetname "")
		)
		(fill
			(thermal_gap 0.5)
			(thermal_bridge_width 0.5)
			(island_removal_mode 0)
		)
		(polygon
			(pts
				(arc
					(start 52.633372 -287.682432)
					(mid 52.629652 -287.691412)
					(end 52.620672 -287.695132)
				)
				(arc
					(start 51.147472 -287.695132)
					(mid 51.138492 -287.691412)
					(end 51.134772 -287.682432)
				)
				(arc
					(start 51.134772 -287.187894)
					(mid 51.138492 -287.178914)
					(end 51.147472 -287.175194)
				)
				(arc
					(start 52.620672 -287.175194)
					(mid 52.629652 -287.178914)
					(end 52.633372 -287.187894)
				)
			)
		)
	)
	(zone
		(layer "In1.Cu")
		(hatch none 0.5)
		(connect_pads
			(clearance 0)
		)
		(min_thickness 0.25)
		(keepout
			(tracks not_allowed)
			(vias allowed)
			(pads allowed)
			(copperpour not_allowed)
			(footprints allowed)
		)
		(placement
			(enabled no)
			(sheetname "")
		)
		(fill
			(thermal_gap 0.5)
			(thermal_bridge_width 0.5)
			(island_removal_mode 0)
		)
		(polygon
			(pts
				(arc
					(start 184.365392 -272.382488)
					(mid 184.361672 -272.391468)
					(end 184.352692 -272.395188)
				)
				(arc
					(start 182.879492 -272.395188)
					(mid 182.870512 -272.391468)
					(end 182.866792 -272.382488)
				)
				(arc
					(start 182.866792 -271.88795)
					(mid 182.870512 -271.87897)
					(end 182.879492 -271.87525)
				)
				(arc
					(start 184.352692 -271.87525)
					(mid 184.361672 -271.87897)
					(end 184.365392 -271.88795)
				)
			)
		)
	)
	(zone
		(layer "In1.Cu")
		(hatch none 0.5)
		(connect_pads
			(clearance 0)
		)
		(min_thickness 0.25)
		(keepout
			(tracks not_allowed)
			(vias allowed)
			(pads allowed)
			(copperpour not_allowed)
			(footprints allowed)
		)
		(placement
			(enabled no)
			(sheetname "")
		)
		(fill
			(thermal_gap 0.5)
			(thermal_bridge_width 0.5)
			(island_removal_mode 0)
		)
		(polygon
			(pts
				(arc
					(start 420.661338 -284.282134)
					(mid 420.657618 -284.291114)
					(end 420.648638 -284.294834)
				)
				(arc
					(start 419.175438 -284.294834)
					(mid 419.166458 -284.291114)
					(end 419.162738 -284.282134)
				)
				(arc
					(start 419.162738 -283.787596)
					(mid 419.166458 -283.778616)
					(end 419.175438 -283.774896)
				)
				(arc
					(start 420.648638 -283.774896)
					(mid 420.657618 -283.778616)
					(end 420.661338 -283.787596)
				)
			)
		)
	)
	(zone
		(layer "In1.Cu")
		(hatch none 0.5)
		(connect_pads
			(clearance 0)
		)
		(min_thickness 0.25)
		(keepout
			(tracks not_allowed)
			(vias allowed)
			(pads allowed)
			(copperpour not_allowed)
			(footprints allowed)
		)
		(placement
			(enabled no)
			(sheetname "")
		)
		(fill
			(thermal_gap 0.5)
			(thermal_bridge_width 0.5)
			(island_removal_mode 0)
		)
		(polygon
			(pts
				(arc
					(start 187.809378 -237.532418)
					(mid 187.805658 -237.541398)
					(end 187.796678 -237.545118)
				)
				(arc
					(start 186.323478 -237.545118)
					(mid 186.314498 -237.541398)
					(end 186.310778 -237.532418)
				)
				(arc
					(start 186.310778 -237.03788)
					(mid 186.314498 -237.0289)
					(end 186.323478 -237.02518)
				)
				(arc
					(start 187.796678 -237.02518)
					(mid 187.805658 -237.0289)
					(end 187.809378 -237.03788)
				)
			)
		)
	)
	(zone
		(layer "In1.Cu")
		(hatch none 0.5)
		(connect_pads
			(clearance 0)
		)
		(min_thickness 0.25)
		(keepout
			(tracks not_allowed)
			(vias allowed)
			(pads allowed)
			(copperpour not_allowed)
			(footprints allowed)
		)
		(placement
			(enabled no)
			(sheetname "")
		)
		(fill
			(thermal_gap 0.5)
			(thermal_bridge_width 0.5)
			(island_removal_mode 0)
		)
		(polygon
			(pts
				(arc
					(start 417.217352 -278.332184)
					(mid 417.213632 -278.341164)
					(end 417.204652 -278.344884)
				)
				(arc
					(start 415.731452 -278.344884)
					(mid 415.722472 -278.341164)
					(end 415.718752 -278.332184)
				)
				(arc
					(start 415.718752 -277.837646)
					(mid 415.722472 -277.828666)
					(end 415.731452 -277.824946)
				)
				(arc
					(start 417.204652 -277.824946)
					(mid 417.213632 -277.828666)
					(end 417.217352 -277.837646)
				)
			)
		)
	)
	(zone
		(layer "In1.Cu")
		(hatch none 0.5)
		(connect_pads
			(clearance 0)
		)
		(min_thickness 0.25)
		(keepout
			(tracks not_allowed)
			(vias allowed)
			(pads allowed)
			(copperpour not_allowed)
			(footprints allowed)
		)
		(placement
			(enabled no)
			(sheetname "")
		)
		(fill
			(thermal_gap 0.5)
			(thermal_bridge_width 0.5)
			(island_removal_mode 0)
		)
		(polygon
			(pts
				(arc
					(start 293.029386 -311.482232)
					(mid 293.025666 -311.491212)
					(end 293.016686 -311.494932)
				)
				(arc
					(start 291.543486 -311.494932)
					(mid 291.534506 -311.491212)
					(end 291.530786 -311.482232)
				)
				(arc
					(start 291.530786 -310.987694)
					(mid 291.534506 -310.978714)
					(end 291.543486 -310.974994)
				)
				(arc
					(start 293.016686 -310.974994)
					(mid 293.025666 -310.978714)
					(end 293.029386 -310.987694)
				)
			)
		)
	)
	(zone
		(layer "In1.Cu")
		(hatch none 0.5)
		(connect_pads
			(clearance 0)
		)
		(min_thickness 0.25)
		(keepout
			(tracks not_allowed)
			(vias allowed)
			(pads allowed)
			(copperpour not_allowed)
			(footprints allowed)
		)
		(placement
			(enabled no)
			(sheetname "")
		)
		(fill
			(thermal_gap 0.5)
			(thermal_bridge_width 0.5)
			(island_removal_mode 0)
		)
		(polygon
			(pts
				(arc
					(start 454.937368 -294.482266)
					(mid 454.933648 -294.491246)
					(end 454.924668 -294.494966)
				)
				(arc
					(start 453.451468 -294.494966)
					(mid 453.442488 -294.491246)
					(end 453.438768 -294.482266)
				)
				(arc
					(start 453.438768 -293.987728)
					(mid 453.442488 -293.978748)
					(end 453.451468 -293.975028)
				)
				(arc
					(start 454.924668 -293.975028)
					(mid 454.933648 -293.978748)
					(end 454.937368 -293.987728)
				)
			)
		)
	)
	(zone
		(layer "In1.Cu")
		(hatch none 0.5)
		(connect_pads
			(clearance 0)
		)
		(min_thickness 0.25)
		(keepout
			(tracks not_allowed)
			(vias allowed)
			(pads allowed)
			(copperpour not_allowed)
			(footprints allowed)
		)
		(placement
			(enabled no)
			(sheetname "")
		)
		(fill
			(thermal_gap 0.5)
			(thermal_bridge_width 0.5)
			(island_removal_mode 0)
		)
		(polygon
			(pts
				(arc
					(start 60.177426 -206.93253)
					(mid 60.173706 -206.94151)
					(end 60.164726 -206.94523)
				)
				(arc
					(start 58.691526 -206.94523)
					(mid 58.682546 -206.94151)
					(end 58.678826 -206.93253)
				)
				(arc
					(start 58.678826 -206.437992)
					(mid 58.682546 -206.429012)
					(end 58.691526 -206.425292)
				)
				(arc
					(start 60.164726 -206.425292)
					(mid 60.173706 -206.429012)
					(end 60.177426 -206.437992)
				)
			)
		)
	)
	(zone
		(layer "In1.Cu")
		(hatch none 0.5)
		(connect_pads
			(clearance 0)
		)
		(min_thickness 0.25)
		(keepout
			(tracks not_allowed)
			(vias allowed)
			(pads allowed)
			(copperpour not_allowed)
			(footprints allowed)
		)
		(placement
			(enabled no)
			(sheetname "")
		)
		(fill
			(thermal_gap 0.5)
			(thermal_bridge_width 0.5)
			(island_removal_mode 0)
		)
		(polygon
			(pts
				(arc
					(start 435.749446 -201.83221)
					(mid 435.745726 -201.84119)
					(end 435.736746 -201.84491)
				)
				(arc
					(start 434.263546 -201.84491)
					(mid 434.254566 -201.84119)
					(end 434.250846 -201.83221)
				)
				(arc
					(start 434.250846 -201.337672)
					(mid 434.254566 -201.328692)
					(end 434.263546 -201.324972)
				)
				(arc
					(start 435.736746 -201.324972)
					(mid 435.745726 -201.328692)
					(end 435.749446 -201.337672)
				)
			)
		)
	)
	(zone
		(layer "In1.Cu")
		(hatch none 0.5)
		(connect_pads
			(clearance 0)
		)
		(min_thickness 0.25)
		(keepout
			(tracks not_allowed)
			(vias allowed)
			(pads allowed)
			(copperpour not_allowed)
			(footprints allowed)
		)
		(placement
			(enabled no)
			(sheetname "")
		)
		(fill
			(thermal_gap 0.5)
			(thermal_bridge_width 0.5)
			(island_removal_mode 0)
		)
		(polygon
			(pts
				(arc
					(start 335.988914 -393.69238)
					(mid 335.607914 -393.69238)
					(end 335.988914 -393.69238)
				)
			)
		)
	)
	(zone
		(layer "In1.Cu")
		(hatch none 0.5)
		(connect_pads
			(clearance 0)
		)
		(min_thickness 0.25)
		(keepout
			(tracks not_allowed)
			(vias allowed)
			(pads allowed)
			(copperpour not_allowed)
			(footprints allowed)
		)
		(placement
			(enabled no)
			(sheetname "")
		)
		(fill
			(thermal_gap 0.5)
			(thermal_bridge_width 0.5)
			(island_removal_mode 0)
		)
		(polygon
			(pts
				(arc
					(start 417.217352 -269.832328)
					(mid 417.213632 -269.841308)
					(end 417.204652 -269.845028)
				)
				(arc
					(start 415.731452 -269.845028)
					(mid 415.722472 -269.841308)
					(end 415.718752 -269.832328)
				)
				(arc
					(start 415.718752 -269.33779)
					(mid 415.722472 -269.32881)
					(end 415.731452 -269.32509)
				)
				(arc
					(start 417.204652 -269.32509)
					(mid 417.213632 -269.32881)
					(end 417.217352 -269.33779)
				)
			)
		)
	)
	(zone
		(layer "In1.Cu")
		(hatch none 0.5)
		(connect_pads
			(clearance 0)
		)
		(min_thickness 0.25)
		(keepout
			(tracks not_allowed)
			(vias allowed)
			(pads allowed)
			(copperpour not_allowed)
			(footprints allowed)
		)
		(placement
			(enabled no)
			(sheetname "")
		)
		(fill
			(thermal_gap 0.5)
			(thermal_bridge_width 0.5)
			(island_removal_mode 0)
		)
		(polygon
			(pts
				(arc
					(start 56.077358 -280.882344)
					(mid 56.073638 -280.891324)
					(end 56.064658 -280.895044)
				)
				(arc
					(start 54.591458 -280.895044)
					(mid 54.582478 -280.891324)
					(end 54.578758 -280.882344)
				)
				(arc
					(start 54.578758 -280.387806)
					(mid 54.582478 -280.378826)
					(end 54.591458 -280.375106)
				)
				(arc
					(start 56.064658 -280.375106)
					(mid 56.073638 -280.378826)
					(end 56.077358 -280.387806)
				)
			)
		)
	)
	(zone
		(layer "In1.Cu")
		(hatch none 0.5)
		(connect_pads
			(clearance 0)
		)
		(min_thickness 0.25)
		(keepout
			(tracks not_allowed)
			(vias allowed)
			(pads allowed)
			(copperpour not_allowed)
			(footprints allowed)
		)
		(placement
			(enabled no)
			(sheetname "")
		)
		(fill
			(thermal_gap 0.5)
			(thermal_bridge_width 0.5)
			(island_removal_mode 0)
		)
		(polygon
			(pts
				(arc
					(start 266.29741 -282.582112)
					(mid 266.29369 -282.591092)
					(end 266.28471 -282.594812)
				)
				(arc
					(start 264.81151 -282.594812)
					(mid 264.80253 -282.591092)
					(end 264.79881 -282.582112)
				)
				(arc
					(start 264.79881 -282.087574)
					(mid 264.80253 -282.078594)
					(end 264.81151 -282.074874)
				)
				(arc
					(start 266.28471 -282.074874)
					(mid 266.29369 -282.078594)
					(end 266.29741 -282.087574)
				)
			)
		)
	)
	(zone
		(layer "In1.Cu")
		(hatch none 0.5)
		(connect_pads
			(clearance 0)
		)
		(min_thickness 0.25)
		(keepout
			(tracks not_allowed)
			(vias allowed)
			(pads allowed)
			(copperpour not_allowed)
			(footprints allowed)
		)
		(placement
			(enabled no)
			(sheetname "")
		)
		(fill
			(thermal_gap 0.5)
			(thermal_bridge_width 0.5)
			(island_removal_mode 0)
		)
		(polygon
			(pts
				(arc
					(start 60.661296 -385.31038)
					(mid 60.280296 -385.31038)
					(end 60.661296 -385.31038)
				)
			)
		)
	)
	(zone
		(layer "In1.Cu")
		(hatch none 0.5)
		(connect_pads
			(clearance 0)
		)
		(min_thickness 0.25)
		(keepout
			(tracks not_allowed)
			(vias allowed)
			(pads allowed)
			(copperpour not_allowed)
			(footprints allowed)
		)
		(placement
			(enabled no)
			(sheetname "")
		)
		(fill
			(thermal_gap 0.5)
			(thermal_bridge_width 0.5)
			(island_removal_mode 0)
		)
		(polygon
			(pts
				(arc
					(start 281.385264 -212.032088)
					(mid 281.381544 -212.041068)
					(end 281.372564 -212.044788)
				)
				(arc
					(start 279.899364 -212.044788)
					(mid 279.890384 -212.041068)
					(end 279.886664 -212.032088)
				)
				(arc
					(start 279.886664 -211.53755)
					(mid 279.890384 -211.52857)
					(end 279.899364 -211.52485)
				)
				(arc
					(start 281.372564 -211.52485)
					(mid 281.381544 -211.52857)
					(end 281.385264 -211.53755)
				)
			)
		)
	)
	(zone
		(layer "In1.Cu")
		(hatch none 0.5)
		(connect_pads
			(clearance 0)
		)
		(min_thickness 0.25)
		(keepout
			(tracks not_allowed)
			(vias allowed)
			(pads allowed)
			(copperpour not_allowed)
			(footprints allowed)
		)
		(placement
			(enabled no)
			(sheetname "")
		)
		(fill
			(thermal_gap 0.5)
			(thermal_bridge_width 0.5)
			(island_removal_mode 0)
		)
		(polygon
			(pts
				(arc
					(start 443.2935 -314.032138)
					(mid 443.28978 -314.041118)
					(end 443.2808 -314.044838)
				)
				(arc
					(start 441.8076 -314.044838)
					(mid 441.79862 -314.041118)
					(end 441.7949 -314.032138)
				)
				(arc
					(start 441.7949 -313.5376)
					(mid 441.79862 -313.52862)
					(end 441.8076 -313.5249)
				)
				(arc
					(start 443.2808 -313.5249)
					(mid 443.28978 -313.52862)
					(end 443.2935 -313.5376)
				)
			)
		)
	)
	(zone
		(layer "In1.Cu")
		(hatch none 0.5)
		(connect_pads
			(clearance 0)
		)
		(min_thickness 0.25)
		(keepout
			(tracks not_allowed)
			(vias allowed)
			(pads allowed)
			(copperpour not_allowed)
			(footprints allowed)
		)
		(placement
			(enabled no)
			(sheetname "")
		)
		(fill
			(thermal_gap 0.5)
			(thermal_bridge_width 0.5)
			(island_removal_mode 0)
		)
		(polygon
			(pts
				(arc
					(start 439.849514 -212.882226)
					(mid 439.845794 -212.891206)
					(end 439.836814 -212.894926)
				)
				(arc
					(start 438.363614 -212.894926)
					(mid 438.354634 -212.891206)
					(end 438.350914 -212.882226)
				)
				(arc
					(start 438.350914 -212.387688)
					(mid 438.354634 -212.378708)
					(end 438.363614 -212.374988)
				)
				(arc
					(start 439.836814 -212.374988)
					(mid 439.845794 -212.378708)
					(end 439.849514 -212.387688)
				)
			)
		)
	)
	(zone
		(layer "In1.Cu")
		(hatch none 0.5)
		(connect_pads
			(clearance 0)
		)
		(min_thickness 0.25)
		(keepout
			(tracks not_allowed)
			(vias allowed)
			(pads allowed)
			(copperpour not_allowed)
			(footprints allowed)
		)
		(placement
			(enabled no)
			(sheetname "")
		)
		(fill
			(thermal_gap 0.5)
			(thermal_bridge_width 0.5)
			(island_removal_mode 0)
		)
		(polygon
			(pts
				(arc
					(start 65.861184 -386.003292)
					(mid 65.480184 -386.003292)
					(end 65.861184 -386.003292)
				)
			)
		)
	)
	(zone
		(layer "In1.Cu")
		(hatch none 0.5)
		(connect_pads
			(clearance 0)
		)
		(min_thickness 0.25)
		(keepout
			(tracks not_allowed)
			(vias allowed)
			(pads allowed)
			(copperpour not_allowed)
			(footprints allowed)
		)
		(placement
			(enabled no)
			(sheetname "")
		)
		(fill
			(thermal_gap 0.5)
			(thermal_bridge_width 0.5)
			(island_removal_mode 0)
		)
		(polygon
			(pts
				(arc
					(start 91.989148 -385.31038)
					(mid 91.608148 -385.31038)
					(end 91.989148 -385.31038)
				)
			)
		)
	)
	(zone
		(layer "In1.Cu")
		(hatch none 0.5)
		(connect_pads
			(clearance 0)
		)
		(min_thickness 0.25)
		(keepout
			(tracks not_allowed)
			(vias allowed)
			(pads allowed)
			(copperpour not_allowed)
			(footprints allowed)
		)
		(placement
			(enabled no)
			(sheetname "")
		)
		(fill
			(thermal_gap 0.5)
			(thermal_bridge_width 0.5)
			(island_removal_mode 0)
		)
		(polygon
			(pts
				(arc
					(start 273.841464 -284.282134)
					(mid 273.837744 -284.291114)
					(end 273.828764 -284.294834)
				)
				(arc
					(start 272.355564 -284.294834)
					(mid 272.346584 -284.291114)
					(end 272.342864 -284.282134)
				)
				(arc
					(start 272.342864 -283.787596)
					(mid 272.346584 -283.778616)
					(end 272.355564 -283.774896)
				)
				(arc
					(start 273.828764 -283.774896)
					(mid 273.837744 -283.778616)
					(end 273.841464 -283.787596)
				)
			)
		)
	)
	(zone
		(layer "In1.Cu")
		(hatch none 0.5)
		(connect_pads
			(clearance 0)
		)
		(min_thickness 0.25)
		(keepout
			(tracks not_allowed)
			(vias allowed)
			(pads allowed)
			(copperpour not_allowed)
			(footprints allowed)
		)
		(placement
			(enabled no)
			(sheetname "")
		)
		(fill
			(thermal_gap 0.5)
			(thermal_bridge_width 0.5)
			(island_removal_mode 0)
		)
		(polygon
			(pts
				(arc
					(start 439.849514 -270.682212)
					(mid 439.845794 -270.691192)
					(end 439.836814 -270.694912)
				)
				(arc
					(start 438.363614 -270.694912)
					(mid 438.354634 -270.691192)
					(end 438.350914 -270.682212)
				)
				(arc
					(start 438.350914 -270.187674)
					(mid 438.354634 -270.178694)
					(end 438.363614 -270.174974)
				)
				(arc
					(start 439.836814 -270.174974)
					(mid 439.845794 -270.178694)
					(end 439.849514 -270.187674)
				)
			)
		)
	)
	(zone
		(layer "In1.Cu")
		(hatch none 0.5)
		(connect_pads
			(clearance 0)
		)
		(min_thickness 0.25)
		(keepout
			(tracks not_allowed)
			(vias allowed)
			(pads allowed)
			(copperpour not_allowed)
			(footprints allowed)
		)
		(placement
			(enabled no)
			(sheetname "")
		)
		(fill
			(thermal_gap 0.5)
			(thermal_bridge_width 0.5)
			(island_removal_mode 0)
		)
		(polygon
			(pts
				(arc
					(start 288.929318 -302.982122)
					(mid 288.925598 -302.991102)
					(end 288.916618 -302.994822)
				)
				(arc
					(start 287.443418 -302.994822)
					(mid 287.434438 -302.991102)
					(end 287.430718 -302.982122)
				)
				(arc
					(start 287.430718 -302.487584)
					(mid 287.434438 -302.478604)
					(end 287.443418 -302.474884)
				)
				(arc
					(start 288.916618 -302.474884)
					(mid 288.925598 -302.478604)
					(end 288.929318 -302.487584)
				)
			)
		)
	)
	(zone
		(layer "In1.Cu")
		(hatch none 0.5)
		(connect_pads
			(clearance 0)
		)
		(min_thickness 0.25)
		(keepout
			(tracks not_allowed)
			(vias allowed)
			(pads allowed)
			(copperpour not_allowed)
			(footprints allowed)
		)
		(placement
			(enabled no)
			(sheetname "")
		)
		(fill
			(thermal_gap 0.5)
			(thermal_bridge_width 0.5)
			(island_removal_mode 0)
		)
		(polygon
			(pts
				(arc
					(start 304.017426 -206.082138)
					(mid 304.013706 -206.091118)
					(end 304.004726 -206.094838)
				)
				(arc
					(start 302.531526 -206.094838)
					(mid 302.522546 -206.091118)
					(end 302.518826 -206.082138)
				)
				(arc
					(start 302.518826 -205.5876)
					(mid 302.522546 -205.57862)
					(end 302.531526 -205.5749)
				)
				(arc
					(start 304.004726 -205.5749)
					(mid 304.013706 -205.57862)
					(end 304.017426 -205.5876)
				)
			)
		)
	)
	(zone
		(layer "In1.Cu")
		(hatch none 0.5)
		(connect_pads
			(clearance 0)
		)
		(min_thickness 0.25)
		(keepout
			(tracks not_allowed)
			(vias allowed)
			(pads allowed)
			(copperpour not_allowed)
			(footprints allowed)
		)
		(placement
			(enabled no)
			(sheetname "")
		)
		(fill
			(thermal_gap 0.5)
			(thermal_bridge_width 0.5)
			(island_removal_mode 0)
		)
		(polygon
			(pts
				(arc
					(start 149.488906 -385.31038)
					(mid 149.107906 -385.31038)
					(end 149.488906 -385.31038)
				)
			)
		)
	)
	(zone
		(layer "In1.Cu")
		(hatch none 0.5)
		(connect_pads
			(clearance 0)
		)
		(min_thickness 0.25)
		(keepout
			(tracks not_allowed)
			(vias allowed)
			(pads allowed)
			(copperpour not_allowed)
			(footprints allowed)
		)
		(placement
			(enabled no)
			(sheetname "")
		)
		(fill
			(thermal_gap 0.5)
			(thermal_bridge_width 0.5)
			(island_removal_mode 0)
		)
		(polygon
			(pts
				(arc
					(start 454.937368 -251.132086)
					(mid 454.933648 -251.141066)
					(end 454.924668 -251.144786)
				)
				(arc
					(start 453.451468 -251.144786)
					(mid 453.442488 -251.141066)
					(end 453.438768 -251.132086)
				)
				(arc
					(start 453.438768 -250.637548)
					(mid 453.442488 -250.628568)
					(end 453.451468 -250.624848)
				)
				(arc
					(start 454.924668 -250.624848)
					(mid 454.933648 -250.628568)
					(end 454.937368 -250.637548)
				)
			)
		)
	)
	(zone
		(layer "In1.Cu")
		(hatch none 0.5)
		(connect_pads
			(clearance 0)
		)
		(min_thickness 0.25)
		(keepout
			(tracks not_allowed)
			(vias allowed)
			(pads allowed)
			(copperpour not_allowed)
			(footprints allowed)
		)
		(placement
			(enabled no)
			(sheetname "")
		)
		(fill
			(thermal_gap 0.5)
			(thermal_bridge_width 0.5)
			(island_removal_mode 0)
		)
		(polygon
			(pts
				(arc
					(start 22.45741 -297.032426)
					(mid 22.45369 -297.041406)
					(end 22.44471 -297.045126)
				)
				(arc
					(start 20.97151 -297.045126)
					(mid 20.96253 -297.041406)
					(end 20.95881 -297.032426)
				)
				(arc
					(start 20.95881 -296.537888)
					(mid 20.96253 -296.528908)
					(end 20.97151 -296.525188)
				)
				(arc
					(start 22.44471 -296.525188)
					(mid 22.45369 -296.528908)
					(end 22.45741 -296.537888)
				)
			)
		)
	)
	(zone
		(layer "In1.Cu")
		(hatch none 0.5)
		(connect_pads
			(clearance 0)
		)
		(min_thickness 0.25)
		(keepout
			(tracks not_allowed)
			(vias allowed)
			(pads allowed)
			(copperpour not_allowed)
			(footprints allowed)
		)
		(placement
			(enabled no)
			(sheetname "")
		)
		(fill
			(thermal_gap 0.5)
			(thermal_bridge_width 0.5)
			(island_removal_mode 0)
		)
		(polygon
			(pts
				(arc
					(start 206.9973 -254.532384)
					(mid 206.99358 -254.541364)
					(end 206.9846 -254.545084)
				)
				(arc
					(start 205.5114 -254.545084)
					(mid 205.50242 -254.541364)
					(end 205.4987 -254.532384)
				)
				(arc
					(start 205.4987 -254.037846)
					(mid 205.50242 -254.028866)
					(end 205.5114 -254.025146)
				)
				(arc
					(start 206.9846 -254.025146)
					(mid 206.99358 -254.028866)
					(end 206.9973 -254.037846)
				)
			)
		)
	)
	(zone
		(layer "In1.Cu")
		(hatch none 0.5)
		(connect_pads
			(clearance 0)
		)
		(min_thickness 0.25)
		(keepout
			(tracks not_allowed)
			(vias allowed)
			(pads allowed)
			(copperpour not_allowed)
			(footprints allowed)
		)
		(placement
			(enabled no)
			(sheetname "")
		)
		(fill
			(thermal_gap 0.5)
			(thermal_bridge_width 0.5)
			(island_removal_mode 0)
		)
		(polygon
			(pts
				(arc
					(start 288.929318 -253.682246)
					(mid 288.925598 -253.691226)
					(end 288.916618 -253.694946)
				)
				(arc
					(start 287.443418 -253.694946)
					(mid 287.434438 -253.691226)
					(end 287.430718 -253.682246)
				)
				(arc
					(start 287.430718 -253.187708)
					(mid 287.434438 -253.178728)
					(end 287.443418 -253.175008)
				)
				(arc
					(start 288.916618 -253.175008)
					(mid 288.925598 -253.178728)
					(end 288.929318 -253.187708)
				)
			)
		)
	)
	(zone
		(layer "In1.Cu")
		(hatch none 0.5)
		(connect_pads
			(clearance 0)
		)
		(min_thickness 0.25)
		(keepout
			(tracks not_allowed)
			(vias allowed)
			(pads allowed)
			(copperpour not_allowed)
			(footprints allowed)
		)
		(placement
			(enabled no)
			(sheetname "")
		)
		(fill
			(thermal_gap 0.5)
			(thermal_bridge_width 0.5)
			(island_removal_mode 0)
		)
		(polygon
			(pts
				(arc
					(start 381.470408 -392.30427)
					(mid 381.165608 -392.30427)
					(end 381.470408 -392.30427)
				)
			)
		)
	)
	(zone
		(layer "In1.Cu")
		(hatch none 0.5)
		(connect_pads
			(clearance 0)
		)
		(min_thickness 0.25)
		(keepout
			(tracks not_allowed)
			(vias allowed)
			(pads allowed)
			(copperpour not_allowed)
			(footprints allowed)
		)
		(placement
			(enabled no)
			(sheetname "")
		)
		(fill
			(thermal_gap 0.5)
			(thermal_bridge_width 0.5)
			(island_removal_mode 0)
		)
		(polygon
			(pts
				(arc
					(start 296.473372 -301.2821)
					(mid 296.469652 -301.29108)
					(end 296.460672 -301.2948)
				)
				(arc
					(start 294.987472 -301.2948)
					(mid 294.978492 -301.29108)
					(end 294.974772 -301.2821)
				)
				(arc
					(start 294.974772 -300.787562)
					(mid 294.978492 -300.778582)
					(end 294.987472 -300.774862)
				)
				(arc
					(start 296.460672 -300.774862)
					(mid 296.469652 -300.778582)
					(end 296.473372 -300.787562)
				)
			)
		)
	)
	(zone
		(layer "In1.Cu")
		(hatch none 0.5)
		(connect_pads
			(clearance 0)
		)
		(min_thickness 0.25)
		(keepout
			(tracks not_allowed)
			(vias allowed)
			(pads allowed)
			(copperpour not_allowed)
			(footprints allowed)
		)
		(placement
			(enabled no)
			(sheetname "")
		)
		(fill
			(thermal_gap 0.5)
			(thermal_bridge_width 0.5)
			(island_removal_mode 0)
		)
		(polygon
			(pts
				(arc
					(start 165.177216 -291.93236)
					(mid 165.173496 -291.94134)
					(end 165.164516 -291.94506)
				)
				(arc
					(start 163.691316 -291.94506)
					(mid 163.682336 -291.94134)
					(end 163.678616 -291.93236)
				)
				(arc
					(start 163.678616 -291.437822)
					(mid 163.682336 -291.428842)
					(end 163.691316 -291.425122)
				)
				(arc
					(start 165.164516 -291.425122)
					(mid 165.173496 -291.428842)
					(end 165.177216 -291.437822)
				)
			)
		)
	)
	(zone
		(layer "In1.Cu")
		(hatch none 0.5)
		(connect_pads
			(clearance 0)
		)
		(min_thickness 0.25)
		(keepout
			(tracks not_allowed)
			(vias allowed)
			(pads allowed)
			(copperpour not_allowed)
			(footprints allowed)
		)
		(placement
			(enabled no)
			(sheetname "")
		)
		(fill
			(thermal_gap 0.5)
			(thermal_bridge_width 0.5)
			(island_removal_mode 0)
		)
		(polygon
			(pts
				(arc
					(start 169.277284 -285.132526)
					(mid 169.273564 -285.141506)
					(end 169.264584 -285.145226)
				)
				(arc
					(start 167.791384 -285.145226)
					(mid 167.782404 -285.141506)
					(end 167.778684 -285.132526)
				)
				(arc
					(start 167.778684 -284.637988)
					(mid 167.782404 -284.629008)
					(end 167.791384 -284.625288)
				)
				(arc
					(start 169.264584 -284.625288)
					(mid 169.273564 -284.629008)
					(end 169.277284 -284.637988)
				)
			)
		)
	)
	(zone
		(layer "In1.Cu")
		(hatch none 0.5)
		(connect_pads
			(clearance 0)
		)
		(min_thickness 0.25)
		(keepout
			(tracks not_allowed)
			(vias allowed)
			(pads allowed)
			(copperpour not_allowed)
			(footprints allowed)
		)
		(placement
			(enabled no)
			(sheetname "")
		)
		(fill
			(thermal_gap 0.5)
			(thermal_bridge_width 0.5)
			(island_removal_mode 0)
		)
		(polygon
			(pts
				(arc
					(start 443.2935 -204.382116)
					(mid 443.28978 -204.391096)
					(end 443.2808 -204.394816)
				)
				(arc
					(start 441.8076 -204.394816)
					(mid 441.79862 -204.391096)
					(end 441.7949 -204.382116)
				)
				(arc
					(start 441.7949 -203.887578)
					(mid 441.79862 -203.878598)
					(end 441.8076 -203.874878)
				)
				(arc
					(start 443.2808 -203.874878)
					(mid 443.28978 -203.878598)
					(end 443.2935 -203.887578)
				)
			)
		)
	)
	(zone
		(layer "In1.Cu")
		(hatch none 0.5)
		(connect_pads
			(clearance 0)
		)
		(min_thickness 0.25)
		(keepout
			(tracks not_allowed)
			(vias allowed)
			(pads allowed)
			(copperpour not_allowed)
			(footprints allowed)
		)
		(placement
			(enabled no)
			(sheetname "")
		)
		(fill
			(thermal_gap 0.5)
			(thermal_bridge_width 0.5)
			(island_removal_mode 0)
		)
		(polygon
			(pts
				(arc
					(start 60.177426 -242.632484)
					(mid 60.173706 -242.641464)
					(end 60.164726 -242.645184)
				)
				(arc
					(start 58.691526 -242.645184)
					(mid 58.682546 -242.641464)
					(end 58.678826 -242.632484)
				)
				(arc
					(start 58.678826 -242.137946)
					(mid 58.682546 -242.128966)
					(end 58.691526 -242.125246)
				)
				(arc
					(start 60.164726 -242.125246)
					(mid 60.173706 -242.128966)
					(end 60.177426 -242.137946)
				)
			)
		)
	)
	(zone
		(layer "In1.Cu")
		(hatch none 0.5)
		(connect_pads
			(clearance 0)
		)
		(min_thickness 0.25)
		(keepout
			(tracks not_allowed)
			(vias allowed)
			(pads allowed)
			(copperpour not_allowed)
			(footprints allowed)
		)
		(placement
			(enabled no)
			(sheetname "")
		)
		(fill
			(thermal_gap 0.5)
			(thermal_bridge_width 0.5)
			(island_removal_mode 0)
		)
		(polygon
			(pts
				(arc
					(start 308.117494 -211.182204)
					(mid 308.113774 -211.191184)
					(end 308.104794 -211.194904)
				)
				(arc
					(start 306.631594 -211.194904)
					(mid 306.622614 -211.191184)
					(end 306.618894 -211.182204)
				)
				(arc
					(start 306.618894 -210.687666)
					(mid 306.622614 -210.678686)
					(end 306.631594 -210.674966)
				)
				(arc
					(start 308.104794 -210.674966)
					(mid 308.113774 -210.678686)
					(end 308.117494 -210.687666)
				)
			)
		)
	)
	(zone
		(layer "In1.Cu")
		(hatch none 0.5)
		(connect_pads
			(clearance 0)
		)
		(min_thickness 0.25)
		(keepout
			(tracks not_allowed)
			(vias allowed)
			(pads allowed)
			(copperpour not_allowed)
			(footprints allowed)
		)
		(placement
			(enabled no)
			(sheetname "")
		)
		(fill
			(thermal_gap 0.5)
			(thermal_bridge_width 0.5)
			(island_removal_mode 0)
		)
		(polygon
			(pts
				(arc
					(start 447.393568 -247.732296)
					(mid 447.389848 -247.741276)
					(end 447.380868 -247.744996)
				)
				(arc
					(start 445.907668 -247.744996)
					(mid 445.898688 -247.741276)
					(end 445.894968 -247.732296)
				)
				(arc
					(start 445.894968 -247.237758)
					(mid 445.898688 -247.228778)
					(end 445.907668 -247.225058)
				)
				(arc
					(start 447.380868 -247.225058)
					(mid 447.389848 -247.228778)
					(end 447.393568 -247.237758)
				)
			)
		)
	)
	(zone
		(layer "In1.Cu")
		(hatch none 0.5)
		(connect_pads
			(clearance 0)
		)
		(min_thickness 0.25)
		(keepout
			(tracks not_allowed)
			(vias allowed)
			(pads allowed)
			(copperpour not_allowed)
			(footprints allowed)
		)
		(placement
			(enabled no)
			(sheetname "")
		)
		(fill
			(thermal_gap 0.5)
			(thermal_bridge_width 0.5)
			(island_removal_mode 0)
		)
		(polygon
			(pts
				(arc
					(start 180.265324 -296.182542)
					(mid 180.261604 -296.191522)
					(end 180.252624 -296.195242)
				)
				(arc
					(start 178.779424 -296.195242)
					(mid 178.770444 -296.191522)
					(end 178.766724 -296.182542)
				)
				(arc
					(start 178.766724 -295.688004)
					(mid 178.770444 -295.679024)
					(end 178.779424 -295.675304)
				)
				(arc
					(start 180.252624 -295.675304)
					(mid 180.261604 -295.679024)
					(end 180.265324 -295.688004)
				)
			)
		)
	)
	(zone
		(layer "In1.Cu")
		(hatch none 0.5)
		(connect_pads
			(clearance 0)
		)
		(min_thickness 0.25)
		(keepout
			(tracks not_allowed)
			(vias allowed)
			(pads allowed)
			(copperpour not_allowed)
			(footprints allowed)
		)
		(placement
			(enabled no)
			(sheetname "")
		)
		(fill
			(thermal_gap 0.5)
			(thermal_bridge_width 0.5)
			(island_removal_mode 0)
		)
		(polygon
			(pts
				(arc
					(start 265.87831 -261.93496)
					(mid 265.21791 -261.93496)
					(end 265.87831 -261.93496)
				)
			)
		)
	)
	(zone
		(layer "In1.Cu")
		(hatch none 0.5)
		(connect_pads
			(clearance 0)
		)
		(min_thickness 0.25)
		(keepout
			(tracks not_allowed)
			(vias allowed)
			(pads allowed)
			(copperpour not_allowed)
			(footprints allowed)
		)
		(placement
			(enabled no)
			(sheetname "")
		)
		(fill
			(thermal_gap 0.5)
			(thermal_bridge_width 0.5)
			(island_removal_mode 0)
		)
		(polygon
			(pts
				(arc
					(start 266.29741 -286.832294)
					(mid 266.29369 -286.841274)
					(end 266.28471 -286.844994)
				)
				(arc
					(start 264.81151 -286.844994)
					(mid 264.80253 -286.841274)
					(end 264.79881 -286.832294)
				)
				(arc
					(start 264.79881 -286.337756)
					(mid 264.80253 -286.328776)
					(end 264.81151 -286.325056)
				)
				(arc
					(start 266.28471 -286.325056)
					(mid 266.29369 -286.328776)
					(end 266.29741 -286.337756)
				)
			)
		)
	)
	(zone
		(layer "In1.Cu")
		(hatch none 0.5)
		(connect_pads
			(clearance 0)
		)
		(min_thickness 0.25)
		(keepout
			(tracks not_allowed)
			(vias allowed)
			(pads allowed)
			(copperpour not_allowed)
			(footprints allowed)
		)
		(placement
			(enabled no)
			(sheetname "")
		)
		(fill
			(thermal_gap 0.5)
			(thermal_bridge_width 0.5)
			(island_removal_mode 0)
		)
		(polygon
			(pts
				(arc
					(start 176.821338 -264.732516)
					(mid 176.817618 -264.741496)
					(end 176.808638 -264.745216)
				)
				(arc
					(start 175.335438 -264.745216)
					(mid 175.326458 -264.741496)
					(end 175.322738 -264.732516)
				)
				(arc
					(start 175.322738 -264.237978)
					(mid 175.326458 -264.228998)
					(end 175.335438 -264.225278)
				)
				(arc
					(start 176.808638 -264.225278)
					(mid 176.817618 -264.228998)
					(end 176.821338 -264.237978)
				)
			)
		)
	)
	(zone
		(layer "In1.Cu")
		(hatch none 0.5)
		(connect_pads
			(clearance 0)
		)
		(min_thickness 0.25)
		(keepout
			(tracks not_allowed)
			(vias allowed)
			(pads allowed)
			(copperpour not_allowed)
			(footprints allowed)
		)
		(placement
			(enabled no)
			(sheetname "")
		)
		(fill
			(thermal_gap 0.5)
			(thermal_bridge_width 0.5)
			(island_removal_mode 0)
		)
		(polygon
			(pts
				(arc
					(start 273.841464 -277.4823)
					(mid 273.837744 -277.49128)
					(end 273.828764 -277.495)
				)
				(arc
					(start 272.355564 -277.495)
					(mid 272.346584 -277.49128)
					(end 272.342864 -277.4823)
				)
				(arc
					(start 272.342864 -276.987762)
					(mid 272.346584 -276.978782)
					(end 272.355564 -276.975062)
				)
				(arc
					(start 273.828764 -276.975062)
					(mid 273.837744 -276.978782)
					(end 273.841464 -276.987762)
				)
			)
		)
	)
	(zone
		(layer "In1.Cu")
		(hatch none 0.5)
		(connect_pads
			(clearance 0)
		)
		(min_thickness 0.25)
		(keepout
			(tracks not_allowed)
			(vias allowed)
			(pads allowed)
			(copperpour not_allowed)
			(footprints allowed)
		)
		(placement
			(enabled no)
			(sheetname "")
		)
		(fill
			(thermal_gap 0.5)
			(thermal_bridge_width 0.5)
			(island_removal_mode 0)
		)
		(polygon
			(pts
				(arc
					(start 199.4535 -222.232474)
					(mid 199.44978 -222.241454)
					(end 199.4408 -222.245174)
				)
				(arc
					(start 197.9676 -222.245174)
					(mid 197.95862 -222.241454)
					(end 197.9549 -222.232474)
				)
				(arc
					(start 197.9549 -221.737936)
					(mid 197.95862 -221.728956)
					(end 197.9676 -221.725236)
				)
				(arc
					(start 199.4408 -221.725236)
					(mid 199.44978 -221.728956)
					(end 199.4535 -221.737936)
				)
			)
		)
	)
	(zone
		(layer "In1.Cu")
		(hatch none 0.5)
		(connect_pads
			(clearance 0)
		)
		(min_thickness 0.25)
		(keepout
			(tracks not_allowed)
			(vias allowed)
			(pads allowed)
			(copperpour not_allowed)
			(footprints allowed)
		)
		(placement
			(enabled no)
			(sheetname "")
		)
		(fill
			(thermal_gap 0.5)
			(thermal_bridge_width 0.5)
			(island_removal_mode 0)
		)
		(polygon
			(pts
				(arc
					(start 52.633372 -236.682534)
					(mid 52.629652 -236.691514)
					(end 52.620672 -236.695234)
				)
				(arc
					(start 51.147472 -236.695234)
					(mid 51.138492 -236.691514)
					(end 51.134772 -236.682534)
				)
				(arc
					(start 51.134772 -236.187996)
					(mid 51.138492 -236.179016)
					(end 51.147472 -236.175296)
				)
				(arc
					(start 52.620672 -236.175296)
					(mid 52.629652 -236.179016)
					(end 52.633372 -236.187996)
				)
			)
		)
	)
	(zone
		(layer "In1.Cu")
		(hatch none 0.5)
		(connect_pads
			(clearance 0)
		)
		(min_thickness 0.25)
		(keepout
			(tracks not_allowed)
			(vias allowed)
			(pads allowed)
			(copperpour not_allowed)
			(footprints allowed)
		)
		(placement
			(enabled no)
			(sheetname "")
		)
		(fill
			(thermal_gap 0.5)
			(thermal_bridge_width 0.5)
			(island_removal_mode 0)
		)
		(polygon
			(pts
				(arc
					(start 124.561092 -389.467344)
					(mid 124.180092 -389.467344)
					(end 124.561092 -389.467344)
				)
			)
		)
	)
	(zone
		(layer "In1.Cu")
		(hatch none 0.5)
		(connect_pads
			(clearance 0)
		)
		(min_thickness 0.25)
		(keepout
			(tracks not_allowed)
			(vias allowed)
			(pads allowed)
			(copperpour not_allowed)
			(footprints allowed)
		)
		(placement
			(enabled no)
			(sheetname "")
		)
		(fill
			(thermal_gap 0.5)
			(thermal_bridge_width 0.5)
			(island_removal_mode 0)
		)
		(polygon
			(pts
				(arc
					(start 293.029386 -231.582214)
					(mid 293.025666 -231.591194)
					(end 293.016686 -231.594914)
				)
				(arc
					(start 291.543486 -231.594914)
					(mid 291.534506 -231.591194)
					(end 291.530786 -231.582214)
				)
				(arc
					(start 291.530786 -231.087676)
					(mid 291.534506 -231.078696)
					(end 291.543486 -231.074976)
				)
				(arc
					(start 293.016686 -231.074976)
					(mid 293.025666 -231.078696)
					(end 293.029386 -231.087676)
				)
			)
		)
	)
	(zone
		(layer "In1.Cu")
		(hatch none 0.5)
		(connect_pads
			(clearance 0)
		)
		(min_thickness 0.25)
		(keepout
			(tracks not_allowed)
			(vias allowed)
			(pads allowed)
			(copperpour not_allowed)
			(footprints allowed)
		)
		(placement
			(enabled no)
			(sheetname "")
		)
		(fill
			(thermal_gap 0.5)
			(thermal_bridge_width 0.5)
			(island_removal_mode 0)
		)
		(polygon
			(pts
				(arc
					(start 33.445196 -312.33237)
					(mid 33.441476 -312.34135)
					(end 33.432496 -312.34507)
				)
				(arc
					(start 31.959296 -312.34507)
					(mid 31.950316 -312.34135)
					(end 31.946596 -312.33237)
				)
				(arc
					(start 31.946596 -311.837832)
					(mid 31.950316 -311.828852)
					(end 31.959296 -311.825132)
				)
				(arc
					(start 33.432496 -311.825132)
					(mid 33.441476 -311.828852)
					(end 33.445196 -311.837832)
				)
			)
		)
	)
	(zone
		(layer "In1.Cu")
		(hatch none 0.5)
		(connect_pads
			(clearance 0)
		)
		(min_thickness 0.25)
		(keepout
			(tracks not_allowed)
			(vias allowed)
			(pads allowed)
			(copperpour not_allowed)
			(footprints allowed)
		)
		(placement
			(enabled no)
			(sheetname "")
		)
		(fill
			(thermal_gap 0.5)
			(thermal_bridge_width 0.5)
			(island_removal_mode 0)
		)
		(polygon
			(pts
				(arc
					(start 439.849514 -246.032274)
					(mid 439.845794 -246.041254)
					(end 439.836814 -246.044974)
				)
				(arc
					(start 438.363614 -246.044974)
					(mid 438.354634 -246.041254)
					(end 438.350914 -246.032274)
				)
				(arc
					(start 438.350914 -245.537736)
					(mid 438.354634 -245.528756)
					(end 438.363614 -245.525036)
				)
				(arc
					(start 439.836814 -245.525036)
					(mid 439.845794 -245.528756)
					(end 439.849514 -245.537736)
				)
			)
		)
	)
	(zone
		(layer "In1.Cu")
		(hatch none 0.5)
		(connect_pads
			(clearance 0)
		)
		(min_thickness 0.25)
		(keepout
			(tracks not_allowed)
			(vias allowed)
			(pads allowed)
			(copperpour not_allowed)
			(footprints allowed)
		)
		(placement
			(enabled no)
			(sheetname "")
		)
		(fill
			(thermal_gap 0.5)
			(thermal_bridge_width 0.5)
			(island_removal_mode 0)
		)
		(polygon
			(pts
				(arc
					(start 45.089318 -239.23244)
					(mid 45.085598 -239.24142)
					(end 45.076618 -239.24514)
				)
				(arc
					(start 43.603418 -239.24514)
					(mid 43.594438 -239.24142)
					(end 43.590718 -239.23244)
				)
				(arc
					(start 43.590718 -238.737902)
					(mid 43.594438 -238.728922)
					(end 43.603418 -238.725202)
				)
				(arc
					(start 45.076618 -238.725202)
					(mid 45.085598 -238.728922)
					(end 45.089318 -238.737902)
				)
			)
		)
	)
	(zone
		(layer "In1.Cu")
		(hatch none 0.5)
		(connect_pads
			(clearance 0)
		)
		(min_thickness 0.25)
		(keepout
			(tracks not_allowed)
			(vias allowed)
			(pads allowed)
			(copperpour not_allowed)
			(footprints allowed)
		)
		(placement
			(enabled no)
			(sheetname "")
		)
		(fill
			(thermal_gap 0.5)
			(thermal_bridge_width 0.5)
			(island_removal_mode 0)
		)
		(polygon
			(pts
				(arc
					(start 202.897232 -200.132442)
					(mid 202.893512 -200.141422)
					(end 202.884532 -200.145142)
				)
				(arc
					(start 201.411332 -200.145142)
					(mid 201.402352 -200.141422)
					(end 201.398632 -200.132442)
				)
				(arc
					(start 201.398632 -199.637904)
					(mid 201.402352 -199.628924)
					(end 201.411332 -199.625204)
				)
				(arc
					(start 202.884532 -199.625204)
					(mid 202.893512 -199.628924)
					(end 202.897232 -199.637904)
				)
			)
		)
	)
	(zone
		(layer "In1.Cu")
		(hatch none 0.5)
		(connect_pads
			(clearance 0)
		)
		(min_thickness 0.25)
		(keepout
			(tracks not_allowed)
			(vias allowed)
			(pads allowed)
			(copperpour not_allowed)
			(footprints allowed)
		)
		(placement
			(enabled no)
			(sheetname "")
		)
		(fill
			(thermal_gap 0.5)
			(thermal_bridge_width 0.5)
			(island_removal_mode 0)
		)
		(polygon
			(pts
				(arc
					(start 409.488894 -397.849344)
					(mid 409.107894 -397.849344)
					(end 409.488894 -397.849344)
				)
			)
		)
	)
	(zone
		(layer "In1.Cu")
		(hatch none 0.5)
		(connect_pads
			(clearance 0)
		)
		(min_thickness 0.25)
		(keepout
			(tracks not_allowed)
			(vias allowed)
			(pads allowed)
			(copperpour not_allowed)
			(footprints allowed)
		)
		(placement
			(enabled no)
			(sheetname "")
		)
		(fill
			(thermal_gap 0.5)
			(thermal_bridge_width 0.5)
			(island_removal_mode 0)
		)
		(polygon
			(pts
				(arc
					(start 195.353432 -265.5824)
					(mid 195.349712 -265.59138)
					(end 195.340732 -265.5951)
				)
				(arc
					(start 193.867532 -265.5951)
					(mid 193.858552 -265.59138)
					(end 193.854832 -265.5824)
				)
				(arc
					(start 193.854832 -265.087862)
					(mid 193.858552 -265.078882)
					(end 193.867532 -265.075162)
				)
				(arc
					(start 195.340732 -265.075162)
					(mid 195.349712 -265.078882)
					(end 195.353432 -265.087862)
				)
			)
		)
	)
	(zone
		(layer "In1.Cu")
		(hatch none 0.5)
		(connect_pads
			(clearance 0)
		)
		(min_thickness 0.25)
		(keepout
			(tracks not_allowed)
			(vias allowed)
			(pads allowed)
			(copperpour not_allowed)
			(footprints allowed)
		)
		(placement
			(enabled no)
			(sheetname "")
		)
		(fill
			(thermal_gap 0.5)
			(thermal_bridge_width 0.5)
			(island_removal_mode 0)
		)
		(polygon
			(pts
				(arc
					(start 140.955268 -15.90294)
					(mid 140.977586 -15.849058)
					(end 141.031468 -15.82674)
				)
				(arc
					(start 141.860016 -15.82674)
					(mid 141.913898 -15.849058)
					(end 141.936216 -15.90294)
				)
				(arc
					(start 141.936216 -17.19834)
					(mid 141.913898 -17.252222)
					(end 141.860016 -17.27454)
				)
				(arc
					(start 141.031468 -17.27454)
					(mid 140.977586 -17.252222)
					(end 140.955268 -17.19834)
				)
			)
		)
	)
	(zone
		(layer "In1.Cu")
		(hatch none 0.5)
		(connect_pads
			(clearance 0)
		)
		(min_thickness 0.25)
		(keepout
			(tracks not_allowed)
			(vias allowed)
			(pads allowed)
			(copperpour not_allowed)
			(footprints allowed)
		)
		(placement
			(enabled no)
			(sheetname "")
		)
		(fill
			(thermal_gap 0.5)
			(thermal_bridge_width 0.5)
			(island_removal_mode 0)
		)
		(polygon
			(pts
				(arc
					(start 30.001464 -291.082476)
					(mid 29.997744 -291.091456)
					(end 29.988764 -291.095176)
				)
				(arc
					(start 28.515564 -291.095176)
					(mid 28.506584 -291.091456)
					(end 28.502864 -291.082476)
				)
				(arc
					(start 28.502864 -290.587938)
					(mid 28.506584 -290.578958)
					(end 28.515564 -290.575238)
				)
				(arc
					(start 29.988764 -290.575238)
					(mid 29.997744 -290.578958)
					(end 30.001464 -290.587938)
				)
			)
		)
	)
	(zone
		(layer "In1.Cu")
		(hatch none 0.5)
		(connect_pads
			(clearance 0)
		)
		(min_thickness 0.25)
		(keepout
			(tracks not_allowed)
			(vias allowed)
			(pads allowed)
			(copperpour not_allowed)
			(footprints allowed)
		)
		(placement
			(enabled no)
			(sheetname "")
		)
		(fill
			(thermal_gap 0.5)
			(thermal_bridge_width 0.5)
			(island_removal_mode 0)
		)
		(polygon
			(pts
				(arc
					(start 169.277284 -268.13256)
					(mid 169.273564 -268.14154)
					(end 169.264584 -268.14526)
				)
				(arc
					(start 167.791384 -268.14526)
					(mid 167.782404 -268.14154)
					(end 167.778684 -268.13256)
				)
				(arc
					(start 167.778684 -267.638022)
					(mid 167.782404 -267.629042)
					(end 167.791384 -267.625322)
				)
				(arc
					(start 169.264584 -267.625322)
					(mid 169.273564 -267.629042)
					(end 169.277284 -267.638022)
				)
			)
		)
	)
	(zone
		(layer "In1.Cu")
		(hatch none 0.5)
		(connect_pads
			(clearance 0)
		)
		(min_thickness 0.25)
		(keepout
			(tracks not_allowed)
			(vias allowed)
			(pads allowed)
			(copperpour not_allowed)
			(footprints allowed)
		)
		(placement
			(enabled no)
			(sheetname "")
		)
		(fill
			(thermal_gap 0.5)
			(thermal_bridge_width 0.5)
			(island_removal_mode 0)
		)
		(polygon
			(pts
				(arc
					(start 165.177216 -224.78238)
					(mid 165.173496 -224.79136)
					(end 165.164516 -224.79508)
				)
				(arc
					(start 163.691316 -224.79508)
					(mid 163.682336 -224.79136)
					(end 163.678616 -224.78238)
				)
				(arc
					(start 163.678616 -224.287842)
					(mid 163.682336 -224.278862)
					(end 163.691316 -224.275142)
				)
				(arc
					(start 165.164516 -224.275142)
					(mid 165.173496 -224.278862)
					(end 165.177216 -224.287842)
				)
			)
		)
	)
	(zone
		(layer "In1.Cu")
		(hatch none 0.5)
		(connect_pads
			(clearance 0)
		)
		(min_thickness 0.25)
		(keepout
			(tracks not_allowed)
			(vias allowed)
			(pads allowed)
			(copperpour not_allowed)
			(footprints allowed)
		)
		(placement
			(enabled no)
			(sheetname "")
		)
		(fill
			(thermal_gap 0.5)
			(thermal_bridge_width 0.5)
			(island_removal_mode 0)
		)
		(polygon
			(pts
				(arc
					(start 118.89105 -383.440686)
					(mid 119.01805 -383.567686)
					(end 119.14505 -383.440686)
				)
				(arc
					(start 119.14505 -383.364486)
					(mid 119.01805 -383.237486)
					(end 118.89105 -383.364486)
				)
			)
		)
	)
	(zone
		(layer "In1.Cu")
		(hatch none 0.5)
		(connect_pads
			(clearance 0)
		)
		(min_thickness 0.25)
		(keepout
			(tracks not_allowed)
			(vias allowed)
			(pads allowed)
			(copperpour not_allowed)
			(footprints allowed)
		)
		(placement
			(enabled no)
			(sheetname "")
		)
		(fill
			(thermal_gap 0.5)
			(thermal_bridge_width 0.5)
			(island_removal_mode 0)
		)
		(polygon
			(pts
				(arc
					(start 48.533304 -253.6825)
					(mid 48.529584 -253.69148)
					(end 48.520604 -253.6952)
				)
				(arc
					(start 47.047404 -253.6952)
					(mid 47.038424 -253.69148)
					(end 47.034704 -253.6825)
				)
				(arc
					(start 47.034704 -253.187962)
					(mid 47.038424 -253.178982)
					(end 47.047404 -253.175262)
				)
				(arc
					(start 48.520604 -253.175262)
					(mid 48.529584 -253.178982)
					(end 48.533304 -253.187962)
				)
			)
		)
	)
	(zone
		(layer "In1.Cu")
		(hatch none 0.5)
		(connect_pads
			(clearance 0)
		)
		(min_thickness 0.25)
		(keepout
			(tracks not_allowed)
			(vias allowed)
			(pads allowed)
			(copperpour not_allowed)
			(footprints allowed)
		)
		(placement
			(enabled no)
			(sheetname "")
		)
		(fill
			(thermal_gap 0.5)
			(thermal_bridge_width 0.5)
			(island_removal_mode 0)
		)
		(polygon
			(pts
				(arc
					(start 30.001464 -222.232474)
					(mid 29.997744 -222.241454)
					(end 29.988764 -222.245174)
				)
				(arc
					(start 28.515564 -222.245174)
					(mid 28.506584 -222.241454)
					(end 28.502864 -222.232474)
				)
				(arc
					(start 28.502864 -221.737936)
					(mid 28.506584 -221.728956)
					(end 28.515564 -221.725236)
				)
				(arc
					(start 29.988764 -221.725236)
					(mid 29.997744 -221.728956)
					(end 30.001464 -221.737936)
				)
			)
		)
	)
	(zone
		(layer "In1.Cu")
		(hatch none 0.5)
		(connect_pads
			(clearance 0)
		)
		(min_thickness 0.25)
		(keepout
			(tracks not_allowed)
			(vias allowed)
			(pads allowed)
			(copperpour not_allowed)
			(footprints allowed)
		)
		(placement
			(enabled no)
			(sheetname "")
		)
		(fill
			(thermal_gap 0.5)
			(thermal_bridge_width 0.5)
			(island_removal_mode 0)
		)
		(polygon
			(pts
				(arc
					(start 169.277284 -308.082442)
					(mid 169.273564 -308.091422)
					(end 169.264584 -308.095142)
				)
				(arc
					(start 167.791384 -308.095142)
					(mid 167.782404 -308.091422)
					(end 167.778684 -308.082442)
				)
				(arc
					(start 167.778684 -307.587904)
					(mid 167.782404 -307.578924)
					(end 167.791384 -307.575204)
				)
				(arc
					(start 169.264584 -307.575204)
					(mid 169.273564 -307.578924)
					(end 169.277284 -307.587904)
				)
			)
		)
	)
	(zone
		(layer "In1.Cu")
		(hatch none 0.5)
		(connect_pads
			(clearance 0)
		)
		(min_thickness 0.25)
		(keepout
			(tracks not_allowed)
			(vias allowed)
			(pads allowed)
			(copperpour not_allowed)
			(footprints allowed)
		)
		(placement
			(enabled no)
			(sheetname "")
		)
		(fill
			(thermal_gap 0.5)
			(thermal_bridge_width 0.5)
			(island_removal_mode 0)
		)
		(polygon
			(pts
				(arc
					(start 206.9973 -263.032494)
					(mid 206.99358 -263.041474)
					(end 206.9846 -263.045194)
				)
				(arc
					(start 205.5114 -263.045194)
					(mid 205.50242 -263.041474)
					(end 205.4987 -263.032494)
				)
				(arc
					(start 205.4987 -262.537956)
					(mid 205.50242 -262.528976)
					(end 205.5114 -262.525256)
				)
				(arc
					(start 206.9846 -262.525256)
					(mid 206.99358 -262.528976)
					(end 206.9973 -262.537956)
				)
			)
		)
	)
	(zone
		(layer "In1.Cu")
		(hatch none 0.5)
		(connect_pads
			(clearance 0)
		)
		(min_thickness 0.25)
		(keepout
			(tracks not_allowed)
			(vias allowed)
			(pads allowed)
			(copperpour not_allowed)
			(footprints allowed)
		)
		(placement
			(enabled no)
			(sheetname "")
		)
		(fill
			(thermal_gap 0.5)
			(thermal_bridge_width 0.5)
			(island_removal_mode 0)
		)
		(polygon
			(pts
				(arc
					(start 169.277284 -311.482486)
					(mid 169.273564 -311.491466)
					(end 169.264584 -311.495186)
				)
				(arc
					(start 167.791384 -311.495186)
					(mid 167.782404 -311.491466)
					(end 167.778684 -311.482486)
				)
				(arc
					(start 167.778684 -310.987948)
					(mid 167.782404 -310.978968)
					(end 167.791384 -310.975248)
				)
				(arc
					(start 169.264584 -310.975248)
					(mid 169.273564 -310.978968)
					(end 169.277284 -310.987948)
				)
			)
		)
	)
	(zone
		(layer "In1.Cu")
		(hatch none 0.5)
		(connect_pads
			(clearance 0)
		)
		(min_thickness 0.25)
		(keepout
			(tracks not_allowed)
			(vias allowed)
			(pads allowed)
			(copperpour not_allowed)
			(footprints allowed)
		)
		(placement
			(enabled no)
			(sheetname "")
		)
		(fill
			(thermal_gap 0.5)
			(thermal_bridge_width 0.5)
			(island_removal_mode 0)
		)
		(polygon
			(pts
				(arc
					(start 172.72127 -217.132408)
					(mid 172.71755 -217.141388)
					(end 172.70857 -217.145108)
				)
				(arc
					(start 171.23537 -217.145108)
					(mid 171.22639 -217.141388)
					(end 171.22267 -217.132408)
				)
				(arc
					(start 171.22267 -216.63787)
					(mid 171.22639 -216.62889)
					(end 171.23537 -216.62517)
				)
				(arc
					(start 172.70857 -216.62517)
					(mid 172.71755 -216.62889)
					(end 172.72127 -216.63787)
				)
			)
		)
	)
	(zone
		(layer "In1.Cu")
		(hatch none 0.5)
		(connect_pads
			(clearance 0)
		)
		(min_thickness 0.25)
		(keepout
			(tracks not_allowed)
			(vias allowed)
			(pads allowed)
			(copperpour not_allowed)
			(footprints allowed)
		)
		(placement
			(enabled no)
			(sheetname "")
		)
		(fill
			(thermal_gap 0.5)
			(thermal_bridge_width 0.5)
			(island_removal_mode 0)
		)
		(polygon
			(pts
				(arc
					(start 30.001464 -199.282558)
					(mid 29.997744 -199.291538)
					(end 29.988764 -199.295258)
				)
				(arc
					(start 28.515564 -199.295258)
					(mid 28.506584 -199.291538)
					(end 28.502864 -199.282558)
				)
				(arc
					(start 28.502864 -198.78802)
					(mid 28.506584 -198.77904)
					(end 28.515564 -198.77532)
				)
				(arc
					(start 29.988764 -198.77532)
					(mid 29.997744 -198.77904)
					(end 30.001464 -198.78802)
				)
			)
		)
	)
	(zone
		(layer "In1.Cu")
		(hatch none 0.5)
		(connect_pads
			(clearance 0)
		)
		(min_thickness 0.25)
		(keepout
			(tracks not_allowed)
			(vias allowed)
			(pads allowed)
			(copperpour not_allowed)
			(footprints allowed)
		)
		(placement
			(enabled no)
			(sheetname "")
		)
		(fill
			(thermal_gap 0.5)
			(thermal_bridge_width 0.5)
			(island_removal_mode 0)
		)
		(polygon
			(pts
				(arc
					(start 314.990734 -399.701258)
					(mid 315.117734 -399.828258)
					(end 315.244734 -399.701258)
				)
				(arc
					(start 315.244734 -399.625058)
					(mid 315.117734 -399.498058)
					(end 314.990734 -399.625058)
				)
			)
		)
	)
	(zone
		(layer "In1.Cu")
		(hatch none 0.5)
		(connect_pads
			(clearance 0)
		)
		(min_thickness 0.25)
		(keepout
			(tracks not_allowed)
			(vias allowed)
			(pads allowed)
			(copperpour not_allowed)
			(footprints allowed)
		)
		(placement
			(enabled no)
			(sheetname "")
		)
		(fill
			(thermal_gap 0.5)
			(thermal_bridge_width 0.5)
			(island_removal_mode 0)
		)
		(polygon
			(pts
				(arc
					(start 270.397478 -203.532232)
					(mid 270.393758 -203.541212)
					(end 270.384778 -203.544932)
				)
				(arc
					(start 268.911578 -203.544932)
					(mid 268.902598 -203.541212)
					(end 268.898878 -203.532232)
				)
				(arc
					(start 268.898878 -203.037694)
					(mid 268.902598 -203.028714)
					(end 268.911578 -203.024994)
				)
				(arc
					(start 270.384778 -203.024994)
					(mid 270.393758 -203.028714)
					(end 270.397478 -203.037694)
				)
			)
		)
	)
	(zone
		(layer "In1.Cu")
		(hatch none 0.5)
		(connect_pads
			(clearance 0)
		)
		(min_thickness 0.25)
		(keepout
			(tracks not_allowed)
			(vias allowed)
			(pads allowed)
			(copperpour not_allowed)
			(footprints allowed)
		)
		(placement
			(enabled no)
			(sheetname "")
		)
		(fill
			(thermal_gap 0.5)
			(thermal_bridge_width 0.5)
			(island_removal_mode 0)
		)
		(polygon
			(pts
				(arc
					(start 454.937368 -304.682144)
					(mid 454.933648 -304.691124)
					(end 454.924668 -304.694844)
				)
				(arc
					(start 453.451468 -304.694844)
					(mid 453.442488 -304.691124)
					(end 453.438768 -304.682144)
				)
				(arc
					(start 453.438768 -304.187606)
					(mid 453.442488 -304.178626)
					(end 453.451468 -304.174906)
				)
				(arc
					(start 454.924668 -304.174906)
					(mid 454.933648 -304.178626)
					(end 454.937368 -304.187606)
				)
			)
		)
	)
	(zone
		(layer "In1.Cu")
		(hatch none 0.5)
		(connect_pads
			(clearance 0)
		)
		(min_thickness 0.25)
		(keepout
			(tracks not_allowed)
			(vias allowed)
			(pads allowed)
			(copperpour not_allowed)
			(footprints allowed)
		)
		(placement
			(enabled no)
			(sheetname "")
		)
		(fill
			(thermal_gap 0.5)
			(thermal_bridge_width 0.5)
			(island_removal_mode 0)
		)
		(polygon
			(pts
				(arc
					(start 439.849514 -266.432284)
					(mid 439.845794 -266.441264)
					(end 439.836814 -266.444984)
				)
				(arc
					(start 438.363614 -266.444984)
					(mid 438.354634 -266.441264)
					(end 438.350914 -266.432284)
				)
				(arc
					(start 438.350914 -265.937746)
					(mid 438.354634 -265.928766)
					(end 438.363614 -265.925046)
				)
				(arc
					(start 439.836814 -265.925046)
					(mid 439.845794 -265.928766)
					(end 439.849514 -265.937746)
				)
			)
		)
	)
	(zone
		(layer "In1.Cu")
		(hatch none 0.5)
		(connect_pads
			(clearance 0)
		)
		(min_thickness 0.25)
		(keepout
			(tracks not_allowed)
			(vias allowed)
			(pads allowed)
			(copperpour not_allowed)
			(footprints allowed)
		)
		(placement
			(enabled no)
			(sheetname "")
		)
		(fill
			(thermal_gap 0.5)
			(thermal_bridge_width 0.5)
			(island_removal_mode 0)
		)
		(polygon
			(pts
				(arc
					(start 89.118694 -391.319258)
					(mid 89.245694 -391.446258)
					(end 89.372694 -391.319258)
				)
				(arc
					(start 89.372694 -391.243058)
					(mid 89.245694 -391.116058)
					(end 89.118694 -391.243058)
				)
			)
		)
	)
	(zone
		(layer "In1.Cu")
		(hatch none 0.5)
		(connect_pads
			(clearance 0)
		)
		(min_thickness 0.25)
		(keepout
			(tracks not_allowed)
			(vias allowed)
			(pads allowed)
			(copperpour not_allowed)
			(footprints allowed)
		)
		(placement
			(enabled no)
			(sheetname "")
		)
		(fill
			(thermal_gap 0.5)
			(thermal_bridge_width 0.5)
			(island_removal_mode 0)
		)
		(polygon
			(pts
				(arc
					(start 22.45741 -210.332574)
					(mid 22.45369 -210.341554)
					(end 22.44471 -210.345274)
				)
				(arc
					(start 20.97151 -210.345274)
					(mid 20.96253 -210.341554)
					(end 20.95881 -210.332574)
				)
				(arc
					(start 20.95881 -209.838036)
					(mid 20.96253 -209.829056)
					(end 20.97151 -209.825336)
				)
				(arc
					(start 22.44471 -209.825336)
					(mid 22.45369 -209.829056)
					(end 22.45741 -209.838036)
				)
			)
		)
	)
	(zone
		(layer "In1.Cu")
		(hatch none 0.5)
		(connect_pads
			(clearance 0)
		)
		(min_thickness 0.25)
		(keepout
			(tracks not_allowed)
			(vias allowed)
			(pads allowed)
			(copperpour not_allowed)
			(footprints allowed)
		)
		(placement
			(enabled no)
			(sheetname "")
		)
		(fill
			(thermal_gap 0.5)
			(thermal_bridge_width 0.5)
			(island_removal_mode 0)
		)
		(polygon
			(pts
				(arc
					(start 206.9973 -211.182458)
					(mid 206.99358 -211.191438)
					(end 206.9846 -211.195158)
				)
				(arc
					(start 205.5114 -211.195158)
					(mid 205.50242 -211.191438)
					(end 205.4987 -211.182458)
				)
				(arc
					(start 205.4987 -210.68792)
					(mid 205.50242 -210.67894)
					(end 205.5114 -210.67522)
				)
				(arc
					(start 206.9846 -210.67522)
					(mid 206.99358 -210.67894)
					(end 206.9973 -210.68792)
				)
			)
		)
	)
	(zone
		(layer "In1.Cu")
		(hatch none 0.5)
		(connect_pads
			(clearance 0)
		)
		(min_thickness 0.25)
		(keepout
			(tracks not_allowed)
			(vias allowed)
			(pads allowed)
			(copperpour not_allowed)
			(footprints allowed)
		)
		(placement
			(enabled no)
			(sheetname "")
		)
		(fill
			(thermal_gap 0.5)
			(thermal_bridge_width 0.5)
			(island_removal_mode 0)
		)
		(polygon
			(pts
				(arc
					(start 165.177216 -228.182424)
					(mid 165.173496 -228.191404)
					(end 165.164516 -228.195124)
				)
				(arc
					(start 163.691316 -228.195124)
					(mid 163.682336 -228.191404)
					(end 163.678616 -228.182424)
				)
				(arc
					(start 163.678616 -227.687886)
					(mid 163.682336 -227.678906)
					(end 163.691316 -227.675186)
				)
				(arc
					(start 165.164516 -227.675186)
					(mid 165.173496 -227.678906)
					(end 165.177216 -227.687886)
				)
			)
		)
	)
	(zone
		(layer "In1.Cu")
		(hatch none 0.5)
		(connect_pads
			(clearance 0)
		)
		(min_thickness 0.25)
		(keepout
			(tracks not_allowed)
			(vias allowed)
			(pads allowed)
			(copperpour not_allowed)
			(footprints allowed)
		)
		(placement
			(enabled no)
			(sheetname "")
		)
		(fill
			(thermal_gap 0.5)
			(thermal_bridge_width 0.5)
			(island_removal_mode 0)
		)
		(polygon
			(pts
				(arc
					(start 202.897232 -254.532384)
					(mid 202.893512 -254.541364)
					(end 202.884532 -254.545084)
				)
				(arc
					(start 201.411332 -254.545084)
					(mid 201.402352 -254.541364)
					(end 201.398632 -254.532384)
				)
				(arc
					(start 201.398632 -254.037846)
					(mid 201.402352 -254.028866)
					(end 201.411332 -254.025146)
				)
				(arc
					(start 202.884532 -254.025146)
					(mid 202.893512 -254.028866)
					(end 202.897232 -254.037846)
				)
			)
		)
	)
	(zone
		(layer "In1.Cu")
		(hatch none 0.5)
		(connect_pads
			(clearance 0)
		)
		(min_thickness 0.25)
		(keepout
			(tracks not_allowed)
			(vias allowed)
			(pads allowed)
			(copperpour not_allowed)
			(footprints allowed)
		)
		(placement
			(enabled no)
			(sheetname "")
		)
		(fill
			(thermal_gap 0.5)
			(thermal_bridge_width 0.5)
			(island_removal_mode 0)
		)
		(polygon
			(pts
				(arc
					(start 93.189044 -388.774432)
					(mid 92.808044 -388.774432)
					(end 93.189044 -388.774432)
				)
			)
		)
	)
	(zone
		(layer "In1.Cu")
		(hatch none 0.5)
		(connect_pads
			(clearance 0)
		)
		(min_thickness 0.25)
		(keepout
			(tracks not_allowed)
			(vias allowed)
			(pads allowed)
			(copperpour not_allowed)
			(footprints allowed)
		)
		(placement
			(enabled no)
			(sheetname "")
		)
		(fill
			(thermal_gap 0.5)
			(thermal_bridge_width 0.5)
			(island_removal_mode 0)
		)
		(polygon
			(pts
				(arc
					(start 341.518494 -391.822686)
					(mid 341.645494 -391.949686)
					(end 341.772494 -391.822686)
				)
				(arc
					(start 341.772494 -391.746486)
					(mid 341.645494 -391.619486)
					(end 341.518494 -391.746486)
				)
			)
		)
	)
	(zone
		(layer "In1.Cu")
		(hatch none 0.5)
		(connect_pads
			(clearance 0)
		)
		(min_thickness 0.25)
		(keepout
			(tracks not_allowed)
			(vias allowed)
			(pads allowed)
			(copperpour not_allowed)
			(footprints allowed)
		)
		(placement
			(enabled no)
			(sheetname "")
		)
		(fill
			(thermal_gap 0.5)
			(thermal_bridge_width 0.5)
			(island_removal_mode 0)
		)
		(polygon
			(pts
				(arc
					(start 125.94082 -33.005268)
					(mid 125.994702 -32.98295)
					(end 126.01702 -32.929068)
				)
				(arc
					(start 126.01702 -32.573468)
					(mid 125.994702 -32.519586)
					(end 125.94082 -32.497268)
				)
				(arc
					(start 124.03582 -32.497268)
					(mid 123.981938 -32.519586)
					(end 123.95962 -32.573468)
				)
				(arc
					(start 123.95962 -32.929068)
					(mid 123.981938 -32.98295)
					(end 124.03582 -33.005268)
				)
			)
		)
	)
	(zone
		(layer "In1.Cu")
		(hatch none 0.5)
		(connect_pads
			(clearance 0)
		)
		(min_thickness 0.25)
		(keepout
			(tracks not_allowed)
			(vias allowed)
			(pads allowed)
			(copperpour not_allowed)
			(footprints allowed)
		)
		(placement
			(enabled no)
			(sheetname "")
		)
		(fill
			(thermal_gap 0.5)
			(thermal_bridge_width 0.5)
			(island_removal_mode 0)
		)
		(polygon
			(pts
				(arc
					(start 293.029386 -239.232186)
					(mid 293.025666 -239.241166)
					(end 293.016686 -239.244886)
				)
				(arc
					(start 291.543486 -239.244886)
					(mid 291.534506 -239.241166)
					(end 291.530786 -239.232186)
				)
				(arc
					(start 291.530786 -238.737648)
					(mid 291.534506 -238.728668)
					(end 291.543486 -238.724948)
				)
				(arc
					(start 293.016686 -238.724948)
					(mid 293.025666 -238.728668)
					(end 293.029386 -238.737648)
				)
			)
		)
	)
	(zone
		(layer "In1.Cu")
		(hatch none 0.5)
		(connect_pads
			(clearance 0)
		)
		(min_thickness 0.25)
		(keepout
			(tracks not_allowed)
			(vias allowed)
			(pads allowed)
			(copperpour not_allowed)
			(footprints allowed)
		)
		(placement
			(enabled no)
			(sheetname "")
		)
		(fill
			(thermal_gap 0.5)
			(thermal_bridge_width 0.5)
			(island_removal_mode 0)
		)
		(polygon
			(pts
				(arc
					(start 206.5782 -285.735268)
					(mid 205.9178 -285.735268)
					(end 206.5782 -285.735268)
				)
			)
		)
	)
	(zone
		(layer "In1.Cu")
		(hatch none 0.5)
		(connect_pads
			(clearance 0)
		)
		(min_thickness 0.25)
		(keepout
			(tracks not_allowed)
			(vias allowed)
			(pads allowed)
			(copperpour not_allowed)
			(footprints allowed)
		)
		(placement
			(enabled no)
			(sheetname "")
		)
		(fill
			(thermal_gap 0.5)
			(thermal_bridge_width 0.5)
			(island_removal_mode 0)
		)
		(polygon
			(pts
				(arc
					(start 439.849514 -244.332252)
					(mid 439.845794 -244.341232)
					(end 439.836814 -244.344952)
				)
				(arc
					(start 438.363614 -244.344952)
					(mid 438.354634 -244.341232)
					(end 438.350914 -244.332252)
				)
				(arc
					(start 438.350914 -243.837714)
					(mid 438.354634 -243.828734)
					(end 438.363614 -243.825014)
				)
				(arc
					(start 439.836814 -243.825014)
					(mid 439.845794 -243.828734)
					(end 439.849514 -243.837714)
				)
			)
		)
	)
	(zone
		(layer "In1.Cu")
		(hatch none 0.5)
		(connect_pads
			(clearance 0)
		)
		(min_thickness 0.25)
		(keepout
			(tracks not_allowed)
			(vias allowed)
			(pads allowed)
			(copperpour not_allowed)
			(footprints allowed)
		)
		(placement
			(enabled no)
			(sheetname "")
		)
		(fill
			(thermal_gap 0.5)
			(thermal_bridge_width 0.5)
			(island_removal_mode 0)
		)
		(polygon
			(pts
				(arc
					(start 199.4535 -252.832362)
					(mid 199.44978 -252.841342)
					(end 199.4408 -252.845062)
				)
				(arc
					(start 197.9676 -252.845062)
					(mid 197.95862 -252.841342)
					(end 197.9549 -252.832362)
				)
				(arc
					(start 197.9549 -252.337824)
					(mid 197.95862 -252.328844)
					(end 197.9676 -252.325124)
				)
				(arc
					(start 199.4408 -252.325124)
					(mid 199.44978 -252.328844)
					(end 199.4535 -252.337824)
				)
			)
		)
	)
	(zone
		(layer "In1.Cu")
		(hatch none 0.5)
		(connect_pads
			(clearance 0)
		)
		(min_thickness 0.25)
		(keepout
			(tracks not_allowed)
			(vias allowed)
			(pads allowed)
			(copperpour not_allowed)
			(footprints allowed)
		)
		(placement
			(enabled no)
			(sheetname "")
		)
		(fill
			(thermal_gap 0.5)
			(thermal_bridge_width 0.5)
			(island_removal_mode 0)
		)
		(polygon
			(pts
				(arc
					(start 414.288732 -394.385292)
					(mid 413.907732 -394.385292)
					(end 414.288732 -394.385292)
				)
			)
		)
	)
	(zone
		(layer "In1.Cu")
		(hatch none 0.5)
		(connect_pads
			(clearance 0)
		)
		(min_thickness 0.25)
		(keepout
			(tracks not_allowed)
			(vias allowed)
			(pads allowed)
			(copperpour not_allowed)
			(footprints allowed)
		)
		(placement
			(enabled no)
			(sheetname "")
		)
		(fill
			(thermal_gap 0.5)
			(thermal_bridge_width 0.5)
			(island_removal_mode 0)
		)
		(polygon
			(pts
				(arc
					(start 413.117284 -248.58218)
					(mid 413.113564 -248.59116)
					(end 413.104584 -248.59488)
				)
				(arc
					(start 411.631384 -248.59488)
					(mid 411.622404 -248.59116)
					(end 411.618684 -248.58218)
				)
				(arc
					(start 411.618684 -248.087642)
					(mid 411.622404 -248.078662)
					(end 411.631384 -248.074942)
				)
				(arc
					(start 413.104584 -248.074942)
					(mid 413.113564 -248.078662)
					(end 413.117284 -248.087642)
				)
			)
		)
	)
	(zone
		(layer "In1.Cu")
		(hatch none 0.5)
		(connect_pads
			(clearance 0)
		)
		(min_thickness 0.25)
		(keepout
			(tracks not_allowed)
			(vias allowed)
			(pads allowed)
			(copperpour not_allowed)
			(footprints allowed)
		)
		(placement
			(enabled no)
			(sheetname "")
		)
		(fill
			(thermal_gap 0.5)
			(thermal_bridge_width 0.5)
			(island_removal_mode 0)
		)
		(polygon
			(pts
				(arc
					(start 450.8373 -291.932106)
					(mid 450.83358 -291.941086)
					(end 450.8246 -291.944806)
				)
				(arc
					(start 449.3514 -291.944806)
					(mid 449.34242 -291.941086)
					(end 449.3387 -291.932106)
				)
				(arc
					(start 449.3387 -291.437568)
					(mid 449.34242 -291.428588)
					(end 449.3514 -291.424868)
				)
				(arc
					(start 450.8246 -291.424868)
					(mid 450.83358 -291.428588)
					(end 450.8373 -291.437568)
				)
			)
		)
	)
	(zone
		(layer "In1.Cu")
		(hatch none 0.5)
		(connect_pads
			(clearance 0)
		)
		(min_thickness 0.25)
		(keepout
			(tracks not_allowed)
			(vias allowed)
			(pads allowed)
			(copperpour not_allowed)
			(footprints allowed)
		)
		(placement
			(enabled no)
			(sheetname "")
		)
		(fill
			(thermal_gap 0.5)
			(thermal_bridge_width 0.5)
			(island_removal_mode 0)
		)
		(polygon
			(pts
				(arc
					(start 18.357342 -245.18239)
					(mid 18.353622 -245.19137)
					(end 18.344642 -245.19509)
				)
				(arc
					(start 16.871442 -245.19509)
					(mid 16.862462 -245.19137)
					(end 16.858742 -245.18239)
				)
				(arc
					(start 16.858742 -244.687852)
					(mid 16.862462 -244.678872)
					(end 16.871442 -244.675152)
				)
				(arc
					(start 18.344642 -244.675152)
					(mid 18.353622 -244.678872)
					(end 18.357342 -244.687852)
				)
			)
		)
	)
	(zone
		(layer "In1.Cu")
		(hatch none 0.5)
		(connect_pads
			(clearance 0)
		)
		(min_thickness 0.25)
		(keepout
			(tracks not_allowed)
			(vias allowed)
			(pads allowed)
			(copperpour not_allowed)
			(footprints allowed)
		)
		(placement
			(enabled no)
			(sheetname "")
		)
		(fill
			(thermal_gap 0.5)
			(thermal_bridge_width 0.5)
			(island_removal_mode 0)
		)
		(polygon
			(pts
				(arc
					(start 46.991016 -391.319258)
					(mid 47.118016 -391.446258)
					(end 47.245016 -391.319258)
				)
				(arc
					(start 47.245016 -391.243058)
					(mid 47.118016 -391.116058)
					(end 46.991016 -391.243058)
				)
			)
		)
	)
	(zone
		(layer "In1.Cu")
		(hatch none 0.5)
		(connect_pads
			(clearance 0)
		)
		(min_thickness 0.25)
		(keepout
			(tracks not_allowed)
			(vias allowed)
			(pads allowed)
			(copperpour not_allowed)
			(footprints allowed)
		)
		(placement
			(enabled no)
			(sheetname "")
		)
		(fill
			(thermal_gap 0.5)
			(thermal_bridge_width 0.5)
			(island_removal_mode 0)
		)
		(polygon
			(pts
				(arc
					(start 165.177216 -234.132374)
					(mid 165.173496 -234.141354)
					(end 165.164516 -234.145074)
				)
				(arc
					(start 163.691316 -234.145074)
					(mid 163.682336 -234.141354)
					(end 163.678616 -234.132374)
				)
				(arc
					(start 163.678616 -233.637836)
					(mid 163.682336 -233.628856)
					(end 163.691316 -233.625136)
				)
				(arc
					(start 165.164516 -233.625136)
					(mid 165.173496 -233.628856)
					(end 165.177216 -233.637836)
				)
			)
		)
	)
	(zone
		(layer "In1.Cu")
		(hatch none 0.5)
		(connect_pads
			(clearance 0)
		)
		(min_thickness 0.25)
		(keepout
			(tracks not_allowed)
			(vias allowed)
			(pads allowed)
			(copperpour not_allowed)
			(footprints allowed)
		)
		(placement
			(enabled no)
			(sheetname "")
		)
		(fill
			(thermal_gap 0.5)
			(thermal_bridge_width 0.5)
			(island_removal_mode 0)
		)
		(polygon
			(pts
				(arc
					(start 184.365392 -247.73255)
					(mid 184.361672 -247.74153)
					(end 184.352692 -247.74525)
				)
				(arc
					(start 182.879492 -247.74525)
					(mid 182.870512 -247.74153)
					(end 182.866792 -247.73255)
				)
				(arc
					(start 182.866792 -247.238012)
					(mid 182.870512 -247.229032)
					(end 182.879492 -247.225312)
				)
				(arc
					(start 184.352692 -247.225312)
					(mid 184.361672 -247.229032)
					(end 184.365392 -247.238012)
				)
			)
		)
	)
	(zone
		(layer "In1.Cu")
		(hatch none 0.5)
		(connect_pads
			(clearance 0)
		)
		(min_thickness 0.25)
		(keepout
			(tracks not_allowed)
			(vias allowed)
			(pads allowed)
			(copperpour not_allowed)
			(footprints allowed)
		)
		(placement
			(enabled no)
			(sheetname "")
		)
		(fill
			(thermal_gap 0.5)
			(thermal_bridge_width 0.5)
			(island_removal_mode 0)
		)
		(polygon
			(pts
				(arc
					(start 187.809378 -211.182458)
					(mid 187.805658 -211.191438)
					(end 187.796678 -211.195158)
				)
				(arc
					(start 186.323478 -211.195158)
					(mid 186.314498 -211.191438)
					(end 186.310778 -211.182458)
				)
				(arc
					(start 186.310778 -210.68792)
					(mid 186.314498 -210.67894)
					(end 186.323478 -210.67522)
				)
				(arc
					(start 187.796678 -210.67522)
					(mid 187.805658 -210.67894)
					(end 187.809378 -210.68792)
				)
			)
		)
	)
	(zone
		(layer "In1.Cu")
		(hatch none 0.5)
		(connect_pads
			(clearance 0)
		)
		(min_thickness 0.25)
		(keepout
			(tracks not_allowed)
			(vias allowed)
			(pads allowed)
			(copperpour not_allowed)
			(footprints allowed)
		)
		(placement
			(enabled no)
			(sheetname "")
		)
		(fill
			(thermal_gap 0.5)
			(thermal_bridge_width 0.5)
			(island_removal_mode 0)
		)
		(polygon
			(pts
				(arc
					(start 371.29085 -399.701258)
					(mid 371.41785 -399.828258)
					(end 371.54485 -399.701258)
				)
				(arc
					(start 371.54485 -399.625058)
					(mid 371.41785 -399.498058)
					(end 371.29085 -399.625058)
				)
			)
		)
	)
	(zone
		(layer "In1.Cu")
		(hatch none 0.5)
		(connect_pads
			(clearance 0)
		)
		(min_thickness 0.25)
		(keepout
			(tracks not_allowed)
			(vias allowed)
			(pads allowed)
			(copperpour not_allowed)
			(footprints allowed)
		)
		(placement
			(enabled no)
			(sheetname "")
		)
		(fill
			(thermal_gap 0.5)
			(thermal_bridge_width 0.5)
			(island_removal_mode 0)
		)
		(polygon
			(pts
				(arc
					(start 432.30546 -303.83226)
					(mid 432.30174 -303.84124)
					(end 432.29276 -303.84496)
				)
				(arc
					(start 430.81956 -303.84496)
					(mid 430.81058 -303.84124)
					(end 430.80686 -303.83226)
				)
				(arc
					(start 430.80686 -303.337722)
					(mid 430.81058 -303.328742)
					(end 430.81956 -303.325022)
				)
				(arc
					(start 432.29276 -303.325022)
					(mid 432.30174 -303.328742)
					(end 432.30546 -303.337722)
				)
			)
		)
	)
	(zone
		(layer "In1.Cu")
		(hatch none 0.5)
		(connect_pads
			(clearance 0)
		)
		(min_thickness 0.25)
		(keepout
			(tracks not_allowed)
			(vias allowed)
			(pads allowed)
			(copperpour not_allowed)
			(footprints allowed)
		)
		(placement
			(enabled no)
			(sheetname "")
		)
		(fill
			(thermal_gap 0.5)
			(thermal_bridge_width 0.5)
			(island_removal_mode 0)
		)
		(polygon
			(pts
				(arc
					(start 300.57344 -317.432182)
					(mid 300.56972 -317.441162)
					(end 300.56074 -317.444882)
				)
				(arc
					(start 299.08754 -317.444882)
					(mid 299.07856 -317.441162)
					(end 299.07484 -317.432182)
				)
				(arc
					(start 299.07484 -316.937644)
					(mid 299.07856 -316.928664)
					(end 299.08754 -316.924944)
				)
				(arc
					(start 300.56074 -316.924944)
					(mid 300.56972 -316.928664)
					(end 300.57344 -316.937644)
				)
			)
		)
	)
	(zone
		(layer "In1.Cu")
		(hatch none 0.5)
		(connect_pads
			(clearance 0)
		)
		(min_thickness 0.25)
		(keepout
			(tracks not_allowed)
			(vias allowed)
			(pads allowed)
			(copperpour not_allowed)
			(footprints allowed)
		)
		(placement
			(enabled no)
			(sheetname "")
		)
		(fill
			(thermal_gap 0.5)
			(thermal_bridge_width 0.5)
			(island_removal_mode 0)
		)
		(polygon
			(pts
				(arc
					(start 266.29741 -263.882124)
					(mid 266.29369 -263.891104)
					(end 266.28471 -263.894824)
				)
				(arc
					(start 264.81151 -263.894824)
					(mid 264.80253 -263.891104)
					(end 264.79881 -263.882124)
				)
				(arc
					(start 264.79881 -263.387586)
					(mid 264.80253 -263.378606)
					(end 264.81151 -263.374886)
				)
				(arc
					(start 266.28471 -263.374886)
					(mid 266.29369 -263.378606)
					(end 266.29741 -263.387586)
				)
			)
		)
	)
	(zone
		(layer "In1.Cu")
		(hatch none 0.5)
		(connect_pads
			(clearance 0)
		)
		(min_thickness 0.25)
		(keepout
			(tracks not_allowed)
			(vias allowed)
			(pads allowed)
			(copperpour not_allowed)
			(footprints allowed)
		)
		(placement
			(enabled no)
			(sheetname "")
		)
		(fill
			(thermal_gap 0.5)
			(thermal_bridge_width 0.5)
			(island_removal_mode 0)
		)
		(polygon
			(pts
				(arc
					(start 419.888924 -397.156432)
					(mid 419.507924 -397.156432)
					(end 419.888924 -397.156432)
				)
			)
		)
	)
	(zone
		(layer "In1.Cu")
		(hatch none 0.5)
		(connect_pads
			(clearance 0)
		)
		(min_thickness 0.25)
		(keepout
			(tracks not_allowed)
			(vias allowed)
			(pads allowed)
			(copperpour not_allowed)
			(footprints allowed)
		)
		(placement
			(enabled no)
			(sheetname "")
		)
		(fill
			(thermal_gap 0.5)
			(thermal_bridge_width 0.5)
			(island_removal_mode 0)
		)
		(polygon
			(pts
				(arc
					(start 48.533304 -213.732364)
					(mid 48.529584 -213.741344)
					(end 48.520604 -213.745064)
				)
				(arc
					(start 47.047404 -213.745064)
					(mid 47.038424 -213.741344)
					(end 47.034704 -213.732364)
				)
				(arc
					(start 47.034704 -213.237826)
					(mid 47.038424 -213.228846)
					(end 47.047404 -213.225126)
				)
				(arc
					(start 48.520604 -213.225126)
					(mid 48.529584 -213.228846)
					(end 48.533304 -213.237826)
				)
			)
		)
	)
	(zone
		(layer "In1.Cu")
		(hatch none 0.5)
		(connect_pads
			(clearance 0)
		)
		(min_thickness 0.25)
		(keepout
			(tracks not_allowed)
			(vias allowed)
			(pads allowed)
			(copperpour not_allowed)
			(footprints allowed)
		)
		(placement
			(enabled no)
			(sheetname "")
		)
		(fill
			(thermal_gap 0.5)
			(thermal_bridge_width 0.5)
			(island_removal_mode 0)
		)
		(polygon
			(pts
				(arc
					(start 61.391038 -391.319258)
					(mid 61.518038 -391.446258)
					(end 61.645038 -391.319258)
				)
				(arc
					(start 61.645038 -391.243058)
					(mid 61.518038 -391.116058)
					(end 61.391038 -391.243058)
				)
			)
		)
	)
	(zone
		(layer "In1.Cu")
		(hatch none 0.5)
		(connect_pads
			(clearance 0)
		)
		(min_thickness 0.25)
		(keepout
			(tracks not_allowed)
			(vias allowed)
			(pads allowed)
			(copperpour not_allowed)
			(footprints allowed)
		)
		(placement
			(enabled no)
			(sheetname "")
		)
		(fill
			(thermal_gap 0.5)
			(thermal_bridge_width 0.5)
			(island_removal_mode 0)
		)
		(polygon
			(pts
				(arc
					(start 424.761406 -285.982156)
					(mid 424.757686 -285.991136)
					(end 424.748706 -285.994856)
				)
				(arc
					(start 423.275506 -285.994856)
					(mid 423.266526 -285.991136)
					(end 423.262806 -285.982156)
				)
				(arc
					(start 423.262806 -285.487618)
					(mid 423.266526 -285.478638)
					(end 423.275506 -285.474918)
				)
				(arc
					(start 424.748706 -285.474918)
					(mid 424.757686 -285.478638)
					(end 424.761406 -285.487618)
				)
			)
		)
	)
	(zone
		(layer "In1.Cu")
		(hatch none 0.5)
		(connect_pads
			(clearance 0)
		)
		(min_thickness 0.25)
		(keepout
			(tracks not_allowed)
			(vias allowed)
			(pads allowed)
			(copperpour not_allowed)
			(footprints allowed)
		)
		(placement
			(enabled no)
			(sheetname "")
		)
		(fill
			(thermal_gap 0.5)
			(thermal_bridge_width 0.5)
			(island_removal_mode 0)
		)
		(polygon
			(pts
				(arc
					(start 428.205392 -304.682144)
					(mid 428.201672 -304.691124)
					(end 428.192692 -304.694844)
				)
				(arc
					(start 426.719492 -304.694844)
					(mid 426.710512 -304.691124)
					(end 426.706792 -304.682144)
				)
				(arc
					(start 426.706792 -304.187606)
					(mid 426.710512 -304.178626)
					(end 426.719492 -304.174906)
				)
				(arc
					(start 428.192692 -304.174906)
					(mid 428.201672 -304.178626)
					(end 428.205392 -304.187606)
				)
			)
		)
	)
	(zone
		(layer "In1.Cu")
		(hatch none 0.5)
		(connect_pads
			(clearance 0)
		)
		(min_thickness 0.25)
		(keepout
			(tracks not_allowed)
			(vias allowed)
			(pads allowed)
			(copperpour not_allowed)
			(footprints allowed)
		)
		(placement
			(enabled no)
			(sheetname "")
		)
		(fill
			(thermal_gap 0.5)
			(thermal_bridge_width 0.5)
			(island_removal_mode 0)
		)
		(polygon
			(pts
				(arc
					(start 147.818602 -383.440686)
					(mid 147.945602 -383.567686)
					(end 148.072602 -383.440686)
				)
				(arc
					(start 148.072602 -383.364486)
					(mid 147.945602 -383.237486)
					(end 147.818602 -383.364486)
				)
			)
		)
	)
	(zone
		(layer "In1.Cu")
		(hatch none 0.5)
		(connect_pads
			(clearance 0)
		)
		(min_thickness 0.25)
		(keepout
			(tracks not_allowed)
			(vias allowed)
			(pads allowed)
			(copperpour not_allowed)
			(footprints allowed)
		)
		(placement
			(enabled no)
			(sheetname "")
		)
		(fill
			(thermal_gap 0.5)
			(thermal_bridge_width 0.5)
			(island_removal_mode 0)
		)
		(polygon
			(pts
				(arc
					(start 60.177426 -298.732448)
					(mid 60.173706 -298.741428)
					(end 60.164726 -298.745148)
				)
				(arc
					(start 58.691526 -298.745148)
					(mid 58.682546 -298.741428)
					(end 58.678826 -298.732448)
				)
				(arc
					(start 58.678826 -298.23791)
					(mid 58.682546 -298.22893)
					(end 58.691526 -298.22521)
				)
				(arc
					(start 60.164726 -298.22521)
					(mid 60.173706 -298.22893)
					(end 60.177426 -298.23791)
				)
			)
		)
	)
	(zone
		(layer "In1.Cu")
		(hatch none 0.5)
		(connect_pads
			(clearance 0)
		)
		(min_thickness 0.25)
		(keepout
			(tracks not_allowed)
			(vias allowed)
			(pads allowed)
			(copperpour not_allowed)
			(footprints allowed)
		)
		(placement
			(enabled no)
			(sheetname "")
		)
		(fill
			(thermal_gap 0.5)
			(thermal_bridge_width 0.5)
			(island_removal_mode 0)
		)
		(polygon
			(pts
				(arc
					(start 265.87831 -230.485188)
					(mid 265.21791 -230.485188)
					(end 265.87831 -230.485188)
				)
			)
		)
	)
	(zone
		(layer "In1.Cu")
		(hatch none 0.5)
		(connect_pads
			(clearance 0)
		)
		(min_thickness 0.25)
		(keepout
			(tracks not_allowed)
			(vias allowed)
			(pads allowed)
			(copperpour not_allowed)
			(footprints allowed)
		)
		(placement
			(enabled no)
			(sheetname "")
		)
		(fill
			(thermal_gap 0.5)
			(thermal_bridge_width 0.5)
			(island_removal_mode 0)
		)
		(polygon
			(pts
				(arc
					(start 347.518482 -391.822686)
					(mid 347.645482 -391.949686)
					(end 347.772482 -391.822686)
				)
				(arc
					(start 347.772482 -391.746486)
					(mid 347.645482 -391.619486)
					(end 347.518482 -391.746486)
				)
			)
		)
	)
	(zone
		(layer "In1.Cu")
		(hatch none 0.5)
		(connect_pads
			(clearance 0)
		)
		(min_thickness 0.25)
		(keepout
			(tracks not_allowed)
			(vias allowed)
			(pads allowed)
			(copperpour not_allowed)
			(footprints allowed)
		)
		(placement
			(enabled no)
			(sheetname "")
		)
		(fill
			(thermal_gap 0.5)
			(thermal_bridge_width 0.5)
			(island_removal_mode 0)
		)
		(polygon
			(pts
				(arc
					(start 154.688794 -389.467344)
					(mid 154.307794 -389.467344)
					(end 154.688794 -389.467344)
				)
			)
		)
	)
	(zone
		(layer "In1.Cu")
		(hatch none 0.5)
		(connect_pads
			(clearance 0)
		)
		(min_thickness 0.25)
		(keepout
			(tracks not_allowed)
			(vias allowed)
			(pads allowed)
			(copperpour not_allowed)
			(footprints allowed)
		)
		(placement
			(enabled no)
			(sheetname "")
		)
		(fill
			(thermal_gap 0.5)
			(thermal_bridge_width 0.5)
			(island_removal_mode 0)
		)
		(polygon
			(pts
				(arc
					(start 454.937368 -222.23222)
					(mid 454.933648 -222.2412)
					(end 454.924668 -222.24492)
				)
				(arc
					(start 453.451468 -222.24492)
					(mid 453.442488 -222.2412)
					(end 453.438768 -222.23222)
				)
				(arc
					(start 453.438768 -221.737682)
					(mid 453.442488 -221.728702)
					(end 453.451468 -221.724982)
				)
				(arc
					(start 454.924668 -221.724982)
					(mid 454.933648 -221.728702)
					(end 454.937368 -221.737682)
				)
			)
		)
	)
	(zone
		(layer "In1.Cu")
		(hatch none 0.5)
		(connect_pads
			(clearance 0)
		)
		(min_thickness 0.25)
		(keepout
			(tracks not_allowed)
			(vias allowed)
			(pads allowed)
			(copperpour not_allowed)
			(footprints allowed)
		)
		(placement
			(enabled no)
			(sheetname "")
		)
		(fill
			(thermal_gap 0.5)
			(thermal_bridge_width 0.5)
			(island_removal_mode 0)
		)
		(polygon
			(pts
				(arc
					(start 187.809378 -308.93258)
					(mid 187.805658 -308.94156)
					(end 187.796678 -308.94528)
				)
				(arc
					(start 186.323478 -308.94528)
					(mid 186.314498 -308.94156)
					(end 186.310778 -308.93258)
				)
				(arc
					(start 186.310778 -308.438042)
					(mid 186.314498 -308.429062)
					(end 186.323478 -308.425342)
				)
				(arc
					(start 187.796678 -308.425342)
					(mid 187.805658 -308.429062)
					(end 187.809378 -308.438042)
				)
			)
		)
	)
	(zone
		(layer "In1.Cu")
		(hatch none 0.5)
		(connect_pads
			(clearance 0)
		)
		(min_thickness 0.25)
		(keepout
			(tracks not_allowed)
			(vias allowed)
			(pads allowed)
			(copperpour not_allowed)
			(footprints allowed)
		)
		(placement
			(enabled no)
			(sheetname "")
		)
		(fill
			(thermal_gap 0.5)
			(thermal_bridge_width 0.5)
			(island_removal_mode 0)
		)
		(polygon
			(pts
				(arc
					(start 169.277284 -206.93253)
					(mid 169.273564 -206.94151)
					(end 169.264584 -206.94523)
				)
				(arc
					(start 167.791384 -206.94523)
					(mid 167.782404 -206.94151)
					(end 167.778684 -206.93253)
				)
				(arc
					(start 167.778684 -206.437992)
					(mid 167.782404 -206.429012)
					(end 167.791384 -206.425292)
				)
				(arc
					(start 169.264584 -206.425292)
					(mid 169.273564 -206.429012)
					(end 169.277284 -206.437992)
				)
			)
		)
	)
	(zone
		(layer "In1.Cu")
		(hatch none 0.5)
		(connect_pads
			(clearance 0)
		)
		(min_thickness 0.25)
		(keepout
			(tracks not_allowed)
			(vias allowed)
			(pads allowed)
			(copperpour not_allowed)
			(footprints allowed)
		)
		(placement
			(enabled no)
			(sheetname "")
		)
		(fill
			(thermal_gap 0.5)
			(thermal_bridge_width 0.5)
			(island_removal_mode 0)
		)
		(polygon
			(pts
				(arc
					(start 22.45741 -199.282558)
					(mid 22.45369 -199.291538)
					(end 22.44471 -199.295258)
				)
				(arc
					(start 20.97151 -199.295258)
					(mid 20.96253 -199.291538)
					(end 20.95881 -199.282558)
				)
				(arc
					(start 20.95881 -198.78802)
					(mid 20.96253 -198.77904)
					(end 20.97151 -198.77532)
				)
				(arc
					(start 22.44471 -198.77532)
					(mid 22.45369 -198.77904)
					(end 22.45741 -198.78802)
				)
			)
		)
	)
	(zone
		(layer "In1.Cu")
		(hatch none 0.5)
		(connect_pads
			(clearance 0)
		)
		(min_thickness 0.25)
		(keepout
			(tracks not_allowed)
			(vias allowed)
			(pads allowed)
			(copperpour not_allowed)
			(footprints allowed)
		)
		(placement
			(enabled no)
			(sheetname "")
		)
		(fill
			(thermal_gap 0.5)
			(thermal_bridge_width 0.5)
			(island_removal_mode 0)
		)
		(polygon
			(pts
				(arc
					(start 172.72127 -274.932394)
					(mid 172.71755 -274.941374)
					(end 172.70857 -274.945094)
				)
				(arc
					(start 171.23537 -274.945094)
					(mid 171.22639 -274.941374)
					(end 171.22267 -274.932394)
				)
				(arc
					(start 171.22267 -274.437856)
					(mid 171.22639 -274.428876)
					(end 171.23537 -274.425156)
				)
				(arc
					(start 172.70857 -274.425156)
					(mid 172.71755 -274.428876)
					(end 172.72127 -274.437856)
				)
			)
		)
	)
	(zone
		(layer "In1.Cu")
		(hatch none 0.5)
		(connect_pads
			(clearance 0)
		)
		(min_thickness 0.25)
		(keepout
			(tracks not_allowed)
			(vias allowed)
			(pads allowed)
			(copperpour not_allowed)
			(footprints allowed)
		)
		(placement
			(enabled no)
			(sheetname "")
		)
		(fill
			(thermal_gap 0.5)
			(thermal_bridge_width 0.5)
			(island_removal_mode 0)
		)
		(polygon
			(pts
				(arc
					(start 187.809378 -230.732584)
					(mid 187.805658 -230.741564)
					(end 187.796678 -230.745284)
				)
				(arc
					(start 186.323478 -230.745284)
					(mid 186.314498 -230.741564)
					(end 186.310778 -230.732584)
				)
				(arc
					(start 186.310778 -230.238046)
					(mid 186.314498 -230.229066)
					(end 186.323478 -230.225346)
				)
				(arc
					(start 187.796678 -230.225346)
					(mid 187.805658 -230.229066)
					(end 187.809378 -230.238046)
				)
			)
		)
	)
	(zone
		(layer "In1.Cu")
		(hatch none 0.5)
		(connect_pads
			(clearance 0)
		)
		(min_thickness 0.25)
		(keepout
			(tracks not_allowed)
			(vias allowed)
			(pads allowed)
			(copperpour not_allowed)
			(footprints allowed)
		)
		(placement
			(enabled no)
			(sheetname "")
		)
		(fill
			(thermal_gap 0.5)
			(thermal_bridge_width 0.5)
			(island_removal_mode 0)
		)
		(polygon
			(pts
				(arc
					(start 277.941532 -229.882192)
					(mid 277.937812 -229.891172)
					(end 277.928832 -229.894892)
				)
				(arc
					(start 276.455632 -229.894892)
					(mid 276.446652 -229.891172)
					(end 276.442932 -229.882192)
				)
				(arc
					(start 276.442932 -229.387654)
					(mid 276.446652 -229.378674)
					(end 276.455632 -229.374954)
				)
				(arc
					(start 277.928832 -229.374954)
					(mid 277.937812 -229.378674)
					(end 277.941532 -229.387654)
				)
			)
		)
	)
	(zone
		(layer "In1.Cu")
		(hatch none 0.5)
		(connect_pads
			(clearance 0)
		)
		(min_thickness 0.25)
		(keepout
			(tracks not_allowed)
			(vias allowed)
			(pads allowed)
			(copperpour not_allowed)
			(footprints allowed)
		)
		(placement
			(enabled no)
			(sheetname "")
		)
		(fill
			(thermal_gap 0.5)
			(thermal_bridge_width 0.5)
			(island_removal_mode 0)
		)
		(polygon
			(pts
				(arc
					(start 187.809378 -262.182356)
					(mid 187.805658 -262.191336)
					(end 187.796678 -262.195056)
				)
				(arc
					(start 186.323478 -262.195056)
					(mid 186.314498 -262.191336)
					(end 186.310778 -262.182356)
				)
				(arc
					(start 186.310778 -261.687818)
					(mid 186.314498 -261.678838)
					(end 186.323478 -261.675118)
				)
				(arc
					(start 187.796678 -261.675118)
					(mid 187.805658 -261.678838)
					(end 187.809378 -261.687818)
				)
			)
		)
	)
	(zone
		(layer "In1.Cu")
		(hatch none 0.5)
		(connect_pads
			(clearance 0)
		)
		(min_thickness 0.25)
		(keepout
			(tracks not_allowed)
			(vias allowed)
			(pads allowed)
			(copperpour not_allowed)
			(footprints allowed)
		)
		(placement
			(enabled no)
			(sheetname "")
		)
		(fill
			(thermal_gap 0.5)
			(thermal_bridge_width 0.5)
			(island_removal_mode 0)
		)
		(polygon
			(pts
				(arc
					(start 202.897232 -215.432386)
					(mid 202.893512 -215.441366)
					(end 202.884532 -215.445086)
				)
				(arc
					(start 201.411332 -215.445086)
					(mid 201.402352 -215.441366)
					(end 201.398632 -215.432386)
				)
				(arc
					(start 201.398632 -214.937848)
					(mid 201.402352 -214.928868)
					(end 201.411332 -214.925148)
				)
				(arc
					(start 202.884532 -214.925148)
					(mid 202.893512 -214.928868)
					(end 202.897232 -214.937848)
				)
			)
		)
	)
	(zone
		(layer "In1.Cu")
		(hatch none 0.5)
		(connect_pads
			(clearance 0)
		)
		(min_thickness 0.25)
		(keepout
			(tracks not_allowed)
			(vias allowed)
			(pads allowed)
			(copperpour not_allowed)
			(footprints allowed)
		)
		(placement
			(enabled no)
			(sheetname "")
		)
		(fill
			(thermal_gap 0.5)
			(thermal_bridge_width 0.5)
			(island_removal_mode 0)
		)
		(polygon
			(pts
				(arc
					(start 277.941532 -233.282236)
					(mid 277.937812 -233.291216)
					(end 277.928832 -233.294936)
				)
				(arc
					(start 276.455632 -233.294936)
					(mid 276.446652 -233.291216)
					(end 276.442932 -233.282236)
				)
				(arc
					(start 276.442932 -232.787698)
					(mid 276.446652 -232.778718)
					(end 276.455632 -232.774998)
				)
				(arc
					(start 277.928832 -232.774998)
					(mid 277.937812 -232.778718)
					(end 277.941532 -232.787698)
				)
			)
		)
	)
	(zone
		(layer "In1.Cu")
		(hatch none 0.5)
		(connect_pads
			(clearance 0)
		)
		(min_thickness 0.25)
		(keepout
			(tracks not_allowed)
			(vias allowed)
			(pads allowed)
			(copperpour not_allowed)
			(footprints allowed)
		)
		(placement
			(enabled no)
			(sheetname "")
		)
		(fill
			(thermal_gap 0.5)
			(thermal_bridge_width 0.5)
			(island_removal_mode 0)
		)
		(polygon
			(pts
				(arc
					(start 202.897232 -274.932394)
					(mid 202.893512 -274.941374)
					(end 202.884532 -274.945094)
				)
				(arc
					(start 201.411332 -274.945094)
					(mid 201.402352 -274.941374)
					(end 201.398632 -274.932394)
				)
				(arc
					(start 201.398632 -274.437856)
					(mid 201.402352 -274.428876)
					(end 201.411332 -274.425156)
				)
				(arc
					(start 202.884532 -274.425156)
					(mid 202.893512 -274.428876)
					(end 202.897232 -274.437856)
				)
			)
		)
	)
	(zone
		(layer "In1.Cu")
		(hatch none 0.5)
		(connect_pads
			(clearance 0)
		)
		(min_thickness 0.25)
		(keepout
			(tracks not_allowed)
			(vias allowed)
			(pads allowed)
			(copperpour not_allowed)
			(footprints allowed)
		)
		(placement
			(enabled no)
			(sheetname "")
		)
		(fill
			(thermal_gap 0.5)
			(thermal_bridge_width 0.5)
			(island_removal_mode 0)
		)
		(polygon
			(pts
				(arc
					(start 428.205392 -262.182102)
					(mid 428.201672 -262.191082)
					(end 428.192692 -262.194802)
				)
				(arc
					(start 426.719492 -262.194802)
					(mid 426.710512 -262.191082)
					(end 426.706792 -262.182102)
				)
				(arc
					(start 426.706792 -261.687564)
					(mid 426.710512 -261.678584)
					(end 426.719492 -261.674864)
				)
				(arc
					(start 428.192692 -261.674864)
					(mid 428.201672 -261.678584)
					(end 428.205392 -261.687564)
				)
			)
		)
	)
	(zone
		(layer "In1.Cu")
		(hatch none 0.5)
		(connect_pads
			(clearance 0)
		)
		(min_thickness 0.25)
		(keepout
			(tracks not_allowed)
			(vias allowed)
			(pads allowed)
			(copperpour not_allowed)
			(footprints allowed)
		)
		(placement
			(enabled no)
			(sheetname "")
		)
		(fill
			(thermal_gap 0.5)
			(thermal_bridge_width 0.5)
			(island_removal_mode 0)
		)
		(polygon
			(pts
				(arc
					(start 48.533304 -241.782346)
					(mid 48.529584 -241.791326)
					(end 48.520604 -241.795046)
				)
				(arc
					(start 47.047404 -241.795046)
					(mid 47.038424 -241.791326)
					(end 47.034704 -241.782346)
				)
				(arc
					(start 47.034704 -241.287808)
					(mid 47.038424 -241.278828)
					(end 47.047404 -241.275108)
				)
				(arc
					(start 48.520604 -241.275108)
					(mid 48.529584 -241.278828)
					(end 48.533304 -241.287808)
				)
			)
		)
	)
	(zone
		(layer "In1.Cu")
		(hatch none 0.5)
		(connect_pads
			(clearance 0)
		)
		(min_thickness 0.25)
		(keepout
			(tracks not_allowed)
			(vias allowed)
			(pads allowed)
			(copperpour not_allowed)
			(footprints allowed)
		)
		(placement
			(enabled no)
			(sheetname "")
		)
		(fill
			(thermal_gap 0.5)
			(thermal_bridge_width 0.5)
			(island_removal_mode 0)
		)
		(polygon
			(pts
				(arc
					(start 424.761406 -303.83226)
					(mid 424.757686 -303.84124)
					(end 424.748706 -303.84496)
				)
				(arc
					(start 423.275506 -303.84496)
					(mid 423.266526 -303.84124)
					(end 423.262806 -303.83226)
				)
				(arc
					(start 423.262806 -303.337722)
					(mid 423.266526 -303.328742)
					(end 423.275506 -303.325022)
				)
				(arc
					(start 424.748706 -303.325022)
					(mid 424.757686 -303.328742)
					(end 424.761406 -303.337722)
				)
			)
		)
	)
	(zone
		(layer "In1.Cu")
		(hatch none 0.5)
		(connect_pads
			(clearance 0)
		)
		(min_thickness 0.25)
		(keepout
			(tracks not_allowed)
			(vias allowed)
			(pads allowed)
			(copperpour not_allowed)
			(footprints allowed)
		)
		(placement
			(enabled no)
			(sheetname "")
		)
		(fill
			(thermal_gap 0.5)
			(thermal_bridge_width 0.5)
			(island_removal_mode 0)
		)
		(polygon
			(pts
				(arc
					(start 308.117494 -238.382302)
					(mid 308.113774 -238.391282)
					(end 308.104794 -238.395002)
				)
				(arc
					(start 306.631594 -238.395002)
					(mid 306.622614 -238.391282)
					(end 306.618894 -238.382302)
				)
				(arc
					(start 306.618894 -237.887764)
					(mid 306.622614 -237.878784)
					(end 306.631594 -237.875064)
				)
				(arc
					(start 308.104794 -237.875064)
					(mid 308.113774 -237.878784)
					(end 308.117494 -237.887764)
				)
			)
		)
	)
	(zone
		(layer "In1.Cu")
		(hatch none 0.5)
		(connect_pads
			(clearance 0)
		)
		(min_thickness 0.25)
		(keepout
			(tracks not_allowed)
			(vias allowed)
			(pads allowed)
			(copperpour not_allowed)
			(footprints allowed)
		)
		(placement
			(enabled no)
			(sheetname "")
		)
		(fill
			(thermal_gap 0.5)
			(thermal_bridge_width 0.5)
			(island_removal_mode 0)
		)
		(polygon
			(pts
				(arc
					(start 439.849514 -225.632264)
					(mid 439.845794 -225.641244)
					(end 439.836814 -225.644964)
				)
				(arc
					(start 438.363614 -225.644964)
					(mid 438.354634 -225.641244)
					(end 438.350914 -225.632264)
				)
				(arc
					(start 438.350914 -225.137726)
					(mid 438.354634 -225.128746)
					(end 438.363614 -225.125026)
				)
				(arc
					(start 439.836814 -225.125026)
					(mid 439.845794 -225.128746)
					(end 439.849514 -225.137726)
				)
			)
		)
	)
	(zone
		(layer "In1.Cu")
		(hatch none 0.5)
		(connect_pads
			(clearance 0)
		)
		(min_thickness 0.25)
		(keepout
			(tracks not_allowed)
			(vias allowed)
			(pads allowed)
			(copperpour not_allowed)
			(footprints allowed)
		)
		(placement
			(enabled no)
			(sheetname "")
		)
		(fill
			(thermal_gap 0.5)
			(thermal_bridge_width 0.5)
			(island_removal_mode 0)
		)
		(polygon
			(pts
				(arc
					(start 184.365392 -289.382454)
					(mid 184.361672 -289.391434)
					(end 184.352692 -289.395154)
				)
				(arc
					(start 182.879492 -289.395154)
					(mid 182.870512 -289.391434)
					(end 182.866792 -289.382454)
				)
				(arc
					(start 182.866792 -288.887916)
					(mid 182.870512 -288.878936)
					(end 182.879492 -288.875216)
				)
				(arc
					(start 184.352692 -288.875216)
					(mid 184.361672 -288.878936)
					(end 184.365392 -288.887916)
				)
			)
		)
	)
	(zone
		(layer "In1.Cu")
		(hatch none 0.5)
		(connect_pads
			(clearance 0)
		)
		(min_thickness 0.25)
		(keepout
			(tracks not_allowed)
			(vias allowed)
			(pads allowed)
			(copperpour not_allowed)
			(footprints allowed)
		)
		(placement
			(enabled no)
			(sheetname "")
		)
		(fill
			(thermal_gap 0.5)
			(thermal_bridge_width 0.5)
			(island_removal_mode 0)
		)
		(polygon
			(pts
				(arc
					(start 413.117284 -301.2821)
					(mid 413.113564 -301.29108)
					(end 413.104584 -301.2948)
				)
				(arc
					(start 411.631384 -301.2948)
					(mid 411.622404 -301.29108)
					(end 411.618684 -301.2821)
				)
				(arc
					(start 411.618684 -300.787562)
					(mid 411.622404 -300.778582)
					(end 411.631384 -300.774862)
				)
				(arc
					(start 413.104584 -300.774862)
					(mid 413.113564 -300.778582)
					(end 413.117284 -300.787562)
				)
			)
		)
	)
	(zone
		(layer "In1.Cu")
		(hatch none 0.5)
		(connect_pads
			(clearance 0)
		)
		(min_thickness 0.25)
		(keepout
			(tracks not_allowed)
			(vias allowed)
			(pads allowed)
			(copperpour not_allowed)
			(footprints allowed)
		)
		(placement
			(enabled no)
			(sheetname "")
		)
		(fill
			(thermal_gap 0.5)
			(thermal_bridge_width 0.5)
			(island_removal_mode 0)
		)
		(polygon
			(pts
				(arc
					(start 127.761238 -385.31038)
					(mid 127.380238 -385.31038)
					(end 127.761238 -385.31038)
				)
			)
		)
	)
	(zone
		(layer "In1.Cu")
		(hatch none 0.5)
		(connect_pads
			(clearance 0)
		)
		(min_thickness 0.25)
		(keepout
			(tracks not_allowed)
			(vias allowed)
			(pads allowed)
			(copperpour not_allowed)
			(footprints allowed)
		)
		(placement
			(enabled no)
			(sheetname "")
		)
		(fill
			(thermal_gap 0.5)
			(thermal_bridge_width 0.5)
			(island_removal_mode 0)
		)
		(polygon
			(pts
				(arc
					(start 206.9973 -240.932462)
					(mid 206.99358 -240.941442)
					(end 206.9846 -240.945162)
				)
				(arc
					(start 205.5114 -240.945162)
					(mid 205.50242 -240.941442)
					(end 205.4987 -240.932462)
				)
				(arc
					(start 205.4987 -240.437924)
					(mid 205.50242 -240.428944)
					(end 205.5114 -240.425224)
				)
				(arc
					(start 206.9846 -240.425224)
					(mid 206.99358 -240.428944)
					(end 206.9973 -240.437924)
				)
			)
		)
	)
	(zone
		(layer "In1.Cu")
		(hatch none 0.5)
		(connect_pads
			(clearance 0)
		)
		(min_thickness 0.25)
		(keepout
			(tracks not_allowed)
			(vias allowed)
			(pads allowed)
			(copperpour not_allowed)
			(footprints allowed)
		)
		(placement
			(enabled no)
			(sheetname "")
		)
		(fill
			(thermal_gap 0.5)
			(thermal_bridge_width 0.5)
			(island_removal_mode 0)
		)
		(polygon
			(pts
				(arc
					(start 288.929318 -314.882276)
					(mid 288.925598 -314.891256)
					(end 288.916618 -314.894976)
				)
				(arc
					(start 287.443418 -314.894976)
					(mid 287.434438 -314.891256)
					(end 287.430718 -314.882276)
				)
				(arc
					(start 287.430718 -314.387738)
					(mid 287.434438 -314.378758)
					(end 287.443418 -314.375038)
				)
				(arc
					(start 288.916618 -314.375038)
					(mid 288.925598 -314.378758)
					(end 288.929318 -314.387738)
				)
			)
		)
	)
	(zone
		(layer "In1.Cu")
		(hatch none 0.5)
		(connect_pads
			(clearance 0)
		)
		(min_thickness 0.25)
		(keepout
			(tracks not_allowed)
			(vias allowed)
			(pads allowed)
			(copperpour not_allowed)
			(footprints allowed)
		)
		(placement
			(enabled no)
			(sheetname "")
		)
		(fill
			(thermal_gap 0.5)
			(thermal_bridge_width 0.5)
			(island_removal_mode 0)
		)
		(polygon
			(pts
				(arc
					(start 147.089114 -385.31038)
					(mid 146.708114 -385.31038)
					(end 147.089114 -385.31038)
				)
			)
		)
	)
	(zone
		(layer "In1.Cu")
		(hatch none 0.5)
		(connect_pads
			(clearance 0)
		)
		(min_thickness 0.25)
		(keepout
			(tracks not_allowed)
			(vias allowed)
			(pads allowed)
			(copperpour not_allowed)
			(footprints allowed)
		)
		(placement
			(enabled no)
			(sheetname "")
		)
		(fill
			(thermal_gap 0.5)
			(thermal_bridge_width 0.5)
			(island_removal_mode 0)
		)
		(polygon
			(pts
				(arc
					(start 180.265324 -241.782346)
					(mid 180.261604 -241.791326)
					(end 180.252624 -241.795046)
				)
				(arc
					(start 178.779424 -241.795046)
					(mid 178.770444 -241.791326)
					(end 178.766724 -241.782346)
				)
				(arc
					(start 178.766724 -241.287808)
					(mid 178.770444 -241.278828)
					(end 178.779424 -241.275108)
				)
				(arc
					(start 180.252624 -241.275108)
					(mid 180.261604 -241.278828)
					(end 180.265324 -241.287808)
				)
			)
		)
	)
	(zone
		(layer "In1.Cu")
		(hatch none 0.5)
		(connect_pads
			(clearance 0)
		)
		(min_thickness 0.25)
		(keepout
			(tracks not_allowed)
			(vias allowed)
			(pads allowed)
			(copperpour not_allowed)
			(footprints allowed)
		)
		(placement
			(enabled no)
			(sheetname "")
		)
		(fill
			(thermal_gap 0.5)
			(thermal_bridge_width 0.5)
			(island_removal_mode 0)
		)
		(polygon
			(pts
				(arc
					(start 349.298006 -392.30427)
					(mid 348.993206 -392.30427)
					(end 349.298006 -392.30427)
				)
			)
		)
	)
	(zone
		(layer "In1.Cu")
		(hatch none 0.5)
		(connect_pads
			(clearance 0)
		)
		(min_thickness 0.25)
		(keepout
			(tracks not_allowed)
			(vias allowed)
			(pads allowed)
			(copperpour not_allowed)
			(footprints allowed)
		)
		(placement
			(enabled no)
			(sheetname "")
		)
		(fill
			(thermal_gap 0.5)
			(thermal_bridge_width 0.5)
			(island_removal_mode 0)
		)
		(polygon
			(pts
				(arc
					(start 45.089318 -238.382556)
					(mid 45.085598 -238.391536)
					(end 45.076618 -238.395256)
				)
				(arc
					(start 43.603418 -238.395256)
					(mid 43.594438 -238.391536)
					(end 43.590718 -238.382556)
				)
				(arc
					(start 43.590718 -237.888018)
					(mid 43.594438 -237.879038)
					(end 43.603418 -237.875318)
				)
				(arc
					(start 45.076618 -237.875318)
					(mid 45.085598 -237.879038)
					(end 45.089318 -237.888018)
				)
			)
		)
	)
	(zone
		(layer "In1.Cu")
		(hatch none 0.5)
		(connect_pads
			(clearance 0)
		)
		(min_thickness 0.25)
		(keepout
			(tracks not_allowed)
			(vias allowed)
			(pads allowed)
			(copperpour not_allowed)
			(footprints allowed)
		)
		(placement
			(enabled no)
			(sheetname "")
		)
		(fill
			(thermal_gap 0.5)
			(thermal_bridge_width 0.5)
			(island_removal_mode 0)
		)
		(polygon
			(pts
				(arc
					(start 30.001464 -251.13234)
					(mid 29.997744 -251.14132)
					(end 29.988764 -251.14504)
				)
				(arc
					(start 28.515564 -251.14504)
					(mid 28.506584 -251.14132)
					(end 28.502864 -251.13234)
				)
				(arc
					(start 28.502864 -250.637802)
					(mid 28.506584 -250.628822)
					(end 28.515564 -250.625102)
				)
				(arc
					(start 29.988764 -250.625102)
					(mid 29.997744 -250.628822)
					(end 30.001464 -250.637802)
				)
			)
		)
	)
	(zone
		(layer "In1.Cu")
		(hatch none 0.5)
		(connect_pads
			(clearance 0)
		)
		(min_thickness 0.25)
		(keepout
			(tracks not_allowed)
			(vias allowed)
			(pads allowed)
			(copperpour not_allowed)
			(footprints allowed)
		)
		(placement
			(enabled no)
			(sheetname "")
		)
		(fill
			(thermal_gap 0.5)
			(thermal_bridge_width 0.5)
			(island_removal_mode 0)
		)
		(polygon
			(pts
				(arc
					(start 30.001464 -274.08251)
					(mid 29.997744 -274.09149)
					(end 29.988764 -274.09521)
				)
				(arc
					(start 28.515564 -274.09521)
					(mid 28.506584 -274.09149)
					(end 28.502864 -274.08251)
				)
				(arc
					(start 28.502864 -273.587972)
					(mid 28.506584 -273.578992)
					(end 28.515564 -273.575272)
				)
				(arc
					(start 29.988764 -273.575272)
					(mid 29.997744 -273.578992)
					(end 30.001464 -273.587972)
				)
			)
		)
	)
	(zone
		(layer "In1.Cu")
		(hatch none 0.5)
		(connect_pads
			(clearance 0)
		)
		(min_thickness 0.25)
		(keepout
			(tracks not_allowed)
			(vias allowed)
			(pads allowed)
			(copperpour not_allowed)
			(footprints allowed)
		)
		(placement
			(enabled no)
			(sheetname "")
		)
		(fill
			(thermal_gap 0.5)
			(thermal_bridge_width 0.5)
			(island_removal_mode 0)
		)
		(polygon
			(pts
				(arc
					(start 195.353432 -240.082578)
					(mid 195.349712 -240.091558)
					(end 195.340732 -240.095278)
				)
				(arc
					(start 193.867532 -240.095278)
					(mid 193.858552 -240.091558)
					(end 193.854832 -240.082578)
				)
				(arc
					(start 193.854832 -239.58804)
					(mid 193.858552 -239.57906)
					(end 193.867532 -239.57534)
				)
				(arc
					(start 195.340732 -239.57534)
					(mid 195.349712 -239.57906)
					(end 195.353432 -239.58804)
				)
			)
		)
	)
	(zone
		(layer "In1.Cu")
		(hatch none 0.5)
		(connect_pads
			(clearance 0)
		)
		(min_thickness 0.25)
		(keepout
			(tracks not_allowed)
			(vias allowed)
			(pads allowed)
			(copperpour not_allowed)
			(footprints allowed)
		)
		(placement
			(enabled no)
			(sheetname "")
		)
		(fill
			(thermal_gap 0.5)
			(thermal_bridge_width 0.5)
			(island_removal_mode 0)
		)
		(polygon
			(pts
				(arc
					(start 202.897232 -232.432352)
					(mid 202.893512 -232.441332)
					(end 202.884532 -232.445052)
				)
				(arc
					(start 201.411332 -232.445052)
					(mid 201.402352 -232.441332)
					(end 201.398632 -232.432352)
				)
				(arc
					(start 201.398632 -231.937814)
					(mid 201.402352 -231.928834)
					(end 201.411332 -231.925114)
				)
				(arc
					(start 202.884532 -231.925114)
					(mid 202.893512 -231.928834)
					(end 202.897232 -231.937814)
				)
			)
		)
	)
	(zone
		(layer "In1.Cu")
		(hatch none 0.5)
		(connect_pads
			(clearance 0)
		)
		(min_thickness 0.25)
		(keepout
			(tracks not_allowed)
			(vias allowed)
			(pads allowed)
			(copperpour not_allowed)
			(footprints allowed)
		)
		(placement
			(enabled no)
			(sheetname "")
		)
		(fill
			(thermal_gap 0.5)
			(thermal_bridge_width 0.5)
			(island_removal_mode 0)
		)
		(polygon
			(pts
				(arc
					(start 127.291084 -391.319258)
					(mid 127.418084 -391.446258)
					(end 127.545084 -391.319258)
				)
				(arc
					(start 127.545084 -391.243058)
					(mid 127.418084 -391.116058)
					(end 127.291084 -391.243058)
				)
			)
		)
	)
	(zone
		(layer "In1.Cu")
		(hatch none 0.5)
		(connect_pads
			(clearance 0)
		)
		(min_thickness 0.25)
		(keepout
			(tracks not_allowed)
			(vias allowed)
			(pads allowed)
			(copperpour not_allowed)
			(footprints allowed)
		)
		(placement
			(enabled no)
			(sheetname "")
		)
		(fill
			(thermal_gap 0.5)
			(thermal_bridge_width 0.5)
			(island_removal_mode 0)
		)
		(polygon
			(pts
				(arc
					(start 304.017426 -280.88209)
					(mid 304.013706 -280.89107)
					(end 304.004726 -280.89479)
				)
				(arc
					(start 302.531526 -280.89479)
					(mid 302.522546 -280.89107)
					(end 302.518826 -280.88209)
				)
				(arc
					(start 302.518826 -280.387552)
					(mid 302.522546 -280.378572)
					(end 302.531526 -280.374852)
				)
				(arc
					(start 304.004726 -280.374852)
					(mid 304.013706 -280.378572)
					(end 304.017426 -280.387552)
				)
			)
		)
	)
	(zone
		(layer "In1.Cu")
		(hatch none 0.5)
		(connect_pads
			(clearance 0)
		)
		(min_thickness 0.25)
		(keepout
			(tracks not_allowed)
			(vias allowed)
			(pads allowed)
			(copperpour not_allowed)
			(footprints allowed)
		)
		(placement
			(enabled no)
			(sheetname "")
		)
		(fill
			(thermal_gap 0.5)
			(thermal_bridge_width 0.5)
			(island_removal_mode 0)
		)
		(polygon
			(pts
				(arc
					(start 18.357342 -267.282422)
					(mid 18.353622 -267.291402)
					(end 18.344642 -267.295122)
				)
				(arc
					(start 16.871442 -267.295122)
					(mid 16.862462 -267.291402)
					(end 16.858742 -267.282422)
				)
				(arc
					(start 16.858742 -266.787884)
					(mid 16.862462 -266.778904)
					(end 16.871442 -266.775184)
				)
				(arc
					(start 18.344642 -266.775184)
					(mid 18.353622 -266.778904)
					(end 18.357342 -266.787884)
				)
			)
		)
	)
	(zone
		(layer "In1.Cu")
		(hatch none 0.5)
		(connect_pads
			(clearance 0)
		)
		(min_thickness 0.25)
		(keepout
			(tracks not_allowed)
			(vias allowed)
			(pads allowed)
			(copperpour not_allowed)
			(footprints allowed)
		)
		(placement
			(enabled no)
			(sheetname "")
		)
		(fill
			(thermal_gap 0.5)
			(thermal_bridge_width 0.5)
			(island_removal_mode 0)
		)
		(polygon
			(pts
				(arc
					(start 428.205392 -211.182204)
					(mid 428.201672 -211.191184)
					(end 428.192692 -211.194904)
				)
				(arc
					(start 426.719492 -211.194904)
					(mid 426.710512 -211.191184)
					(end 426.706792 -211.182204)
				)
				(arc
					(start 426.706792 -210.687666)
					(mid 426.710512 -210.678686)
					(end 426.719492 -210.674966)
				)
				(arc
					(start 428.192692 -210.674966)
					(mid 428.201672 -210.678686)
					(end 428.205392 -210.687666)
				)
			)
		)
	)
	(zone
		(layer "In1.Cu")
		(hatch none 0.5)
		(connect_pads
			(clearance 0)
		)
		(min_thickness 0.25)
		(keepout
			(tracks not_allowed)
			(vias allowed)
			(pads allowed)
			(copperpour not_allowed)
			(footprints allowed)
		)
		(placement
			(enabled no)
			(sheetname "")
		)
		(fill
			(thermal_gap 0.5)
			(thermal_bridge_width 0.5)
			(island_removal_mode 0)
		)
		(polygon
			(pts
				(arc
					(start 37.545264 -197.582536)
					(mid 37.541544 -197.591516)
					(end 37.532564 -197.595236)
				)
				(arc
					(start 36.059364 -197.595236)
					(mid 36.050384 -197.591516)
					(end 36.046664 -197.582536)
				)
				(arc
					(start 36.046664 -197.087998)
					(mid 36.050384 -197.079018)
					(end 36.059364 -197.075298)
				)
				(arc
					(start 37.532564 -197.075298)
					(mid 37.541544 -197.079018)
					(end 37.545264 -197.087998)
				)
			)
		)
	)
	(zone
		(layer "In1.Cu")
		(hatch none 0.5)
		(connect_pads
			(clearance 0)
		)
		(min_thickness 0.25)
		(keepout
			(tracks not_allowed)
			(vias allowed)
			(pads allowed)
			(copperpour not_allowed)
			(footprints allowed)
		)
		(placement
			(enabled no)
			(sheetname "")
		)
		(fill
			(thermal_gap 0.5)
			(thermal_bridge_width 0.5)
			(island_removal_mode 0)
		)
		(polygon
			(pts
				(arc
					(start 57.565544 -17.967198)
					(mid 57.587862 -18.02108)
					(end 57.641744 -18.043398)
				)
				(arc
					(start 57.837324 -18.043398)
					(mid 57.8592 -18.040266)
					(end 57.879234 -18.030952)
				)
				(arc
					(start 58.172858 -17.83842)
					(mid 58.214514 -17.826018)
					(end 58.25617 -17.83842)
				)
				(arc
					(start 58.551064 -18.030952)
					(mid 58.570988 -18.040188)
					(end 58.59272 -18.043398)
				)
				(arc
					(start 58.787284 -18.043398)
					(mid 58.841166 -18.02108)
					(end 58.863484 -17.967198)
				)
				(arc
					(start 58.863484 -17.281398)
					(mid 58.841166 -17.227516)
					(end 58.787284 -17.205198)
				)
				(arc
					(start 58.59272 -17.205198)
					(mid 58.570976 -17.208366)
					(end 58.551064 -17.217644)
				)
				(arc
					(start 58.2549 -17.41043)
					(mid 58.213216 -17.422652)
					(end 58.171588 -17.410176)
				)
				(arc
					(start 57.877964 -17.217644)
					(mid 57.85804 -17.208408)
					(end 57.836308 -17.205198)
				)
				(arc
					(start 57.641744 -17.205198)
					(mid 57.587862 -17.227516)
					(end 57.565544 -17.281398)
				)
			)
		)
	)
	(zone
		(layer "In1.Cu")
		(hatch none 0.5)
		(connect_pads
			(clearance 0)
		)
		(min_thickness 0.25)
		(keepout
			(tracks not_allowed)
			(vias allowed)
			(pads allowed)
			(copperpour not_allowed)
			(footprints allowed)
		)
		(placement
			(enabled no)
			(sheetname "")
		)
		(fill
			(thermal_gap 0.5)
			(thermal_bridge_width 0.5)
			(island_removal_mode 0)
		)
		(polygon
			(pts
				(arc
					(start 195.353432 -212.032342)
					(mid 195.349712 -212.041322)
					(end 195.340732 -212.045042)
				)
				(arc
					(start 193.867532 -212.045042)
					(mid 193.858552 -212.041322)
					(end 193.854832 -212.032342)
				)
				(arc
					(start 193.854832 -211.537804)
					(mid 193.858552 -211.528824)
					(end 193.867532 -211.525104)
				)
				(arc
					(start 195.340732 -211.525104)
					(mid 195.349712 -211.528824)
					(end 195.353432 -211.537804)
				)
			)
		)
	)
	(zone
		(layer "In1.Cu")
		(hatch none 0.5)
		(connect_pads
			(clearance 0)
		)
		(min_thickness 0.25)
		(keepout
			(tracks not_allowed)
			(vias allowed)
			(pads allowed)
			(copperpour not_allowed)
			(footprints allowed)
		)
		(placement
			(enabled no)
			(sheetname "")
		)
		(fill
			(thermal_gap 0.5)
			(thermal_bridge_width 0.5)
			(island_removal_mode 0)
		)
		(polygon
			(pts
				(arc
					(start 388.961122 -394.385292)
					(mid 388.580122 -394.385292)
					(end 388.961122 -394.385292)
				)
			)
		)
	)
	(zone
		(layer "In1.Cu")
		(hatch none 0.5)
		(connect_pads
			(clearance 0)
		)
		(min_thickness 0.25)
		(keepout
			(tracks not_allowed)
			(vias allowed)
			(pads allowed)
			(copperpour not_allowed)
			(footprints allowed)
		)
		(placement
			(enabled no)
			(sheetname "")
		)
		(fill
			(thermal_gap 0.5)
			(thermal_bridge_width 0.5)
			(island_removal_mode 0)
		)
		(polygon
			(pts
				(arc
					(start 60.177426 -292.782498)
					(mid 60.173706 -292.791478)
					(end 60.164726 -292.795198)
				)
				(arc
					(start 58.691526 -292.795198)
					(mid 58.682546 -292.791478)
					(end 58.678826 -292.782498)
				)
				(arc
					(start 58.678826 -292.28796)
					(mid 58.682546 -292.27898)
					(end 58.691526 -292.27526)
				)
				(arc
					(start 60.164726 -292.27526)
					(mid 60.173706 -292.27898)
					(end 60.177426 -292.28796)
				)
			)
		)
	)
	(zone
		(layer "In1.Cu")
		(hatch none 0.5)
		(connect_pads
			(clearance 0)
		)
		(min_thickness 0.25)
		(keepout
			(tracks not_allowed)
			(vias allowed)
			(pads allowed)
			(copperpour not_allowed)
			(footprints allowed)
		)
		(placement
			(enabled no)
			(sheetname "")
		)
		(fill
			(thermal_gap 0.5)
			(thermal_bridge_width 0.5)
			(island_removal_mode 0)
		)
		(polygon
			(pts
				(arc
					(start 206.9973 -309.782464)
					(mid 206.99358 -309.791444)
					(end 206.9846 -309.795164)
				)
				(arc
					(start 205.5114 -309.795164)
					(mid 205.50242 -309.791444)
					(end 205.4987 -309.782464)
				)
				(arc
					(start 205.4987 -309.287926)
					(mid 205.50242 -309.278946)
					(end 205.5114 -309.275226)
				)
				(arc
					(start 206.9846 -309.275226)
					(mid 206.99358 -309.278946)
					(end 206.9973 -309.287926)
				)
			)
		)
	)
	(zone
		(layer "In1.Cu")
		(hatch none 0.5)
		(connect_pads
			(clearance 0)
		)
		(min_thickness 0.25)
		(keepout
			(tracks not_allowed)
			(vias allowed)
			(pads allowed)
			(copperpour not_allowed)
			(footprints allowed)
		)
		(placement
			(enabled no)
			(sheetname "")
		)
		(fill
			(thermal_gap 0.5)
			(thermal_bridge_width 0.5)
			(island_removal_mode 0)
		)
		(polygon
			(pts
				(arc
					(start 417.217352 -240.932208)
					(mid 417.213632 -240.941188)
					(end 417.204652 -240.944908)
				)
				(arc
					(start 415.731452 -240.944908)
					(mid 415.722472 -240.941188)
					(end 415.718752 -240.932208)
				)
				(arc
					(start 415.718752 -240.43767)
					(mid 415.722472 -240.42869)
					(end 415.731452 -240.42497)
				)
				(arc
					(start 417.204652 -240.42497)
					(mid 417.213632 -240.42869)
					(end 417.217352 -240.43767)
				)
			)
		)
	)
	(zone
		(layer "In1.Cu")
		(hatch none 0.5)
		(connect_pads
			(clearance 0)
		)
		(min_thickness 0.25)
		(keepout
			(tracks not_allowed)
			(vias allowed)
			(pads allowed)
			(copperpour not_allowed)
			(footprints allowed)
		)
		(placement
			(enabled no)
			(sheetname "")
		)
		(fill
			(thermal_gap 0.5)
			(thermal_bridge_width 0.5)
			(island_removal_mode 0)
		)
		(polygon
			(pts
				(arc
					(start 51.170332 -383.92227)
					(mid 50.865532 -383.92227)
					(end 51.170332 -383.92227)
				)
			)
		)
	)
	(zone
		(layer "In1.Cu")
		(hatch none 0.5)
		(connect_pads
			(clearance 0)
		)
		(min_thickness 0.25)
		(keepout
			(tracks not_allowed)
			(vias allowed)
			(pads allowed)
			(copperpour not_allowed)
			(footprints allowed)
		)
		(placement
			(enabled no)
			(sheetname "")
		)
		(fill
			(thermal_gap 0.5)
			(thermal_bridge_width 0.5)
			(island_removal_mode 0)
		)
		(polygon
			(pts
				(arc
					(start 176.821338 -249.432572)
					(mid 176.817618 -249.441552)
					(end 176.808638 -249.445272)
				)
				(arc
					(start 175.335438 -249.445272)
					(mid 175.326458 -249.441552)
					(end 175.322738 -249.432572)
				)
				(arc
					(start 175.322738 -248.938034)
					(mid 175.326458 -248.929054)
					(end 175.335438 -248.925334)
				)
				(arc
					(start 176.808638 -248.925334)
					(mid 176.817618 -248.929054)
					(end 176.821338 -248.938034)
				)
			)
		)
	)
	(zone
		(layer "In1.Cu")
		(hatch none 0.5)
		(connect_pads
			(clearance 0)
		)
		(min_thickness 0.25)
		(keepout
			(tracks not_allowed)
			(vias allowed)
			(pads allowed)
			(copperpour not_allowed)
			(footprints allowed)
		)
		(placement
			(enabled no)
			(sheetname "")
		)
		(fill
			(thermal_gap 0.5)
			(thermal_bridge_width 0.5)
			(island_removal_mode 0)
		)
		(polygon
			(pts
				(arc
					(start 281.385264 -243.482114)
					(mid 281.381544 -243.491094)
					(end 281.372564 -243.494814)
				)
				(arc
					(start 279.899364 -243.494814)
					(mid 279.890384 -243.491094)
					(end 279.886664 -243.482114)
				)
				(arc
					(start 279.886664 -242.987576)
					(mid 279.890384 -242.978596)
					(end 279.899364 -242.974876)
				)
				(arc
					(start 281.372564 -242.974876)
					(mid 281.381544 -242.978596)
					(end 281.385264 -242.987576)
				)
			)
		)
	)
	(zone
		(layer "In1.Cu")
		(hatch none 0.5)
		(connect_pads
			(clearance 0)
		)
		(min_thickness 0.25)
		(keepout
			(tracks not_allowed)
			(vias allowed)
			(pads allowed)
			(copperpour not_allowed)
			(footprints allowed)
		)
		(placement
			(enabled no)
			(sheetname "")
		)
		(fill
			(thermal_gap 0.5)
			(thermal_bridge_width 0.5)
			(island_removal_mode 0)
		)
		(polygon
			(pts
				(arc
					(start 52.633372 -201.832464)
					(mid 52.629652 -201.841444)
					(end 52.620672 -201.845164)
				)
				(arc
					(start 51.147472 -201.845164)
					(mid 51.138492 -201.841444)
					(end 51.134772 -201.832464)
				)
				(arc
					(start 51.134772 -201.337926)
					(mid 51.138492 -201.328946)
					(end 51.147472 -201.325226)
				)
				(arc
					(start 52.620672 -201.325226)
					(mid 52.629652 -201.328946)
					(end 52.633372 -201.337926)
				)
			)
		)
	)
	(zone
		(layer "In1.Cu")
		(hatch none 0.5)
		(connect_pads
			(clearance 0)
		)
		(min_thickness 0.25)
		(keepout
			(tracks not_allowed)
			(vias allowed)
			(pads allowed)
			(copperpour not_allowed)
			(footprints allowed)
		)
		(placement
			(enabled no)
			(sheetname "")
		)
		(fill
			(thermal_gap 0.5)
			(thermal_bridge_width 0.5)
			(island_removal_mode 0)
		)
		(polygon
			(pts
				(arc
					(start 385.360926 -394.385292)
					(mid 384.979926 -394.385292)
					(end 385.360926 -394.385292)
				)
			)
		)
	)
	(zone
		(layer "In1.Cu")
		(hatch none 0.5)
		(connect_pads
			(clearance 0)
		)
		(min_thickness 0.25)
		(keepout
			(tracks not_allowed)
			(vias allowed)
			(pads allowed)
			(copperpour not_allowed)
			(footprints allowed)
		)
		(placement
			(enabled no)
			(sheetname "")
		)
		(fill
			(thermal_gap 0.5)
			(thermal_bridge_width 0.5)
			(island_removal_mode 0)
		)
		(polygon
			(pts
				(arc
					(start 206.9973 -270.682466)
					(mid 206.99358 -270.691446)
					(end 206.9846 -270.695166)
				)
				(arc
					(start 205.5114 -270.695166)
					(mid 205.50242 -270.691446)
					(end 205.4987 -270.682466)
				)
				(arc
					(start 205.4987 -270.187928)
					(mid 205.50242 -270.178948)
					(end 205.5114 -270.175228)
				)
				(arc
					(start 206.9846 -270.175228)
					(mid 206.99358 -270.178948)
					(end 206.9973 -270.187928)
				)
			)
		)
	)
	(zone
		(layer "In1.Cu")
		(hatch none 0.5)
		(connect_pads
			(clearance 0)
		)
		(min_thickness 0.25)
		(keepout
			(tracks not_allowed)
			(vias allowed)
			(pads allowed)
			(copperpour not_allowed)
			(footprints allowed)
		)
		(placement
			(enabled no)
			(sheetname "")
		)
		(fill
			(thermal_gap 0.5)
			(thermal_bridge_width 0.5)
			(island_removal_mode 0)
		)
		(polygon
			(pts
				(arc
					(start 121.291096 -383.440686)
					(mid 121.418096 -383.567686)
					(end 121.545096 -383.440686)
				)
				(arc
					(start 121.545096 -383.364486)
					(mid 121.418096 -383.237486)
					(end 121.291096 -383.364486)
				)
			)
		)
	)
	(zone
		(layer "In1.Cu")
		(hatch none 0.5)
		(connect_pads
			(clearance 0)
		)
		(min_thickness 0.25)
		(keepout
			(tracks not_allowed)
			(vias allowed)
			(pads allowed)
			(copperpour not_allowed)
			(footprints allowed)
		)
		(placement
			(enabled no)
			(sheetname "")
		)
		(fill
			(thermal_gap 0.5)
			(thermal_bridge_width 0.5)
			(island_removal_mode 0)
		)
		(polygon
			(pts
				(arc
					(start 130.56108 -386.003292)
					(mid 130.18008 -386.003292)
					(end 130.56108 -386.003292)
				)
			)
		)
	)
	(zone
		(layer "In1.Cu")
		(hatch none 0.5)
		(connect_pads
			(clearance 0)
		)
		(min_thickness 0.25)
		(keepout
			(tracks not_allowed)
			(vias allowed)
			(pads allowed)
			(copperpour not_allowed)
			(footprints allowed)
		)
		(placement
			(enabled no)
			(sheetname "")
		)
		(fill
			(thermal_gap 0.5)
			(thermal_bridge_width 0.5)
			(island_removal_mode 0)
		)
		(polygon
			(pts
				(arc
					(start 187.809378 -280.882344)
					(mid 187.805658 -280.891324)
					(end 187.796678 -280.895044)
				)
				(arc
					(start 186.323478 -280.895044)
					(mid 186.314498 -280.891324)
					(end 186.310778 -280.882344)
				)
				(arc
					(start 186.310778 -280.387806)
					(mid 186.314498 -280.378826)
					(end 186.323478 -280.375106)
				)
				(arc
					(start 187.796678 -280.375106)
					(mid 187.805658 -280.378826)
					(end 187.809378 -280.387806)
				)
			)
		)
	)
	(zone
		(layer "In1.Cu")
		(hatch none 0.5)
		(connect_pads
			(clearance 0)
		)
		(min_thickness 0.25)
		(keepout
			(tracks not_allowed)
			(vias allowed)
			(pads allowed)
			(copperpour not_allowed)
			(footprints allowed)
		)
		(placement
			(enabled no)
			(sheetname "")
		)
		(fill
			(thermal_gap 0.5)
			(thermal_bridge_width 0.5)
			(island_removal_mode 0)
		)
		(polygon
			(pts
				(arc
					(start 277.941532 -240.932208)
					(mid 277.937812 -240.941188)
					(end 277.928832 -240.944908)
				)
				(arc
					(start 276.455632 -240.944908)
					(mid 276.446652 -240.941188)
					(end 276.442932 -240.932208)
				)
				(arc
					(start 276.442932 -240.43767)
					(mid 276.446652 -240.42869)
					(end 276.455632 -240.42497)
				)
				(arc
					(start 277.928832 -240.42497)
					(mid 277.937812 -240.42869)
					(end 277.941532 -240.43767)
				)
			)
		)
	)
	(zone
		(layer "In1.Cu")
		(hatch none 0.5)
		(connect_pads
			(clearance 0)
		)
		(min_thickness 0.25)
		(keepout
			(tracks not_allowed)
			(vias allowed)
			(pads allowed)
			(copperpour not_allowed)
			(footprints allowed)
		)
		(placement
			(enabled no)
			(sheetname "")
		)
		(fill
			(thermal_gap 0.5)
			(thermal_bridge_width 0.5)
			(island_removal_mode 0)
		)
		(polygon
			(pts
				(arc
					(start 206.9973 -239.23244)
					(mid 206.99358 -239.24142)
					(end 206.9846 -239.24514)
				)
				(arc
					(start 205.5114 -239.24514)
					(mid 205.50242 -239.24142)
					(end 205.4987 -239.23244)
				)
				(arc
					(start 205.4987 -238.737902)
					(mid 205.50242 -238.728922)
					(end 205.5114 -238.725202)
				)
				(arc
					(start 206.9846 -238.725202)
					(mid 206.99358 -238.728922)
					(end 206.9973 -238.737902)
				)
			)
		)
	)
	(zone
		(layer "In1.Cu")
		(hatch none 0.5)
		(connect_pads
			(clearance 0)
		)
		(min_thickness 0.25)
		(keepout
			(tracks not_allowed)
			(vias allowed)
			(pads allowed)
			(copperpour not_allowed)
			(footprints allowed)
		)
		(placement
			(enabled no)
			(sheetname "")
		)
		(fill
			(thermal_gap 0.5)
			(thermal_bridge_width 0.5)
			(island_removal_mode 0)
		)
		(polygon
			(pts
				(arc
					(start 160.688782 -386.003292)
					(mid 160.307782 -386.003292)
					(end 160.688782 -386.003292)
				)
			)
		)
	)
	(zone
		(layer "In1.Cu")
		(hatch none 0.5)
		(connect_pads
			(clearance 0)
		)
		(min_thickness 0.25)
		(keepout
			(tracks not_allowed)
			(vias allowed)
			(pads allowed)
			(copperpour not_allowed)
			(footprints allowed)
		)
		(placement
			(enabled no)
			(sheetname "")
		)
		(fill
			(thermal_gap 0.5)
			(thermal_bridge_width 0.5)
			(island_removal_mode 0)
		)
		(polygon
			(pts
				(arc
					(start 30.001464 -270.682466)
					(mid 29.997744 -270.691446)
					(end 29.988764 -270.695166)
				)
				(arc
					(start 28.515564 -270.695166)
					(mid 28.506584 -270.691446)
					(end 28.502864 -270.682466)
				)
				(arc
					(start 28.502864 -270.187928)
					(mid 28.506584 -270.178948)
					(end 28.515564 -270.175228)
				)
				(arc
					(start 29.988764 -270.175228)
					(mid 29.997744 -270.178948)
					(end 30.001464 -270.187928)
				)
			)
		)
	)
	(zone
		(layer "In1.Cu")
		(hatch none 0.5)
		(connect_pads
			(clearance 0)
		)
		(min_thickness 0.25)
		(keepout
			(tracks not_allowed)
			(vias allowed)
			(pads allowed)
			(copperpour not_allowed)
			(footprints allowed)
		)
		(placement
			(enabled no)
			(sheetname "")
		)
		(fill
			(thermal_gap 0.5)
			(thermal_bridge_width 0.5)
			(island_removal_mode 0)
		)
		(polygon
			(pts
				(arc
					(start 435.749446 -280.88209)
					(mid 435.745726 -280.89107)
					(end 435.736746 -280.89479)
				)
				(arc
					(start 434.263546 -280.89479)
					(mid 434.254566 -280.89107)
					(end 434.250846 -280.88209)
				)
				(arc
					(start 434.250846 -280.387552)
					(mid 434.254566 -280.378572)
					(end 434.263546 -280.374852)
				)
				(arc
					(start 435.736746 -280.374852)
					(mid 435.745726 -280.378572)
					(end 435.749446 -280.387552)
				)
			)
		)
	)
	(zone
		(layer "In1.Cu")
		(hatch none 0.5)
		(connect_pads
			(clearance 0)
		)
		(min_thickness 0.25)
		(keepout
			(tracks not_allowed)
			(vias allowed)
			(pads allowed)
			(copperpour not_allowed)
			(footprints allowed)
		)
		(placement
			(enabled no)
			(sheetname "")
		)
		(fill
			(thermal_gap 0.5)
			(thermal_bridge_width 0.5)
			(island_removal_mode 0)
		)
		(polygon
			(pts
				(arc
					(start 180.265324 -265.5824)
					(mid 180.261604 -265.59138)
					(end 180.252624 -265.5951)
				)
				(arc
					(start 178.779424 -265.5951)
					(mid 178.770444 -265.59138)
					(end 178.766724 -265.5824)
				)
				(arc
					(start 178.766724 -265.087862)
					(mid 178.770444 -265.078882)
					(end 178.779424 -265.075162)
				)
				(arc
					(start 180.252624 -265.075162)
					(mid 180.261604 -265.078882)
					(end 180.265324 -265.087862)
				)
			)
		)
	)
	(zone
		(layer "In1.Cu")
		(hatch none 0.5)
		(connect_pads
			(clearance 0)
		)
		(min_thickness 0.25)
		(keepout
			(tracks not_allowed)
			(vias allowed)
			(pads allowed)
			(copperpour not_allowed)
			(footprints allowed)
		)
		(placement
			(enabled no)
			(sheetname "")
		)
		(fill
			(thermal_gap 0.5)
			(thermal_bridge_width 0.5)
			(island_removal_mode 0)
		)
		(polygon
			(pts
				(arc
					(start 304.017426 -253.682246)
					(mid 304.013706 -253.691226)
					(end 304.004726 -253.694946)
				)
				(arc
					(start 302.531526 -253.694946)
					(mid 302.522546 -253.691226)
					(end 302.518826 -253.682246)
				)
				(arc
					(start 302.518826 -253.187708)
					(mid 302.522546 -253.178728)
					(end 302.531526 -253.175008)
				)
				(arc
					(start 304.004726 -253.175008)
					(mid 304.013706 -253.178728)
					(end 304.017426 -253.187708)
				)
			)
		)
	)
	(zone
		(layer "In1.Cu")
		(hatch none 0.5)
		(connect_pads
			(clearance 0)
		)
		(min_thickness 0.25)
		(keepout
			(tracks not_allowed)
			(vias allowed)
			(pads allowed)
			(copperpour not_allowed)
			(footprints allowed)
		)
		(placement
			(enabled no)
			(sheetname "")
		)
		(fill
			(thermal_gap 0.5)
			(thermal_bridge_width 0.5)
			(island_removal_mode 0)
		)
		(polygon
			(pts
				(arc
					(start 52.633372 -281.732482)
					(mid 52.629652 -281.741462)
					(end 52.620672 -281.745182)
				)
				(arc
					(start 51.147472 -281.745182)
					(mid 51.138492 -281.741462)
					(end 51.134772 -281.732482)
				)
				(arc
					(start 51.134772 -281.237944)
					(mid 51.138492 -281.228964)
					(end 51.147472 -281.225244)
				)
				(arc
					(start 52.620672 -281.225244)
					(mid 52.629652 -281.228964)
					(end 52.633372 -281.237944)
				)
			)
		)
	)
	(zone
		(layer "In1.Cu")
		(hatch none 0.5)
		(connect_pads
			(clearance 0)
		)
		(min_thickness 0.25)
		(keepout
			(tracks not_allowed)
			(vias allowed)
			(pads allowed)
			(copperpour not_allowed)
			(footprints allowed)
		)
		(placement
			(enabled no)
			(sheetname "")
		)
		(fill
			(thermal_gap 0.5)
			(thermal_bridge_width 0.5)
			(island_removal_mode 0)
		)
		(polygon
			(pts
				(arc
					(start 315.860938 -394.385292)
					(mid 315.479938 -394.385292)
					(end 315.860938 -394.385292)
				)
			)
		)
	)
	(zone
		(layer "In1.Cu")
		(hatch none 0.5)
		(connect_pads
			(clearance 0)
		)
		(min_thickness 0.25)
		(keepout
			(tracks not_allowed)
			(vias allowed)
			(pads allowed)
			(copperpour not_allowed)
			(footprints allowed)
		)
		(placement
			(enabled no)
			(sheetname "")
		)
		(fill
			(thermal_gap 0.5)
			(thermal_bridge_width 0.5)
			(island_removal_mode 0)
		)
		(polygon
			(pts
				(arc
					(start 56.077358 -276.632416)
					(mid 56.073638 -276.641396)
					(end 56.064658 -276.645116)
				)
				(arc
					(start 54.591458 -276.645116)
					(mid 54.582478 -276.641396)
					(end 54.578758 -276.632416)
				)
				(arc
					(start 54.578758 -276.137878)
					(mid 54.582478 -276.128898)
					(end 54.591458 -276.125178)
				)
				(arc
					(start 56.064658 -276.125178)
					(mid 56.073638 -276.128898)
					(end 56.077358 -276.137878)
				)
			)
		)
	)
	(zone
		(layer "In1.Cu")
		(hatch none 0.5)
		(connect_pads
			(clearance 0)
		)
		(min_thickness 0.25)
		(keepout
			(tracks not_allowed)
			(vias allowed)
			(pads allowed)
			(copperpour not_allowed)
			(footprints allowed)
		)
		(placement
			(enabled no)
			(sheetname "")
		)
		(fill
			(thermal_gap 0.5)
			(thermal_bridge_width 0.5)
			(island_removal_mode 0)
		)
		(polygon
			(pts
				(arc
					(start 176.821338 -285.132526)
					(mid 176.817618 -285.141506)
					(end 176.808638 -285.145226)
				)
				(arc
					(start 175.335438 -285.145226)
					(mid 175.326458 -285.141506)
					(end 175.322738 -285.132526)
				)
				(arc
					(start 175.322738 -284.637988)
					(mid 175.326458 -284.629008)
					(end 175.335438 -284.625288)
				)
				(arc
					(start 176.808638 -284.625288)
					(mid 176.817618 -284.629008)
					(end 176.821338 -284.637988)
				)
			)
		)
	)
	(zone
		(layer "In1.Cu")
		(hatch none 0.5)
		(connect_pads
			(clearance 0)
		)
		(min_thickness 0.25)
		(keepout
			(tracks not_allowed)
			(vias allowed)
			(pads allowed)
			(copperpour not_allowed)
			(footprints allowed)
		)
		(placement
			(enabled no)
			(sheetname "")
		)
		(fill
			(thermal_gap 0.5)
			(thermal_bridge_width 0.5)
			(island_removal_mode 0)
		)
		(polygon
			(pts
				(arc
					(start 30.001464 -297.032426)
					(mid 29.997744 -297.041406)
					(end 29.988764 -297.045126)
				)
				(arc
					(start 28.515564 -297.045126)
					(mid 28.506584 -297.041406)
					(end 28.502864 -297.032426)
				)
				(arc
					(start 28.502864 -296.537888)
					(mid 28.506584 -296.528908)
					(end 28.515564 -296.525188)
				)
				(arc
					(start 29.988764 -296.525188)
					(mid 29.997744 -296.528908)
					(end 30.001464 -296.537888)
				)
			)
		)
	)
	(zone
		(layer "In1.Cu")
		(hatch none 0.5)
		(connect_pads
			(clearance 0)
		)
		(min_thickness 0.25)
		(keepout
			(tracks not_allowed)
			(vias allowed)
			(pads allowed)
			(copperpour not_allowed)
			(footprints allowed)
		)
		(placement
			(enabled no)
			(sheetname "")
		)
		(fill
			(thermal_gap 0.5)
			(thermal_bridge_width 0.5)
			(island_removal_mode 0)
		)
		(polygon
			(pts
				(arc
					(start 206.5782 -311.235344)
					(mid 205.9178 -311.235344)
					(end 206.5782 -311.235344)
				)
			)
		)
	)
	(zone
		(layer "In1.Cu")
		(hatch none 0.5)
		(connect_pads
			(clearance 0)
		)
		(min_thickness 0.25)
		(keepout
			(tracks not_allowed)
			(vias allowed)
			(pads allowed)
			(copperpour not_allowed)
			(footprints allowed)
		)
		(placement
			(enabled no)
			(sheetname "")
		)
		(fill
			(thermal_gap 0.5)
			(thermal_bridge_width 0.5)
			(island_removal_mode 0)
		)
		(polygon
			(pts
				(arc
					(start 420.661338 -263.882124)
					(mid 420.657618 -263.891104)
					(end 420.648638 -263.894824)
				)
				(arc
					(start 419.175438 -263.894824)
					(mid 419.166458 -263.891104)
					(end 419.162738 -263.882124)
				)
				(arc
					(start 419.162738 -263.387586)
					(mid 419.166458 -263.378606)
					(end 419.175438 -263.374886)
				)
				(arc
					(start 420.648638 -263.374886)
					(mid 420.657618 -263.378606)
					(end 420.661338 -263.387586)
				)
			)
		)
	)
	(zone
		(layer "In1.Cu")
		(hatch none 0.5)
		(connect_pads
			(clearance 0)
		)
		(min_thickness 0.25)
		(keepout
			(tracks not_allowed)
			(vias allowed)
			(pads allowed)
			(copperpour not_allowed)
			(footprints allowed)
		)
		(placement
			(enabled no)
			(sheetname "")
		)
		(fill
			(thermal_gap 0.5)
			(thermal_bridge_width 0.5)
			(island_removal_mode 0)
		)
		(polygon
			(pts
				(arc
					(start 304.770028 -392.30427)
					(mid 304.465228 -392.30427)
					(end 304.770028 -392.30427)
				)
			)
		)
	)
	(zone
		(layer "In1.Cu")
		(hatch none 0.5)
		(connect_pads
			(clearance 0)
		)
		(min_thickness 0.25)
		(keepout
			(tracks not_allowed)
			(vias allowed)
			(pads allowed)
			(copperpour not_allowed)
			(footprints allowed)
		)
		(placement
			(enabled no)
			(sheetname "")
		)
		(fill
			(thermal_gap 0.5)
			(thermal_bridge_width 0.5)
			(island_removal_mode 0)
		)
		(polygon
			(pts
				(arc
					(start 413.088836 -397.849344)
					(mid 412.707836 -397.849344)
					(end 413.088836 -397.849344)
				)
			)
		)
	)
	(zone
		(layer "In1.Cu")
		(hatch none 0.5)
		(connect_pads
			(clearance 0)
		)
		(min_thickness 0.25)
		(keepout
			(tracks not_allowed)
			(vias allowed)
			(pads allowed)
			(copperpour not_allowed)
			(footprints allowed)
		)
		(placement
			(enabled no)
			(sheetname "")
		)
		(fill
			(thermal_gap 0.5)
			(thermal_bridge_width 0.5)
			(island_removal_mode 0)
		)
		(polygon
			(pts
				(arc
					(start 40.98925 -279.182576)
					(mid 40.98553 -279.191556)
					(end 40.97655 -279.195276)
				)
				(arc
					(start 39.50335 -279.195276)
					(mid 39.49437 -279.191556)
					(end 39.49065 -279.182576)
				)
				(arc
					(start 39.49065 -278.688038)
					(mid 39.49437 -278.679058)
					(end 39.50335 -278.675338)
				)
				(arc
					(start 40.97655 -278.675338)
					(mid 40.98553 -278.679058)
					(end 40.98925 -278.688038)
				)
			)
		)
	)
	(zone
		(layer "In1.Cu")
		(hatch none 0.5)
		(connect_pads
			(clearance 0)
		)
		(min_thickness 0.25)
		(keepout
			(tracks not_allowed)
			(vias allowed)
			(pads allowed)
			(copperpour not_allowed)
			(footprints allowed)
		)
		(placement
			(enabled no)
			(sheetname "")
		)
		(fill
			(thermal_gap 0.5)
			(thermal_bridge_width 0.5)
			(island_removal_mode 0)
		)
		(polygon
			(pts
				(arc
					(start 265.87831 -239.835182)
					(mid 265.21791 -239.835182)
					(end 265.87831 -239.835182)
				)
			)
		)
	)
	(zone
		(layer "In1.Cu")
		(hatch none 0.5)
		(connect_pads
			(clearance 0)
		)
		(min_thickness 0.25)
		(keepout
			(tracks not_allowed)
			(vias allowed)
			(pads allowed)
			(copperpour not_allowed)
			(footprints allowed)
		)
		(placement
			(enabled no)
			(sheetname "")
		)
		(fill
			(thermal_gap 0.5)
			(thermal_bridge_width 0.5)
			(island_removal_mode 0)
		)
		(polygon
			(pts
				(arc
					(start 56.077358 -316.582552)
					(mid 56.073638 -316.591532)
					(end 56.064658 -316.595252)
				)
				(arc
					(start 54.591458 -316.595252)
					(mid 54.582478 -316.591532)
					(end 54.578758 -316.582552)
				)
				(arc
					(start 54.578758 -316.088014)
					(mid 54.582478 -316.079034)
					(end 54.591458 -316.075314)
				)
				(arc
					(start 56.064658 -316.075314)
					(mid 56.073638 -316.079034)
					(end 56.077358 -316.088014)
				)
			)
		)
	)
	(zone
		(layer "In1.Cu")
		(hatch none 0.5)
		(connect_pads
			(clearance 0)
		)
		(min_thickness 0.25)
		(keepout
			(tracks not_allowed)
			(vias allowed)
			(pads allowed)
			(copperpour not_allowed)
			(footprints allowed)
		)
		(placement
			(enabled no)
			(sheetname "")
		)
		(fill
			(thermal_gap 0.5)
			(thermal_bridge_width 0.5)
			(island_removal_mode 0)
		)
		(polygon
			(pts
				(arc
					(start 40.98925 -301.282354)
					(mid 40.98553 -301.291334)
					(end 40.97655 -301.295054)
				)
				(arc
					(start 39.50335 -301.295054)
					(mid 39.49437 -301.291334)
					(end 39.49065 -301.282354)
				)
				(arc
					(start 39.49065 -300.787816)
					(mid 39.49437 -300.778836)
					(end 39.50335 -300.775116)
				)
				(arc
					(start 40.97655 -300.775116)
					(mid 40.98553 -300.778836)
					(end 40.98925 -300.787816)
				)
			)
		)
	)
	(zone
		(layer "In1.Cu")
		(hatch none 0.5)
		(connect_pads
			(clearance 0)
		)
		(min_thickness 0.25)
		(keepout
			(tracks not_allowed)
			(vias allowed)
			(pads allowed)
			(copperpour not_allowed)
			(footprints allowed)
		)
		(placement
			(enabled no)
			(sheetname "")
		)
		(fill
			(thermal_gap 0.5)
			(thermal_bridge_width 0.5)
			(island_removal_mode 0)
		)
		(polygon
			(pts
				(arc
					(start 277.941532 -285.132272)
					(mid 277.937812 -285.141252)
					(end 277.928832 -285.144972)
				)
				(arc
					(start 276.455632 -285.144972)
					(mid 276.446652 -285.141252)
					(end 276.442932 -285.132272)
				)
				(arc
					(start 276.442932 -284.637734)
					(mid 276.446652 -284.628754)
					(end 276.455632 -284.625034)
				)
				(arc
					(start 277.928832 -284.625034)
					(mid 277.937812 -284.628754)
					(end 277.941532 -284.637734)
				)
			)
		)
	)
	(zone
		(layer "In1.Cu")
		(hatch none 0.5)
		(connect_pads
			(clearance 0)
		)
		(min_thickness 0.25)
		(keepout
			(tracks not_allowed)
			(vias allowed)
			(pads allowed)
			(copperpour not_allowed)
			(footprints allowed)
		)
		(placement
			(enabled no)
			(sheetname "")
		)
		(fill
			(thermal_gap 0.5)
			(thermal_bridge_width 0.5)
			(island_removal_mode 0)
		)
		(polygon
			(pts
				(arc
					(start 40.98925 -314.032392)
					(mid 40.98553 -314.041372)
					(end 40.97655 -314.045092)
				)
				(arc
					(start 39.50335 -314.045092)
					(mid 39.49437 -314.041372)
					(end 39.49065 -314.032392)
				)
				(arc
					(start 39.49065 -313.537854)
					(mid 39.49437 -313.528874)
					(end 39.50335 -313.525154)
				)
				(arc
					(start 40.97655 -313.525154)
					(mid 40.98553 -313.528874)
					(end 40.98925 -313.537854)
				)
			)
		)
	)
	(zone
		(layer "In1.Cu")
		(hatch none 0.5)
		(connect_pads
			(clearance 0)
		)
		(min_thickness 0.25)
		(keepout
			(tracks not_allowed)
			(vias allowed)
			(pads allowed)
			(copperpour not_allowed)
			(footprints allowed)
		)
		(placement
			(enabled no)
			(sheetname "")
		)
		(fill
			(thermal_gap 0.5)
			(thermal_bridge_width 0.5)
			(island_removal_mode 0)
		)
		(polygon
			(pts
				(arc
					(start 382.09093 -391.822686)
					(mid 382.21793 -391.949686)
					(end 382.34493 -391.822686)
				)
				(arc
					(start 382.34493 -391.746486)
					(mid 382.21793 -391.619486)
					(end 382.09093 -391.746486)
				)
			)
		)
	)
	(zone
		(layer "In1.Cu")
		(hatch none 0.5)
		(connect_pads
			(clearance 0)
		)
		(min_thickness 0.25)
		(keepout
			(tracks not_allowed)
			(vias allowed)
			(pads allowed)
			(copperpour not_allowed)
			(footprints allowed)
		)
		(placement
			(enabled no)
			(sheetname "")
		)
		(fill
			(thermal_gap 0.5)
			(thermal_bridge_width 0.5)
			(island_removal_mode 0)
		)
		(polygon
			(pts
				(arc
					(start 33.445196 -305.532536)
					(mid 33.441476 -305.541516)
					(end 33.432496 -305.545236)
				)
				(arc
					(start 31.959296 -305.545236)
					(mid 31.950316 -305.541516)
					(end 31.946596 -305.532536)
				)
				(arc
					(start 31.946596 -305.037998)
					(mid 31.950316 -305.029018)
					(end 31.959296 -305.025298)
				)
				(arc
					(start 33.432496 -305.025298)
					(mid 33.441476 -305.029018)
					(end 33.445196 -305.037998)
				)
			)
		)
	)
	(zone
		(layer "In1.Cu")
		(hatch none 0.5)
		(connect_pads
			(clearance 0)
		)
		(min_thickness 0.25)
		(keepout
			(tracks not_allowed)
			(vias allowed)
			(pads allowed)
			(copperpour not_allowed)
			(footprints allowed)
		)
		(placement
			(enabled no)
			(sheetname "")
		)
		(fill
			(thermal_gap 0.5)
			(thermal_bridge_width 0.5)
			(island_removal_mode 0)
		)
		(polygon
			(pts
				(arc
					(start 277.941532 -229.032308)
					(mid 277.937812 -229.041288)
					(end 277.928832 -229.045008)
				)
				(arc
					(start 276.455632 -229.045008)
					(mid 276.446652 -229.041288)
					(end 276.442932 -229.032308)
				)
				(arc
					(start 276.442932 -228.53777)
					(mid 276.446652 -228.52879)
					(end 276.455632 -228.52507)
				)
				(arc
					(start 277.928832 -228.52507)
					(mid 277.937812 -228.52879)
					(end 277.941532 -228.53777)
				)
			)
		)
	)
	(zone
		(layer "In1.Cu")
		(hatch none 0.5)
		(connect_pads
			(clearance 0)
		)
		(min_thickness 0.25)
		(keepout
			(tracks not_allowed)
			(vias allowed)
			(pads allowed)
			(copperpour not_allowed)
			(footprints allowed)
		)
		(placement
			(enabled no)
			(sheetname "")
		)
		(fill
			(thermal_gap 0.5)
			(thermal_bridge_width 0.5)
			(island_removal_mode 0)
		)
		(polygon
			(pts
				(arc
					(start 265.87831 -312.084974)
					(mid 265.21791 -312.084974)
					(end 265.87831 -312.084974)
				)
			)
		)
	)
	(zone
		(layer "In1.Cu")
		(hatch none 0.5)
		(connect_pads
			(clearance 0)
		)
		(min_thickness 0.25)
		(keepout
			(tracks not_allowed)
			(vias allowed)
			(pads allowed)
			(copperpour not_allowed)
			(footprints allowed)
		)
		(placement
			(enabled no)
			(sheetname "")
		)
		(fill
			(thermal_gap 0.5)
			(thermal_bridge_width 0.5)
			(island_removal_mode 0)
		)
		(polygon
			(pts
				(arc
					(start 121.87047 -383.92227)
					(mid 121.56567 -383.92227)
					(end 121.87047 -383.92227)
				)
			)
		)
	)
	(zone
		(layer "In1.Cu")
		(hatch none 0.5)
		(connect_pads
			(clearance 0)
		)
		(min_thickness 0.25)
		(keepout
			(tracks not_allowed)
			(vias allowed)
			(pads allowed)
			(copperpour not_allowed)
			(footprints allowed)
		)
		(placement
			(enabled no)
			(sheetname "")
		)
		(fill
			(thermal_gap 0.5)
			(thermal_bridge_width 0.5)
			(island_removal_mode 0)
		)
		(polygon
			(pts
				(arc
					(start 159.08909 -388.774432)
					(mid 158.70809 -388.774432)
					(end 159.08909 -388.774432)
				)
			)
		)
	)
	(zone
		(layer "In1.Cu")
		(hatch none 0.5)
		(connect_pads
			(clearance 0)
		)
		(min_thickness 0.25)
		(keepout
			(tracks not_allowed)
			(vias allowed)
			(pads allowed)
			(copperpour not_allowed)
			(footprints allowed)
		)
		(placement
			(enabled no)
			(sheetname "")
		)
		(fill
			(thermal_gap 0.5)
			(thermal_bridge_width 0.5)
			(island_removal_mode 0)
		)
		(polygon
			(pts
				(arc
					(start 187.809378 -217.132408)
					(mid 187.805658 -217.141388)
					(end 187.796678 -217.145108)
				)
				(arc
					(start 186.323478 -217.145108)
					(mid 186.314498 -217.141388)
					(end 186.310778 -217.132408)
				)
				(arc
					(start 186.310778 -216.63787)
					(mid 186.314498 -216.62889)
					(end 186.323478 -216.62517)
				)
				(arc
					(start 187.796678 -216.62517)
					(mid 187.805658 -216.62889)
					(end 187.809378 -216.63787)
				)
			)
		)
	)
	(zone
		(layer "In1.Cu")
		(hatch none 0.5)
		(connect_pads
			(clearance 0)
		)
		(min_thickness 0.25)
		(keepout
			(tracks not_allowed)
			(vias allowed)
			(pads allowed)
			(copperpour not_allowed)
			(footprints allowed)
		)
		(placement
			(enabled no)
			(sheetname "")
		)
		(fill
			(thermal_gap 0.5)
			(thermal_bridge_width 0.5)
			(island_removal_mode 0)
		)
		(polygon
			(pts
				(arc
					(start 206.5782 -262.785352)
					(mid 205.9178 -262.785352)
					(end 206.5782 -262.785352)
				)
			)
		)
	)
	(zone
		(layer "In1.Cu")
		(hatch none 0.5)
		(connect_pads
			(clearance 0)
		)
		(min_thickness 0.25)
		(keepout
			(tracks not_allowed)
			(vias allowed)
			(pads allowed)
			(copperpour not_allowed)
			(footprints allowed)
		)
		(placement
			(enabled no)
			(sheetname "")
		)
		(fill
			(thermal_gap 0.5)
			(thermal_bridge_width 0.5)
			(island_removal_mode 0)
		)
		(polygon
			(pts
				(arc
					(start 52.633372 -240.932462)
					(mid 52.629652 -240.941442)
					(end 52.620672 -240.945162)
				)
				(arc
					(start 51.147472 -240.945162)
					(mid 51.138492 -240.941442)
					(end 51.134772 -240.932462)
				)
				(arc
					(start 51.134772 -240.437924)
					(mid 51.138492 -240.428944)
					(end 51.147472 -240.425224)
				)
				(arc
					(start 52.620672 -240.425224)
					(mid 52.629652 -240.428944)
					(end 52.633372 -240.437924)
				)
			)
		)
	)
	(zone
		(layer "In1.Cu")
		(hatch none 0.5)
		(connect_pads
			(clearance 0)
		)
		(min_thickness 0.25)
		(keepout
			(tracks not_allowed)
			(vias allowed)
			(pads allowed)
			(copperpour not_allowed)
			(footprints allowed)
		)
		(placement
			(enabled no)
			(sheetname "")
		)
		(fill
			(thermal_gap 0.5)
			(thermal_bridge_width 0.5)
			(island_removal_mode 0)
		)
		(polygon
			(pts
				(arc
					(start 304.017426 -295.33215)
					(mid 304.013706 -295.34113)
					(end 304.004726 -295.34485)
				)
				(arc
					(start 302.531526 -295.34485)
					(mid 302.522546 -295.34113)
					(end 302.518826 -295.33215)
				)
				(arc
					(start 302.518826 -294.837612)
					(mid 302.522546 -294.828632)
					(end 302.531526 -294.824912)
				)
				(arc
					(start 304.004726 -294.824912)
					(mid 304.013706 -294.828632)
					(end 304.017426 -294.837612)
				)
			)
		)
	)
	(zone
		(layer "In1.Cu")
		(hatch none 0.5)
		(connect_pads
			(clearance 0)
		)
		(min_thickness 0.25)
		(keepout
			(tracks not_allowed)
			(vias allowed)
			(pads allowed)
			(copperpour not_allowed)
			(footprints allowed)
		)
		(placement
			(enabled no)
			(sheetname "")
		)
		(fill
			(thermal_gap 0.5)
			(thermal_bridge_width 0.5)
			(island_removal_mode 0)
		)
		(polygon
			(pts
				(arc
					(start 202.897232 -248.582434)
					(mid 202.893512 -248.591414)
					(end 202.884532 -248.595134)
				)
				(arc
					(start 201.411332 -248.595134)
					(mid 201.402352 -248.591414)
					(end 201.398632 -248.582434)
				)
				(arc
					(start 201.398632 -248.087896)
					(mid 201.402352 -248.078916)
					(end 201.411332 -248.075196)
				)
				(arc
					(start 202.884532 -248.075196)
					(mid 202.893512 -248.078916)
					(end 202.897232 -248.087896)
				)
			)
		)
	)
	(zone
		(layer "In1.Cu")
		(hatch none 0.5)
		(connect_pads
			(clearance 0)
		)
		(min_thickness 0.25)
		(keepout
			(tracks not_allowed)
			(vias allowed)
			(pads allowed)
			(copperpour not_allowed)
			(footprints allowed)
		)
		(placement
			(enabled no)
			(sheetname "")
		)
		(fill
			(thermal_gap 0.5)
			(thermal_bridge_width 0.5)
			(island_removal_mode 0)
		)
		(polygon
			(pts
				(arc
					(start 417.217352 -200.982326)
					(mid 417.213632 -200.991306)
					(end 417.204652 -200.995026)
				)
				(arc
					(start 415.731452 -200.995026)
					(mid 415.722472 -200.991306)
					(end 415.718752 -200.982326)
				)
				(arc
					(start 415.718752 -200.487788)
					(mid 415.722472 -200.478808)
					(end 415.731452 -200.475088)
				)
				(arc
					(start 417.204652 -200.475088)
					(mid 417.213632 -200.478808)
					(end 417.217352 -200.487788)
				)
			)
		)
	)
	(zone
		(layer "In1.Cu")
		(hatch none 0.5)
		(connect_pads
			(clearance 0)
		)
		(min_thickness 0.25)
		(keepout
			(tracks not_allowed)
			(vias allowed)
			(pads allowed)
			(copperpour not_allowed)
			(footprints allowed)
		)
		(placement
			(enabled no)
			(sheetname "")
		)
		(fill
			(thermal_gap 0.5)
			(thermal_bridge_width 0.5)
			(island_removal_mode 0)
		)
		(polygon
			(pts
				(arc
					(start 439.849514 -239.232186)
					(mid 439.845794 -239.241166)
					(end 439.836814 -239.244886)
				)
				(arc
					(start 438.363614 -239.244886)
					(mid 438.354634 -239.241166)
					(end 438.350914 -239.232186)
				)
				(arc
					(start 438.350914 -238.737648)
					(mid 438.354634 -238.728668)
					(end 438.363614 -238.724948)
				)
				(arc
					(start 439.836814 -238.724948)
					(mid 439.845794 -238.728668)
					(end 439.849514 -238.737648)
				)
			)
		)
	)
	(zone
		(layer "In1.Cu")
		(hatch none 0.5)
		(connect_pads
			(clearance 0)
		)
		(min_thickness 0.25)
		(keepout
			(tracks not_allowed)
			(vias allowed)
			(pads allowed)
			(copperpour not_allowed)
			(footprints allowed)
		)
		(placement
			(enabled no)
			(sheetname "")
		)
		(fill
			(thermal_gap 0.5)
			(thermal_bridge_width 0.5)
			(island_removal_mode 0)
		)
		(polygon
			(pts
				(arc
					(start 158.618682 -383.440686)
					(mid 158.745682 -383.567686)
					(end 158.872682 -383.440686)
				)
				(arc
					(start 158.872682 -383.364486)
					(mid 158.745682 -383.237486)
					(end 158.618682 -383.364486)
				)
			)
		)
	)
	(zone
		(layer "In1.Cu")
		(hatch none 0.5)
		(connect_pads
			(clearance 0)
		)
		(min_thickness 0.25)
		(keepout
			(tracks not_allowed)
			(vias allowed)
			(pads allowed)
			(copperpour not_allowed)
			(footprints allowed)
		)
		(placement
			(enabled no)
			(sheetname "")
		)
		(fill
			(thermal_gap 0.5)
			(thermal_bridge_width 0.5)
			(island_removal_mode 0)
		)
		(polygon
			(pts
				(arc
					(start 270.397478 -251.132086)
					(mid 270.393758 -251.141066)
					(end 270.384778 -251.144786)
				)
				(arc
					(start 268.911578 -251.144786)
					(mid 268.902598 -251.141066)
					(end 268.898878 -251.132086)
				)
				(arc
					(start 268.898878 -250.637548)
					(mid 268.902598 -250.628568)
					(end 268.911578 -250.624848)
				)
				(arc
					(start 270.384778 -250.624848)
					(mid 270.393758 -250.628568)
					(end 270.397478 -250.637548)
				)
			)
		)
	)
	(zone
		(layer "In1.Cu")
		(hatch none 0.5)
		(connect_pads
			(clearance 0)
		)
		(min_thickness 0.25)
		(keepout
			(tracks not_allowed)
			(vias allowed)
			(pads allowed)
			(copperpour not_allowed)
			(footprints allowed)
		)
		(placement
			(enabled no)
			(sheetname "")
		)
		(fill
			(thermal_gap 0.5)
			(thermal_bridge_width 0.5)
			(island_removal_mode 0)
		)
		(polygon
			(pts
				(arc
					(start 40.98925 -226.482402)
					(mid 40.98553 -226.491382)
					(end 40.97655 -226.495102)
				)
				(arc
					(start 39.50335 -226.495102)
					(mid 39.49437 -226.491382)
					(end 39.49065 -226.482402)
				)
				(arc
					(start 39.49065 -225.987864)
					(mid 39.49437 -225.978884)
					(end 39.50335 -225.975164)
				)
				(arc
					(start 40.97655 -225.975164)
					(mid 40.98553 -225.978884)
					(end 40.98925 -225.987864)
				)
			)
		)
	)
	(zone
		(layer "In1.Cu")
		(hatch none 0.5)
		(connect_pads
			(clearance 0)
		)
		(min_thickness 0.25)
		(keepout
			(tracks not_allowed)
			(vias allowed)
			(pads allowed)
			(copperpour not_allowed)
			(footprints allowed)
		)
		(placement
			(enabled no)
			(sheetname "")
		)
		(fill
			(thermal_gap 0.5)
			(thermal_bridge_width 0.5)
			(island_removal_mode 0)
		)
		(polygon
			(pts
				(arc
					(start 149.018752 -391.319258)
					(mid 149.145752 -391.446258)
					(end 149.272752 -391.319258)
				)
				(arc
					(start 149.272752 -391.243058)
					(mid 149.145752 -391.116058)
					(end 149.018752 -391.243058)
				)
			)
		)
	)
	(zone
		(layer "In1.Cu")
		(hatch none 0.5)
		(connect_pads
			(clearance 0)
		)
		(min_thickness 0.25)
		(keepout
			(tracks not_allowed)
			(vias allowed)
			(pads allowed)
			(copperpour not_allowed)
			(footprints allowed)
		)
		(placement
			(enabled no)
			(sheetname "")
		)
		(fill
			(thermal_gap 0.5)
			(thermal_bridge_width 0.5)
			(island_removal_mode 0)
		)
		(polygon
			(pts
				(arc
					(start 90.318844 -391.319258)
					(mid 90.445844 -391.446258)
					(end 90.572844 -391.319258)
				)
				(arc
					(start 90.572844 -391.243058)
					(mid 90.445844 -391.116058)
					(end 90.318844 -391.243058)
				)
			)
		)
	)
	(zone
		(layer "In1.Cu")
		(hatch none 0.5)
		(connect_pads
			(clearance 0)
		)
		(min_thickness 0.25)
		(keepout
			(tracks not_allowed)
			(vias allowed)
			(pads allowed)
			(copperpour not_allowed)
			(footprints allowed)
		)
		(placement
			(enabled no)
			(sheetname "")
		)
		(fill
			(thermal_gap 0.5)
			(thermal_bridge_width 0.5)
			(island_removal_mode 0)
		)
		(polygon
			(pts
				(arc
					(start 206.5782 -309.535322)
					(mid 205.9178 -309.535322)
					(end 206.5782 -309.535322)
				)
			)
		)
	)
	(zone
		(layer "In1.Cu")
		(hatch none 0.5)
		(connect_pads
			(clearance 0)
		)
		(min_thickness 0.25)
		(keepout
			(tracks not_allowed)
			(vias allowed)
			(pads allowed)
			(copperpour not_allowed)
			(footprints allowed)
		)
		(placement
			(enabled no)
			(sheetname "")
		)
		(fill
			(thermal_gap 0.5)
			(thermal_bridge_width 0.5)
			(island_removal_mode 0)
		)
		(polygon
			(pts
				(arc
					(start 131.36118 -388.774432)
					(mid 130.98018 -388.774432)
					(end 131.36118 -388.774432)
				)
			)
		)
	)
	(zone
		(layer "In1.Cu")
		(hatch none 0.5)
		(connect_pads
			(clearance 0)
		)
		(min_thickness 0.25)
		(keepout
			(tracks not_allowed)
			(vias allowed)
			(pads allowed)
			(copperpour not_allowed)
			(footprints allowed)
		)
		(placement
			(enabled no)
			(sheetname "")
		)
		(fill
			(thermal_gap 0.5)
			(thermal_bridge_width 0.5)
			(island_removal_mode 0)
		)
		(polygon
			(pts
				(arc
					(start 25.901396 -285.98241)
					(mid 25.897676 -285.99139)
					(end 25.888696 -285.99511)
				)
				(arc
					(start 24.415496 -285.99511)
					(mid 24.406516 -285.99139)
					(end 24.402796 -285.98241)
				)
				(arc
					(start 24.402796 -285.487872)
					(mid 24.406516 -285.478892)
					(end 24.415496 -285.475172)
				)
				(arc
					(start 25.888696 -285.475172)
					(mid 25.897676 -285.478892)
					(end 25.901396 -285.487872)
				)
			)
		)
	)
	(zone
		(layer "In1.Cu")
		(hatch none 0.5)
		(connect_pads
			(clearance 0)
		)
		(min_thickness 0.25)
		(keepout
			(tracks not_allowed)
			(vias allowed)
			(pads allowed)
			(copperpour not_allowed)
			(footprints allowed)
		)
		(placement
			(enabled no)
			(sheetname "")
		)
		(fill
			(thermal_gap 0.5)
			(thermal_bridge_width 0.5)
			(island_removal_mode 0)
		)
		(polygon
			(pts
				(arc
					(start 45.089318 -281.732482)
					(mid 45.085598 -281.741462)
					(end 45.076618 -281.745182)
				)
				(arc
					(start 43.603418 -281.745182)
					(mid 43.594438 -281.741462)
					(end 43.590718 -281.732482)
				)
				(arc
					(start 43.590718 -281.237944)
					(mid 43.594438 -281.228964)
					(end 43.603418 -281.225244)
				)
				(arc
					(start 45.076618 -281.225244)
					(mid 45.085598 -281.228964)
					(end 45.089318 -281.237944)
				)
			)
		)
	)
	(zone
		(layer "In1.Cu")
		(hatch none 0.5)
		(connect_pads
			(clearance 0)
		)
		(min_thickness 0.25)
		(keepout
			(tracks not_allowed)
			(vias allowed)
			(pads allowed)
			(copperpour not_allowed)
			(footprints allowed)
		)
		(placement
			(enabled no)
			(sheetname "")
		)
		(fill
			(thermal_gap 0.5)
			(thermal_bridge_width 0.5)
			(island_removal_mode 0)
		)
		(polygon
			(pts
				(arc
					(start 48.533304 -285.98241)
					(mid 48.529584 -285.99139)
					(end 48.520604 -285.99511)
				)
				(arc
					(start 47.047404 -285.99511)
					(mid 47.038424 -285.99139)
					(end 47.034704 -285.98241)
				)
				(arc
					(start 47.034704 -285.487872)
					(mid 47.038424 -285.478892)
					(end 47.047404 -285.475172)
				)
				(arc
					(start 48.520604 -285.475172)
					(mid 48.529584 -285.478892)
					(end 48.533304 -285.487872)
				)
			)
		)
	)
	(zone
		(layer "In1.Cu")
		(hatch none 0.5)
		(connect_pads
			(clearance 0)
		)
		(min_thickness 0.25)
		(keepout
			(tracks not_allowed)
			(vias allowed)
			(pads allowed)
			(copperpour not_allowed)
			(footprints allowed)
		)
		(placement
			(enabled no)
			(sheetname "")
		)
		(fill
			(thermal_gap 0.5)
			(thermal_bridge_width 0.5)
			(island_removal_mode 0)
		)
		(polygon
			(pts
				(arc
					(start 191.909446 -229.032562)
					(mid 191.905726 -229.041542)
					(end 191.896746 -229.045262)
				)
				(arc
					(start 190.423546 -229.045262)
					(mid 190.414566 -229.041542)
					(end 190.410846 -229.032562)
				)
				(arc
					(start 190.410846 -228.538024)
					(mid 190.414566 -228.529044)
					(end 190.423546 -228.525324)
				)
				(arc
					(start 191.896746 -228.525324)
					(mid 191.905726 -228.529044)
					(end 191.909446 -228.538024)
				)
			)
		)
	)
	(zone
		(layer "In1.Cu")
		(hatch none 0.5)
		(connect_pads
			(clearance 0)
		)
		(min_thickness 0.25)
		(keepout
			(tracks not_allowed)
			(vias allowed)
			(pads allowed)
			(copperpour not_allowed)
			(footprints allowed)
		)
		(placement
			(enabled no)
			(sheetname "")
		)
		(fill
			(thermal_gap 0.5)
			(thermal_bridge_width 0.5)
			(island_removal_mode 0)
		)
		(polygon
			(pts
				(arc
					(start 202.897232 -295.332404)
					(mid 202.893512 -295.341384)
					(end 202.884532 -295.345104)
				)
				(arc
					(start 201.411332 -295.345104)
					(mid 201.402352 -295.341384)
					(end 201.398632 -295.332404)
				)
				(arc
					(start 201.398632 -294.837866)
					(mid 201.402352 -294.828886)
					(end 201.411332 -294.825166)
				)
				(arc
					(start 202.884532 -294.825166)
					(mid 202.893512 -294.828886)
					(end 202.897232 -294.837866)
				)
			)
		)
	)
	(zone
		(layer "In1.Cu")
		(hatch none 0.5)
		(connect_pads
			(clearance 0)
		)
		(min_thickness 0.25)
		(keepout
			(tracks not_allowed)
			(vias allowed)
			(pads allowed)
			(copperpour not_allowed)
			(footprints allowed)
		)
		(placement
			(enabled no)
			(sheetname "")
		)
		(fill
			(thermal_gap 0.5)
			(thermal_bridge_width 0.5)
			(island_removal_mode 0)
		)
		(polygon
			(pts
				(arc
					(start 191.909446 -219.682568)
					(mid 191.905726 -219.691548)
					(end 191.896746 -219.695268)
				)
				(arc
					(start 190.423546 -219.695268)
					(mid 190.414566 -219.691548)
					(end 190.410846 -219.682568)
				)
				(arc
					(start 190.410846 -219.18803)
					(mid 190.414566 -219.17905)
					(end 190.423546 -219.17533)
				)
				(arc
					(start 191.896746 -219.17533)
					(mid 191.905726 -219.17905)
					(end 191.909446 -219.18803)
				)
			)
		)
	)
	(zone
		(layer "In1.Cu")
		(hatch none 0.5)
		(connect_pads
			(clearance 0)
		)
		(min_thickness 0.25)
		(keepout
			(tracks not_allowed)
			(vias allowed)
			(pads allowed)
			(copperpour not_allowed)
			(footprints allowed)
		)
		(placement
			(enabled no)
			(sheetname "")
		)
		(fill
			(thermal_gap 0.5)
			(thermal_bridge_width 0.5)
			(island_removal_mode 0)
		)
		(polygon
			(pts
				(arc
					(start 435.749446 -235.832142)
					(mid 435.745726 -235.841122)
					(end 435.736746 -235.844842)
				)
				(arc
					(start 434.263546 -235.844842)
					(mid 434.254566 -235.841122)
					(end 434.250846 -235.832142)
				)
				(arc
					(start 434.250846 -235.337604)
					(mid 434.254566 -235.328624)
					(end 434.263546 -235.324904)
				)
				(arc
					(start 435.736746 -235.324904)
					(mid 435.745726 -235.328624)
					(end 435.749446 -235.337604)
				)
			)
		)
	)
	(zone
		(layer "In1.Cu")
		(hatch none 0.5)
		(connect_pads
			(clearance 0)
		)
		(min_thickness 0.25)
		(keepout
			(tracks not_allowed)
			(vias allowed)
			(pads allowed)
			(copperpour not_allowed)
			(footprints allowed)
		)
		(placement
			(enabled no)
			(sheetname "")
		)
		(fill
			(thermal_gap 0.5)
			(thermal_bridge_width 0.5)
			(island_removal_mode 0)
		)
		(polygon
			(pts
				(arc
					(start 30.001464 -295.332404)
					(mid 29.997744 -295.341384)
					(end 29.988764 -295.345104)
				)
				(arc
					(start 28.515564 -295.345104)
					(mid 28.506584 -295.341384)
					(end 28.502864 -295.332404)
				)
				(arc
					(start 28.502864 -294.837866)
					(mid 28.506584 -294.828886)
					(end 28.515564 -294.825166)
				)
				(arc
					(start 29.988764 -294.825166)
					(mid 29.997744 -294.828886)
					(end 30.001464 -294.837866)
				)
			)
		)
	)
	(zone
		(layer "In1.Cu")
		(hatch none 0.5)
		(connect_pads
			(clearance 0)
		)
		(min_thickness 0.25)
		(keepout
			(tracks not_allowed)
			(vias allowed)
			(pads allowed)
			(copperpour not_allowed)
			(footprints allowed)
		)
		(placement
			(enabled no)
			(sheetname "")
		)
		(fill
			(thermal_gap 0.5)
			(thermal_bridge_width 0.5)
			(island_removal_mode 0)
		)
		(polygon
			(pts
				(arc
					(start 120.090946 -383.440686)
					(mid 120.217946 -383.567686)
					(end 120.344946 -383.440686)
				)
				(arc
					(start 120.344946 -383.364486)
					(mid 120.217946 -383.237486)
					(end 120.090946 -383.364486)
				)
			)
		)
	)
	(zone
		(layer "In1.Cu")
		(hatch none 0.5)
		(connect_pads
			(clearance 0)
		)
		(min_thickness 0.25)
		(keepout
			(tracks not_allowed)
			(vias allowed)
			(pads allowed)
			(copperpour not_allowed)
			(footprints allowed)
		)
		(placement
			(enabled no)
			(sheetname "")
		)
		(fill
			(thermal_gap 0.5)
			(thermal_bridge_width 0.5)
			(island_removal_mode 0)
		)
		(polygon
			(pts
				(arc
					(start 176.821338 -212.88248)
					(mid 176.817618 -212.89146)
					(end 176.808638 -212.89518)
				)
				(arc
					(start 175.335438 -212.89518)
					(mid 175.326458 -212.89146)
					(end 175.322738 -212.88248)
				)
				(arc
					(start 175.322738 -212.387942)
					(mid 175.326458 -212.378962)
					(end 175.335438 -212.375242)
				)
				(arc
					(start 176.808638 -212.375242)
					(mid 176.817618 -212.378962)
					(end 176.821338 -212.387942)
				)
			)
		)
	)
	(zone
		(layer "In1.Cu")
		(hatch none 0.5)
		(connect_pads
			(clearance 0)
		)
		(min_thickness 0.25)
		(keepout
			(tracks not_allowed)
			(vias allowed)
			(pads allowed)
			(copperpour not_allowed)
			(footprints allowed)
		)
		(placement
			(enabled no)
			(sheetname "")
		)
		(fill
			(thermal_gap 0.5)
			(thermal_bridge_width 0.5)
			(island_removal_mode 0)
		)
		(polygon
			(pts
				(arc
					(start 308.117494 -272.382234)
					(mid 308.113774 -272.391214)
					(end 308.104794 -272.394934)
				)
				(arc
					(start 306.631594 -272.394934)
					(mid 306.622614 -272.391214)
					(end 306.618894 -272.382234)
				)
				(arc
					(start 306.618894 -271.887696)
					(mid 306.622614 -271.878716)
					(end 306.631594 -271.874996)
				)
				(arc
					(start 308.104794 -271.874996)
					(mid 308.113774 -271.878716)
					(end 308.117494 -271.887696)
				)
			)
		)
	)
	(zone
		(layer "In1.Cu")
		(hatch none 0.5)
		(connect_pads
			(clearance 0)
		)
		(min_thickness 0.25)
		(keepout
			(tracks not_allowed)
			(vias allowed)
			(pads allowed)
			(copperpour not_allowed)
			(footprints allowed)
		)
		(placement
			(enabled no)
			(sheetname "")
		)
		(fill
			(thermal_gap 0.5)
			(thermal_bridge_width 0.5)
			(island_removal_mode 0)
		)
		(polygon
			(pts
				(arc
					(start 169.277284 -236.682534)
					(mid 169.273564 -236.691514)
					(end 169.264584 -236.695234)
				)
				(arc
					(start 167.791384 -236.695234)
					(mid 167.782404 -236.691514)
					(end 167.778684 -236.682534)
				)
				(arc
					(start 167.778684 -236.187996)
					(mid 167.782404 -236.179016)
					(end 167.791384 -236.175296)
				)
				(arc
					(start 169.264584 -236.175296)
					(mid 169.273564 -236.179016)
					(end 169.277284 -236.187996)
				)
			)
		)
	)
	(zone
		(layer "In1.Cu")
		(hatch none 0.5)
		(connect_pads
			(clearance 0)
		)
		(min_thickness 0.25)
		(keepout
			(tracks not_allowed)
			(vias allowed)
			(pads allowed)
			(copperpour not_allowed)
			(footprints allowed)
		)
		(placement
			(enabled no)
			(sheetname "")
		)
		(fill
			(thermal_gap 0.5)
			(thermal_bridge_width 0.5)
			(island_removal_mode 0)
		)
		(polygon
			(pts
				(arc
					(start 325.3105 -379.360684)
					(mid 325.330424 -379.36992)
					(end 325.352156 -379.37313)
				)
				(arc
					(start 325.54672 -379.37313)
					(mid 325.600602 -379.350812)
					(end 325.62292 -379.29693)
				)
				(arc
					(start 325.62292 -378.61113)
					(mid 325.600602 -378.557248)
					(end 325.54672 -378.53493)
				)
				(arc
					(start 325.352156 -378.53493)
					(mid 325.330412 -378.538098)
					(end 325.3105 -378.547376)
				)
				(arc
					(start 325.014336 -378.740162)
					(mid 324.972652 -378.752384)
					(end 324.931024 -378.739908)
				)
				(arc
					(start 324.6374 -378.547376)
					(mid 324.617476 -378.53814)
					(end 324.595744 -378.53493)
				)
				(arc
					(start 324.40118 -378.53493)
					(mid 324.347298 -378.557248)
					(end 324.32498 -378.61113)
				)
				(arc
					(start 324.32498 -379.29693)
					(mid 324.347298 -379.350812)
					(end 324.40118 -379.37313)
				)
				(arc
					(start 324.597014 -379.37313)
					(mid 324.618758 -379.369962)
					(end 324.63867 -379.360684)
				)
				(arc
					(start 324.932294 -379.168152)
					(mid 324.97395 -379.15575)
					(end 325.015606 -379.168152)
				)
			)
		)
	)
	(zone
		(layer "In1.Cu")
		(hatch none 0.5)
		(connect_pads
			(clearance 0)
		)
		(min_thickness 0.25)
		(keepout
			(tracks not_allowed)
			(vias allowed)
			(pads allowed)
			(copperpour not_allowed)
			(footprints allowed)
		)
		(placement
			(enabled no)
			(sheetname "")
		)
		(fill
			(thermal_gap 0.5)
			(thermal_bridge_width 0.5)
			(island_removal_mode 0)
		)
		(polygon
			(pts
				(arc
					(start 420.661338 -285.982156)
					(mid 420.657618 -285.991136)
					(end 420.648638 -285.994856)
				)
				(arc
					(start 419.175438 -285.994856)
					(mid 419.166458 -285.991136)
					(end 419.162738 -285.982156)
				)
				(arc
					(start 419.162738 -285.487618)
					(mid 419.166458 -285.478638)
					(end 419.175438 -285.474918)
				)
				(arc
					(start 420.648638 -285.474918)
					(mid 420.657618 -285.478638)
					(end 420.661338 -285.487618)
				)
			)
		)
	)
	(zone
		(layer "In1.Cu")
		(hatch none 0.5)
		(connect_pads
			(clearance 0)
		)
		(min_thickness 0.25)
		(keepout
			(tracks not_allowed)
			(vias allowed)
			(pads allowed)
			(copperpour not_allowed)
			(footprints allowed)
		)
		(placement
			(enabled no)
			(sheetname "")
		)
		(fill
			(thermal_gap 0.5)
			(thermal_bridge_width 0.5)
			(island_removal_mode 0)
		)
		(polygon
			(pts
				(arc
					(start 277.941532 -261.332218)
					(mid 277.937812 -261.341198)
					(end 277.928832 -261.344918)
				)
				(arc
					(start 276.455632 -261.344918)
					(mid 276.446652 -261.341198)
					(end 276.442932 -261.332218)
				)
				(arc
					(start 276.442932 -260.83768)
					(mid 276.446652 -260.8287)
					(end 276.455632 -260.82498)
				)
				(arc
					(start 277.928832 -260.82498)
					(mid 277.937812 -260.8287)
					(end 277.941532 -260.83768)
				)
			)
		)
	)
	(zone
		(layer "In1.Cu")
		(hatch none 0.5)
		(connect_pads
			(clearance 0)
		)
		(min_thickness 0.25)
		(keepout
			(tracks not_allowed)
			(vias allowed)
			(pads allowed)
			(copperpour not_allowed)
			(footprints allowed)
		)
		(placement
			(enabled no)
			(sheetname "")
		)
		(fill
			(thermal_gap 0.5)
			(thermal_bridge_width 0.5)
			(island_removal_mode 0)
		)
		(polygon
			(pts
				(arc
					(start 22.45741 -266.432538)
					(mid 22.45369 -266.441518)
					(end 22.44471 -266.445238)
				)
				(arc
					(start 20.97151 -266.445238)
					(mid 20.96253 -266.441518)
					(end 20.95881 -266.432538)
				)
				(arc
					(start 20.95881 -265.938)
					(mid 20.96253 -265.92902)
					(end 20.97151 -265.9253)
				)
				(arc
					(start 22.44471 -265.9253)
					(mid 22.45369 -265.92902)
					(end 22.45741 -265.938)
				)
			)
		)
	)
	(zone
		(layer "In1.Cu")
		(hatch none 0.5)
		(connect_pads
			(clearance 0)
		)
		(min_thickness 0.25)
		(keepout
			(tracks not_allowed)
			(vias allowed)
			(pads allowed)
			(copperpour not_allowed)
			(footprints allowed)
		)
		(placement
			(enabled no)
			(sheetname "")
		)
		(fill
			(thermal_gap 0.5)
			(thermal_bridge_width 0.5)
			(island_removal_mode 0)
		)
		(polygon
			(pts
				(arc
					(start 387.361176 -393.69238)
					(mid 386.980176 -393.69238)
					(end 387.361176 -393.69238)
				)
			)
		)
	)
	(zone
		(layer "In1.Cu")
		(hatch none 0.5)
		(connect_pads
			(clearance 0)
		)
		(min_thickness 0.25)
		(keepout
			(tracks not_allowed)
			(vias allowed)
			(pads allowed)
			(copperpour not_allowed)
			(footprints allowed)
		)
		(placement
			(enabled no)
			(sheetname "")
		)
		(fill
			(thermal_gap 0.5)
			(thermal_bridge_width 0.5)
			(island_removal_mode 0)
		)
		(polygon
			(pts
				(arc
					(start 37.545264 -203.532486)
					(mid 37.541544 -203.541466)
					(end 37.532564 -203.545186)
				)
				(arc
					(start 36.059364 -203.545186)
					(mid 36.050384 -203.541466)
					(end 36.046664 -203.532486)
				)
				(arc
					(start 36.046664 -203.037948)
					(mid 36.050384 -203.028968)
					(end 36.059364 -203.025248)
				)
				(arc
					(start 37.532564 -203.025248)
					(mid 37.541544 -203.028968)
					(end 37.545264 -203.037948)
				)
			)
		)
	)
	(zone
		(layer "In1.Cu")
		(hatch none 0.5)
		(connect_pads
			(clearance 0)
		)
		(min_thickness 0.25)
		(keepout
			(tracks not_allowed)
			(vias allowed)
			(pads allowed)
			(copperpour not_allowed)
			(footprints allowed)
		)
		(placement
			(enabled no)
			(sheetname "")
		)
		(fill
			(thermal_gap 0.5)
			(thermal_bridge_width 0.5)
			(island_removal_mode 0)
		)
		(polygon
			(pts
				(arc
					(start 285.485332 -240.932208)
					(mid 285.481612 -240.941188)
					(end 285.472632 -240.944908)
				)
				(arc
					(start 283.999432 -240.944908)
					(mid 283.990452 -240.941188)
					(end 283.986732 -240.932208)
				)
				(arc
					(start 283.986732 -240.43767)
					(mid 283.990452 -240.42869)
					(end 283.999432 -240.42497)
				)
				(arc
					(start 285.472632 -240.42497)
					(mid 285.481612 -240.42869)
					(end 285.485332 -240.43767)
				)
			)
		)
	)
	(zone
		(layer "In1.Cu")
		(hatch none 0.5)
		(connect_pads
			(clearance 0)
		)
		(min_thickness 0.25)
		(keepout
			(tracks not_allowed)
			(vias allowed)
			(pads allowed)
			(copperpour not_allowed)
			(footprints allowed)
		)
		(placement
			(enabled no)
			(sheetname "")
		)
		(fill
			(thermal_gap 0.5)
			(thermal_bridge_width 0.5)
			(island_removal_mode 0)
		)
		(polygon
			(pts
				(arc
					(start 285.485332 -199.282304)
					(mid 285.481612 -199.291284)
					(end 285.472632 -199.295004)
				)
				(arc
					(start 283.999432 -199.295004)
					(mid 283.990452 -199.291284)
					(end 283.986732 -199.282304)
				)
				(arc
					(start 283.986732 -198.787766)
					(mid 283.990452 -198.778786)
					(end 283.999432 -198.775066)
				)
				(arc
					(start 285.472632 -198.775066)
					(mid 285.481612 -198.778786)
					(end 285.485332 -198.787766)
				)
			)
		)
	)
	(zone
		(layer "In1.Cu")
		(hatch none 0.5)
		(connect_pads
			(clearance 0)
		)
		(min_thickness 0.25)
		(keepout
			(tracks not_allowed)
			(vias allowed)
			(pads allowed)
			(copperpour not_allowed)
			(footprints allowed)
		)
		(placement
			(enabled no)
			(sheetname "")
		)
		(fill
			(thermal_gap 0.5)
			(thermal_bridge_width 0.5)
			(island_removal_mode 0)
		)
		(polygon
			(pts
				(arc
					(start 30.001464 -269.832582)
					(mid 29.997744 -269.841562)
					(end 29.988764 -269.845282)
				)
				(arc
					(start 28.515564 -269.845282)
					(mid 28.506584 -269.841562)
					(end 28.502864 -269.832582)
				)
				(arc
					(start 28.502864 -269.338044)
					(mid 28.506584 -269.329064)
					(end 28.515564 -269.325344)
				)
				(arc
					(start 29.988764 -269.325344)
					(mid 29.997744 -269.329064)
					(end 30.001464 -269.338044)
				)
			)
		)
	)
	(zone
		(layer "In1.Cu")
		(hatch none 0.5)
		(connect_pads
			(clearance 0)
		)
		(min_thickness 0.25)
		(keepout
			(tracks not_allowed)
			(vias allowed)
			(pads allowed)
			(copperpour not_allowed)
			(footprints allowed)
		)
		(placement
			(enabled no)
			(sheetname "")
		)
		(fill
			(thermal_gap 0.5)
			(thermal_bridge_width 0.5)
			(island_removal_mode 0)
		)
		(polygon
			(pts
				(arc
					(start 93.58884 -389.467344)
					(mid 93.20784 -389.467344)
					(end 93.58884 -389.467344)
				)
			)
		)
	)
	(zone
		(layer "In1.Cu")
		(hatch none 0.5)
		(connect_pads
			(clearance 0)
		)
		(min_thickness 0.25)
		(keepout
			(tracks not_allowed)
			(vias allowed)
			(pads allowed)
			(copperpour not_allowed)
			(footprints allowed)
		)
		(placement
			(enabled no)
			(sheetname "")
		)
		(fill
			(thermal_gap 0.5)
			(thermal_bridge_width 0.5)
			(island_removal_mode 0)
		)
		(polygon
			(pts
				(arc
					(start 199.4535 -287.682432)
					(mid 199.44978 -287.691412)
					(end 199.4408 -287.695132)
				)
				(arc
					(start 197.9676 -287.695132)
					(mid 197.95862 -287.691412)
					(end 197.9549 -287.682432)
				)
				(arc
					(start 197.9549 -287.187894)
					(mid 197.95862 -287.178914)
					(end 197.9676 -287.175194)
				)
				(arc
					(start 199.4408 -287.175194)
					(mid 199.44978 -287.178914)
					(end 199.4535 -287.187894)
				)
			)
		)
	)
	(zone
		(layer "In1.Cu")
		(hatch none 0.5)
		(connect_pads
			(clearance 0)
		)
		(min_thickness 0.25)
		(keepout
			(tracks not_allowed)
			(vias allowed)
			(pads allowed)
			(copperpour not_allowed)
			(footprints allowed)
		)
		(placement
			(enabled no)
			(sheetname "")
		)
		(fill
			(thermal_gap 0.5)
			(thermal_bridge_width 0.5)
			(island_removal_mode 0)
		)
		(polygon
			(pts
				(arc
					(start 404.289006 -397.156432)
					(mid 403.908006 -397.156432)
					(end 404.289006 -397.156432)
				)
			)
		)
	)
	(zone
		(layer "In1.Cu")
		(hatch none 0.5)
		(connect_pads
			(clearance 0)
		)
		(min_thickness 0.25)
		(keepout
			(tracks not_allowed)
			(vias allowed)
			(pads allowed)
			(copperpour not_allowed)
			(footprints allowed)
		)
		(placement
			(enabled no)
			(sheetname "")
		)
		(fill
			(thermal_gap 0.5)
			(thermal_bridge_width 0.5)
			(island_removal_mode 0)
		)
		(polygon
			(pts
				(arc
					(start 281.385264 -262.182102)
					(mid 281.381544 -262.191082)
					(end 281.372564 -262.194802)
				)
				(arc
					(start 279.899364 -262.194802)
					(mid 279.890384 -262.191082)
					(end 279.886664 -262.182102)
				)
				(arc
					(start 279.886664 -261.687564)
					(mid 279.890384 -261.678584)
					(end 279.899364 -261.674864)
				)
				(arc
					(start 281.372564 -261.674864)
					(mid 281.381544 -261.678584)
					(end 281.385264 -261.687564)
				)
			)
		)
	)
	(zone
		(layer "In1.Cu")
		(hatch none 0.5)
		(connect_pads
			(clearance 0)
		)
		(min_thickness 0.25)
		(keepout
			(tracks not_allowed)
			(vias allowed)
			(pads allowed)
			(copperpour not_allowed)
			(footprints allowed)
		)
		(placement
			(enabled no)
			(sheetname "")
		)
		(fill
			(thermal_gap 0.5)
			(thermal_bridge_width 0.5)
			(island_removal_mode 0)
		)
		(polygon
			(pts
				(arc
					(start 432.30546 -216.28227)
					(mid 432.30174 -216.29125)
					(end 432.29276 -216.29497)
				)
				(arc
					(start 430.81956 -216.29497)
					(mid 430.81058 -216.29125)
					(end 430.80686 -216.28227)
				)
				(arc
					(start 430.80686 -215.787732)
					(mid 430.81058 -215.778752)
					(end 430.81956 -215.775032)
				)
				(arc
					(start 432.29276 -215.775032)
					(mid 432.30174 -215.778752)
					(end 432.30546 -215.787732)
				)
			)
		)
	)
	(zone
		(layer "In1.Cu")
		(hatch none 0.5)
		(connect_pads
			(clearance 0)
		)
		(min_thickness 0.25)
		(keepout
			(tracks not_allowed)
			(vias allowed)
			(pads allowed)
			(copperpour not_allowed)
			(footprints allowed)
		)
		(placement
			(enabled no)
			(sheetname "")
		)
		(fill
			(thermal_gap 0.5)
			(thermal_bridge_width 0.5)
			(island_removal_mode 0)
		)
		(polygon
			(pts
				(arc
					(start 52.633372 -244.332506)
					(mid 52.629652 -244.341486)
					(end 52.620672 -244.345206)
				)
				(arc
					(start 51.147472 -244.345206)
					(mid 51.138492 -244.341486)
					(end 51.134772 -244.332506)
				)
				(arc
					(start 51.134772 -243.837968)
					(mid 51.138492 -243.828988)
					(end 51.147472 -243.825268)
				)
				(arc
					(start 52.620672 -243.825268)
					(mid 52.629652 -243.828988)
					(end 52.633372 -243.837968)
				)
			)
		)
	)
	(zone
		(layer "In1.Cu")
		(hatch none 0.5)
		(connect_pads
			(clearance 0)
		)
		(min_thickness 0.25)
		(keepout
			(tracks not_allowed)
			(vias allowed)
			(pads allowed)
			(copperpour not_allowed)
			(footprints allowed)
		)
		(placement
			(enabled no)
			(sheetname "")
		)
		(fill
			(thermal_gap 0.5)
			(thermal_bridge_width 0.5)
			(island_removal_mode 0)
		)
		(polygon
			(pts
				(arc
					(start 432.30546 -261.332218)
					(mid 432.30174 -261.341198)
					(end 432.29276 -261.344918)
				)
				(arc
					(start 430.81956 -261.344918)
					(mid 430.81058 -261.341198)
					(end 430.80686 -261.332218)
				)
				(arc
					(start 430.80686 -260.83768)
					(mid 430.81058 -260.8287)
					(end 430.81956 -260.82498)
				)
				(arc
					(start 432.29276 -260.82498)
					(mid 432.30174 -260.8287)
					(end 432.30546 -260.83768)
				)
			)
		)
	)
	(zone
		(layer "In1.Cu")
		(hatch none 0.5)
		(connect_pads
			(clearance 0)
		)
		(min_thickness 0.25)
		(keepout
			(tracks not_allowed)
			(vias allowed)
			(pads allowed)
			(copperpour not_allowed)
			(footprints allowed)
		)
		(placement
			(enabled no)
			(sheetname "")
		)
		(fill
			(thermal_gap 0.5)
			(thermal_bridge_width 0.5)
			(island_removal_mode 0)
		)
		(polygon
			(pts
				(arc
					(start 293.029386 -294.482266)
					(mid 293.025666 -294.491246)
					(end 293.016686 -294.494966)
				)
				(arc
					(start 291.543486 -294.494966)
					(mid 291.534506 -294.491246)
					(end 291.530786 -294.482266)
				)
				(arc
					(start 291.530786 -293.987728)
					(mid 291.534506 -293.978748)
					(end 291.543486 -293.975028)
				)
				(arc
					(start 293.016686 -293.975028)
					(mid 293.025666 -293.978748)
					(end 293.029386 -293.987728)
				)
			)
		)
	)
	(zone
		(layer "In1.Cu")
		(hatch none 0.5)
		(connect_pads
			(clearance 0)
		)
		(min_thickness 0.25)
		(keepout
			(tracks not_allowed)
			(vias allowed)
			(pads allowed)
			(copperpour not_allowed)
			(footprints allowed)
		)
		(placement
			(enabled no)
			(sheetname "")
		)
		(fill
			(thermal_gap 0.5)
			(thermal_bridge_width 0.5)
			(island_removal_mode 0)
		)
		(polygon
			(pts
				(arc
					(start 165.488874 -386.003292)
					(mid 165.107874 -386.003292)
					(end 165.488874 -386.003292)
				)
			)
		)
	)
	(zone
		(layer "In1.Cu")
		(hatch none 0.5)
		(connect_pads
			(clearance 0)
		)
		(min_thickness 0.25)
		(keepout
			(tracks not_allowed)
			(vias allowed)
			(pads allowed)
			(copperpour not_allowed)
			(footprints allowed)
		)
		(placement
			(enabled no)
			(sheetname "")
		)
		(fill
			(thermal_gap 0.5)
			(thermal_bridge_width 0.5)
			(island_removal_mode 0)
		)
		(polygon
			(pts
				(arc
					(start 325.334376 -385.243578)
					(mid 325.32514 -385.263502)
					(end 325.32193 -385.285234)
				)
				(arc
					(start 325.32193 -385.479798)
					(mid 325.344248 -385.53368)
					(end 325.39813 -385.555998)
				)
				(arc
					(start 326.08393 -385.555998)
					(mid 326.137812 -385.53368)
					(end 326.16013 -385.479798)
				)
				(arc
					(start 326.16013 -385.285234)
					(mid 326.156962 -385.26349)
					(end 326.147684 -385.243578)
				)
				(arc
					(start 325.954898 -384.947414)
					(mid 325.942676 -384.90573)
					(end 325.955152 -384.864102)
				)
				(arc
					(start 326.147684 -384.570478)
					(mid 326.15692 -384.550554)
					(end 326.16013 -384.528822)
				)
				(arc
					(start 326.16013 -384.334258)
					(mid 326.137812 -384.280376)
					(end 326.08393 -384.258058)
				)
				(arc
					(start 325.39813 -384.258058)
					(mid 325.344248 -384.280376)
					(end 325.32193 -384.334258)
				)
				(arc
					(start 325.32193 -384.530092)
					(mid 325.325098 -384.551836)
					(end 325.334376 -384.571748)
				)
				(arc
					(start 325.526908 -384.865372)
					(mid 325.53931 -384.907028)
					(end 325.526908 -384.948684)
				)
			)
		)
	)
	(zone
		(layer "In1.Cu")
		(hatch none 0.5)
		(connect_pads
			(clearance 0)
		)
		(min_thickness 0.25)
		(keepout
			(tracks not_allowed)
			(vias allowed)
			(pads allowed)
			(copperpour not_allowed)
			(footprints allowed)
		)
		(placement
			(enabled no)
			(sheetname "")
		)
		(fill
			(thermal_gap 0.5)
			(thermal_bridge_width 0.5)
			(island_removal_mode 0)
		)
		(polygon
			(pts
				(arc
					(start 350.388682 -393.69238)
					(mid 350.007682 -393.69238)
					(end 350.388682 -393.69238)
				)
			)
		)
	)
	(zone
		(layer "In1.Cu")
		(hatch none 0.5)
		(connect_pads
			(clearance 0)
		)
		(min_thickness 0.25)
		(keepout
			(tracks not_allowed)
			(vias allowed)
			(pads allowed)
			(copperpour not_allowed)
			(footprints allowed)
		)
		(placement
			(enabled no)
			(sheetname "")
		)
		(fill
			(thermal_gap 0.5)
			(thermal_bridge_width 0.5)
			(island_removal_mode 0)
		)
		(polygon
			(pts
				(arc
					(start 285.485332 -252.832108)
					(mid 285.481612 -252.841088)
					(end 285.472632 -252.844808)
				)
				(arc
					(start 283.999432 -252.844808)
					(mid 283.990452 -252.841088)
					(end 283.986732 -252.832108)
				)
				(arc
					(start 283.986732 -252.33757)
					(mid 283.990452 -252.32859)
					(end 283.999432 -252.32487)
				)
				(arc
					(start 285.472632 -252.32487)
					(mid 285.481612 -252.32859)
					(end 285.485332 -252.33757)
				)
			)
		)
	)
	(zone
		(layer "In1.Cu")
		(hatch none 0.5)
		(connect_pads
			(clearance 0)
		)
		(min_thickness 0.25)
		(keepout
			(tracks not_allowed)
			(vias allowed)
			(pads allowed)
			(copperpour not_allowed)
			(footprints allowed)
		)
		(placement
			(enabled no)
			(sheetname "")
		)
		(fill
			(thermal_gap 0.5)
			(thermal_bridge_width 0.5)
			(island_removal_mode 0)
		)
		(polygon
			(pts
				(arc
					(start 435.749446 -291.932106)
					(mid 435.745726 -291.941086)
					(end 435.736746 -291.944806)
				)
				(arc
					(start 434.263546 -291.944806)
					(mid 434.254566 -291.941086)
					(end 434.250846 -291.932106)
				)
				(arc
					(start 434.250846 -291.437568)
					(mid 434.254566 -291.428588)
					(end 434.263546 -291.424868)
				)
				(arc
					(start 435.736746 -291.424868)
					(mid 435.745726 -291.428588)
					(end 435.749446 -291.437568)
				)
			)
		)
	)
	(zone
		(layer "In1.Cu")
		(hatch none 0.5)
		(connect_pads
			(clearance 0)
		)
		(min_thickness 0.25)
		(keepout
			(tracks not_allowed)
			(vias allowed)
			(pads allowed)
			(copperpour not_allowed)
			(footprints allowed)
		)
		(placement
			(enabled no)
			(sheetname "")
		)
		(fill
			(thermal_gap 0.5)
			(thermal_bridge_width 0.5)
			(island_removal_mode 0)
		)
		(polygon
			(pts
				(arc
					(start 415.198052 -399.143474)
					(mid 414.893252 -399.143474)
					(end 415.198052 -399.143474)
				)
			)
		)
	)
	(zone
		(layer "In1.Cu")
		(hatch none 0.5)
		(connect_pads
			(clearance 0)
		)
		(min_thickness 0.25)
		(keepout
			(tracks not_allowed)
			(vias allowed)
			(pads allowed)
			(copperpour not_allowed)
			(footprints allowed)
		)
		(placement
			(enabled no)
			(sheetname "")
		)
		(fill
			(thermal_gap 0.5)
			(thermal_bridge_width 0.5)
			(island_removal_mode 0)
		)
		(polygon
			(pts
				(arc
					(start 191.909446 -203.532486)
					(mid 191.905726 -203.541466)
					(end 191.896746 -203.545186)
				)
				(arc
					(start 190.423546 -203.545186)
					(mid 190.414566 -203.541466)
					(end 190.410846 -203.532486)
				)
				(arc
					(start 190.410846 -203.037948)
					(mid 190.414566 -203.028968)
					(end 190.423546 -203.025248)
				)
				(arc
					(start 191.896746 -203.025248)
					(mid 191.905726 -203.028968)
					(end 191.909446 -203.037948)
				)
			)
		)
	)
	(zone
		(layer "In1.Cu")
		(hatch none 0.5)
		(connect_pads
			(clearance 0)
		)
		(min_thickness 0.25)
		(keepout
			(tracks not_allowed)
			(vias allowed)
			(pads allowed)
			(copperpour not_allowed)
			(footprints allowed)
		)
		(placement
			(enabled no)
			(sheetname "")
		)
		(fill
			(thermal_gap 0.5)
			(thermal_bridge_width 0.5)
			(island_removal_mode 0)
		)
		(polygon
			(pts
				(arc
					(start 56.077358 -235.832396)
					(mid 56.073638 -235.841376)
					(end 56.064658 -235.845096)
				)
				(arc
					(start 54.591458 -235.845096)
					(mid 54.582478 -235.841376)
					(end 54.578758 -235.832396)
				)
				(arc
					(start 54.578758 -235.337858)
					(mid 54.582478 -235.328878)
					(end 54.591458 -235.325158)
				)
				(arc
					(start 56.064658 -235.325158)
					(mid 56.073638 -235.328878)
					(end 56.077358 -235.337858)
				)
			)
		)
	)
	(zone
		(layer "In1.Cu")
		(hatch none 0.5)
		(connect_pads
			(clearance 0)
		)
		(min_thickness 0.25)
		(keepout
			(tracks not_allowed)
			(vias allowed)
			(pads allowed)
			(copperpour not_allowed)
			(footprints allowed)
		)
		(placement
			(enabled no)
			(sheetname "")
		)
		(fill
			(thermal_gap 0.5)
			(thermal_bridge_width 0.5)
			(island_removal_mode 0)
		)
		(polygon
			(pts
				(arc
					(start 447.393568 -238.382302)
					(mid 447.389848 -238.391282)
					(end 447.380868 -238.395002)
				)
				(arc
					(start 445.907668 -238.395002)
					(mid 445.898688 -238.391282)
					(end 445.894968 -238.382302)
				)
				(arc
					(start 445.894968 -237.887764)
					(mid 445.898688 -237.878784)
					(end 445.907668 -237.875064)
				)
				(arc
					(start 447.380868 -237.875064)
					(mid 447.389848 -237.878784)
					(end 447.393568 -237.887764)
				)
			)
		)
	)
	(zone
		(layer "In1.Cu")
		(hatch none 0.5)
		(connect_pads
			(clearance 0)
		)
		(min_thickness 0.25)
		(keepout
			(tracks not_allowed)
			(vias allowed)
			(pads allowed)
			(copperpour not_allowed)
			(footprints allowed)
		)
		(placement
			(enabled no)
			(sheetname "")
		)
		(fill
			(thermal_gap 0.5)
			(thermal_bridge_width 0.5)
			(island_removal_mode 0)
		)
		(polygon
			(pts
				(arc
					(start 380.891034 -399.701258)
					(mid 381.018034 -399.828258)
					(end 381.145034 -399.701258)
				)
				(arc
					(start 381.145034 -399.625058)
					(mid 381.018034 -399.498058)
					(end 380.891034 -399.625058)
				)
			)
		)
	)
	(zone
		(layer "In1.Cu")
		(hatch none 0.5)
		(connect_pads
			(clearance 0)
		)
		(min_thickness 0.25)
		(keepout
			(tracks not_allowed)
			(vias allowed)
			(pads allowed)
			(copperpour not_allowed)
			(footprints allowed)
		)
		(placement
			(enabled no)
			(sheetname "")
		)
		(fill
			(thermal_gap 0.5)
			(thermal_bridge_width 0.5)
			(island_removal_mode 0)
		)
		(polygon
			(pts
				(arc
					(start 300.57344 -313.182254)
					(mid 300.56972 -313.191234)
					(end 300.56074 -313.194954)
				)
				(arc
					(start 299.08754 -313.194954)
					(mid 299.07856 -313.191234)
					(end 299.07484 -313.182254)
				)
				(arc
					(start 299.07484 -312.687716)
					(mid 299.07856 -312.678736)
					(end 299.08754 -312.675016)
				)
				(arc
					(start 300.56074 -312.675016)
					(mid 300.56972 -312.678736)
					(end 300.57344 -312.687716)
				)
			)
		)
	)
	(zone
		(layer "In1.Cu")
		(hatch none 0.5)
		(connect_pads
			(clearance 0)
		)
		(min_thickness 0.25)
		(keepout
			(tracks not_allowed)
			(vias allowed)
			(pads allowed)
			(copperpour not_allowed)
			(footprints allowed)
		)
		(placement
			(enabled no)
			(sheetname "")
		)
		(fill
			(thermal_gap 0.5)
			(thermal_bridge_width 0.5)
			(island_removal_mode 0)
		)
		(polygon
			(pts
				(arc
					(start 206.9973 -214.582502)
					(mid 206.99358 -214.591482)
					(end 206.9846 -214.595202)
				)
				(arc
					(start 205.5114 -214.595202)
					(mid 205.50242 -214.591482)
					(end 205.4987 -214.582502)
				)
				(arc
					(start 205.4987 -214.087964)
					(mid 205.50242 -214.078984)
					(end 205.5114 -214.075264)
				)
				(arc
					(start 206.9846 -214.075264)
					(mid 206.99358 -214.078984)
					(end 206.9973 -214.087964)
				)
			)
		)
	)
	(zone
		(layer "In1.Cu")
		(hatch none 0.5)
		(connect_pads
			(clearance 0)
		)
		(min_thickness 0.25)
		(keepout
			(tracks not_allowed)
			(vias allowed)
			(pads allowed)
			(copperpour not_allowed)
			(footprints allowed)
		)
		(placement
			(enabled no)
			(sheetname "")
		)
		(fill
			(thermal_gap 0.5)
			(thermal_bridge_width 0.5)
			(island_removal_mode 0)
		)
		(polygon
			(pts
				(arc
					(start 281.385264 -237.532164)
					(mid 281.381544 -237.541144)
					(end 281.372564 -237.544864)
				)
				(arc
					(start 279.899364 -237.544864)
					(mid 279.890384 -237.541144)
					(end 279.886664 -237.532164)
				)
				(arc
					(start 279.886664 -237.037626)
					(mid 279.890384 -237.028646)
					(end 279.899364 -237.024926)
				)
				(arc
					(start 281.372564 -237.024926)
					(mid 281.381544 -237.028646)
					(end 281.385264 -237.037626)
				)
			)
		)
	)
	(zone
		(layer "In1.Cu")
		(hatch none 0.5)
		(connect_pads
			(clearance 0)
		)
		(min_thickness 0.25)
		(keepout
			(tracks not_allowed)
			(vias allowed)
			(pads allowed)
			(copperpour not_allowed)
			(footprints allowed)
		)
		(placement
			(enabled no)
			(sheetname "")
		)
		(fill
			(thermal_gap 0.5)
			(thermal_bridge_width 0.5)
			(island_removal_mode 0)
		)
		(polygon
			(pts
				(arc
					(start 206.5782 -317.185294)
					(mid 205.9178 -317.185294)
					(end 206.5782 -317.185294)
				)
			)
		)
	)
	(zone
		(layer "In1.Cu")
		(hatch none 0.5)
		(connect_pads
			(clearance 0)
		)
		(min_thickness 0.25)
		(keepout
			(tracks not_allowed)
			(vias allowed)
			(pads allowed)
			(copperpour not_allowed)
			(footprints allowed)
		)
		(placement
			(enabled no)
			(sheetname "")
		)
		(fill
			(thermal_gap 0.5)
			(thermal_bridge_width 0.5)
			(island_removal_mode 0)
		)
		(polygon
			(pts
				(arc
					(start 165.177216 -202.682348)
					(mid 165.173496 -202.691328)
					(end 165.164516 -202.695048)
				)
				(arc
					(start 163.691316 -202.695048)
					(mid 163.682336 -202.691328)
					(end 163.678616 -202.682348)
				)
				(arc
					(start 163.678616 -202.18781)
					(mid 163.682336 -202.17883)
					(end 163.691316 -202.17511)
				)
				(arc
					(start 165.164516 -202.17511)
					(mid 165.173496 -202.17883)
					(end 165.177216 -202.18781)
				)
			)
		)
	)
	(zone
		(layer "In1.Cu")
		(hatch none 0.5)
		(connect_pads
			(clearance 0)
		)
		(min_thickness 0.25)
		(keepout
			(tracks not_allowed)
			(vias allowed)
			(pads allowed)
			(copperpour not_allowed)
			(footprints allowed)
		)
		(placement
			(enabled no)
			(sheetname "")
		)
		(fill
			(thermal_gap 0.5)
			(thermal_bridge_width 0.5)
			(island_removal_mode 0)
		)
		(polygon
			(pts
				(arc
					(start 443.2935 -234.13212)
					(mid 443.28978 -234.1411)
					(end 443.2808 -234.14482)
				)
				(arc
					(start 441.8076 -234.14482)
					(mid 441.79862 -234.1411)
					(end 441.7949 -234.13212)
				)
				(arc
					(start 441.7949 -233.637582)
					(mid 441.79862 -233.628602)
					(end 441.8076 -233.624882)
				)
				(arc
					(start 443.2808 -233.624882)
					(mid 443.28978 -233.628602)
					(end 443.2935 -233.637582)
				)
			)
		)
	)
	(zone
		(layer "In1.Cu")
		(hatch none 0.5)
		(connect_pads
			(clearance 0)
		)
		(min_thickness 0.25)
		(keepout
			(tracks not_allowed)
			(vias allowed)
			(pads allowed)
			(copperpour not_allowed)
			(footprints allowed)
		)
		(placement
			(enabled no)
			(sheetname "")
		)
		(fill
			(thermal_gap 0.5)
			(thermal_bridge_width 0.5)
			(island_removal_mode 0)
		)
		(polygon
			(pts
				(arc
					(start 40.98925 -215.432386)
					(mid 40.98553 -215.441366)
					(end 40.97655 -215.445086)
				)
				(arc
					(start 39.50335 -215.445086)
					(mid 39.49437 -215.441366)
					(end 39.49065 -215.432386)
				)
				(arc
					(start 39.49065 -214.937848)
					(mid 39.49437 -214.928868)
					(end 39.50335 -214.925148)
				)
				(arc
					(start 40.97655 -214.925148)
					(mid 40.98553 -214.928868)
					(end 40.98925 -214.937848)
				)
			)
		)
	)
	(zone
		(layer "In1.Cu")
		(hatch none 0.5)
		(connect_pads
			(clearance 0)
		)
		(min_thickness 0.25)
		(keepout
			(tracks not_allowed)
			(vias allowed)
			(pads allowed)
			(copperpour not_allowed)
			(footprints allowed)
		)
		(placement
			(enabled no)
			(sheetname "")
		)
		(fill
			(thermal_gap 0.5)
			(thermal_bridge_width 0.5)
			(island_removal_mode 0)
		)
		(polygon
			(pts
				(arc
					(start 413.117284 -312.332116)
					(mid 413.113564 -312.341096)
					(end 413.104584 -312.344816)
				)
				(arc
					(start 411.631384 -312.344816)
					(mid 411.622404 -312.341096)
					(end 411.618684 -312.332116)
				)
				(arc
					(start 411.618684 -311.837578)
					(mid 411.622404 -311.828598)
					(end 411.631384 -311.824878)
				)
				(arc
					(start 413.104584 -311.824878)
					(mid 413.113564 -311.828598)
					(end 413.117284 -311.837578)
				)
			)
		)
	)
	(zone
		(layer "In1.Cu")
		(hatch none 0.5)
		(connect_pads
			(clearance 0)
		)
		(min_thickness 0.25)
		(keepout
			(tracks not_allowed)
			(vias allowed)
			(pads allowed)
			(copperpour not_allowed)
			(footprints allowed)
		)
		(placement
			(enabled no)
			(sheetname "")
		)
		(fill
			(thermal_gap 0.5)
			(thermal_bridge_width 0.5)
			(island_removal_mode 0)
		)
		(polygon
			(pts
				(arc
					(start 432.30546 -272.382234)
					(mid 432.30174 -272.391214)
					(end 432.29276 -272.394934)
				)
				(arc
					(start 430.81956 -272.394934)
					(mid 430.81058 -272.391214)
					(end 430.80686 -272.382234)
				)
				(arc
					(start 430.80686 -271.887696)
					(mid 430.81058 -271.878716)
					(end 430.81956 -271.874996)
				)
				(arc
					(start 432.29276 -271.874996)
					(mid 432.30174 -271.878716)
					(end 432.30546 -271.887696)
				)
			)
		)
	)
	(zone
		(layer "In1.Cu")
		(hatch none 0.5)
		(connect_pads
			(clearance 0)
		)
		(min_thickness 0.25)
		(keepout
			(tracks not_allowed)
			(vias allowed)
			(pads allowed)
			(copperpour not_allowed)
			(footprints allowed)
		)
		(placement
			(enabled no)
			(sheetname "")
		)
		(fill
			(thermal_gap 0.5)
			(thermal_bridge_width 0.5)
			(island_removal_mode 0)
		)
		(polygon
			(pts
				(arc
					(start 195.353432 -250.282456)
					(mid 195.349712 -250.291436)
					(end 195.340732 -250.295156)
				)
				(arc
					(start 193.867532 -250.295156)
					(mid 193.858552 -250.291436)
					(end 193.854832 -250.282456)
				)
				(arc
					(start 193.854832 -249.787918)
					(mid 193.858552 -249.778938)
					(end 193.867532 -249.775218)
				)
				(arc
					(start 195.340732 -249.775218)
					(mid 195.349712 -249.778938)
					(end 195.353432 -249.787918)
				)
			)
		)
	)
	(zone
		(layer "In1.Cu")
		(hatch none 0.5)
		(connect_pads
			(clearance 0)
		)
		(min_thickness 0.25)
		(keepout
			(tracks not_allowed)
			(vias allowed)
			(pads allowed)
			(copperpour not_allowed)
			(footprints allowed)
		)
		(placement
			(enabled no)
			(sheetname "")
		)
		(fill
			(thermal_gap 0.5)
			(thermal_bridge_width 0.5)
			(island_removal_mode 0)
		)
		(polygon
			(pts
				(arc
					(start 382.961134 -397.849344)
					(mid 382.580134 -397.849344)
					(end 382.961134 -397.849344)
				)
			)
		)
	)
	(zone
		(layer "In1.Cu")
		(hatch none 0.5)
		(connect_pads
			(clearance 0)
		)
		(min_thickness 0.25)
		(keepout
			(tracks not_allowed)
			(vias allowed)
			(pads allowed)
			(copperpour not_allowed)
			(footprints allowed)
		)
		(placement
			(enabled no)
			(sheetname "")
		)
		(fill
			(thermal_gap 0.5)
			(thermal_bridge_width 0.5)
			(island_removal_mode 0)
		)
		(polygon
			(pts
				(arc
					(start 206.9973 -294.48252)
					(mid 206.99358 -294.4915)
					(end 206.9846 -294.49522)
				)
				(arc
					(start 205.5114 -294.49522)
					(mid 205.50242 -294.4915)
					(end 205.4987 -294.48252)
				)
				(arc
					(start 205.4987 -293.987982)
					(mid 205.50242 -293.979002)
					(end 205.5114 -293.975282)
				)
				(arc
					(start 206.9846 -293.975282)
					(mid 206.99358 -293.979002)
					(end 206.9973 -293.987982)
				)
			)
		)
	)
	(zone
		(layer "In1.Cu")
		(hatch none 0.5)
		(connect_pads
			(clearance 0)
		)
		(min_thickness 0.25)
		(keepout
			(tracks not_allowed)
			(vias allowed)
			(pads allowed)
			(copperpour not_allowed)
			(footprints allowed)
		)
		(placement
			(enabled no)
			(sheetname "")
		)
		(fill
			(thermal_gap 0.5)
			(thermal_bridge_width 0.5)
			(island_removal_mode 0)
		)
		(polygon
			(pts
				(arc
					(start 147.089114 -388.774432)
					(mid 146.708114 -388.774432)
					(end 147.089114 -388.774432)
				)
			)
		)
	)
	(zone
		(layer "In1.Cu")
		(hatch none 0.5)
		(connect_pads
			(clearance 0)
		)
		(min_thickness 0.25)
		(keepout
			(tracks not_allowed)
			(vias allowed)
			(pads allowed)
			(copperpour not_allowed)
			(footprints allowed)
		)
		(placement
			(enabled no)
			(sheetname "")
		)
		(fill
			(thermal_gap 0.5)
			(thermal_bridge_width 0.5)
			(island_removal_mode 0)
		)
		(polygon
			(pts
				(arc
					(start 48.533304 -209.482436)
					(mid 48.529584 -209.491416)
					(end 48.520604 -209.495136)
				)
				(arc
					(start 47.047404 -209.495136)
					(mid 47.038424 -209.491416)
					(end 47.034704 -209.482436)
				)
				(arc
					(start 47.034704 -208.987898)
					(mid 47.038424 -208.978918)
					(end 47.047404 -208.975198)
				)
				(arc
					(start 48.520604 -208.975198)
					(mid 48.529584 -208.978918)
					(end 48.533304 -208.987898)
				)
			)
		)
	)
	(zone
		(layer "In1.Cu")
		(hatch none 0.5)
		(connect_pads
			(clearance 0)
		)
		(min_thickness 0.25)
		(keepout
			(tracks not_allowed)
			(vias allowed)
			(pads allowed)
			(copperpour not_allowed)
			(footprints allowed)
		)
		(placement
			(enabled no)
			(sheetname "")
		)
		(fill
			(thermal_gap 0.5)
			(thermal_bridge_width 0.5)
			(island_removal_mode 0)
		)
		(polygon
			(pts
				(arc
					(start 187.809378 -310.632348)
					(mid 187.805658 -310.641328)
					(end 187.796678 -310.645048)
				)
				(arc
					(start 186.323478 -310.645048)
					(mid 186.314498 -310.641328)
					(end 186.310778 -310.632348)
				)
				(arc
					(start 186.310778 -310.13781)
					(mid 186.314498 -310.12883)
					(end 186.323478 -310.12511)
				)
				(arc
					(start 187.796678 -310.12511)
					(mid 187.805658 -310.12883)
					(end 187.809378 -310.13781)
				)
			)
		)
	)
	(zone
		(layer "In1.Cu")
		(hatch none 0.5)
		(connect_pads
			(clearance 0)
		)
		(min_thickness 0.25)
		(keepout
			(tracks not_allowed)
			(vias allowed)
			(pads allowed)
			(copperpour not_allowed)
			(footprints allowed)
		)
		(placement
			(enabled no)
			(sheetname "")
		)
		(fill
			(thermal_gap 0.5)
			(thermal_bridge_width 0.5)
			(island_removal_mode 0)
		)
		(polygon
			(pts
				(arc
					(start 273.841464 -297.88231)
					(mid 273.837744 -297.89129)
					(end 273.828764 -297.89501)
				)
				(arc
					(start 272.355564 -297.89501)
					(mid 272.346584 -297.89129)
					(end 272.342864 -297.88231)
				)
				(arc
					(start 272.342864 -297.387772)
					(mid 272.346584 -297.378792)
					(end 272.355564 -297.375072)
				)
				(arc
					(start 273.828764 -297.375072)
					(mid 273.837744 -297.378792)
					(end 273.841464 -297.387772)
				)
			)
		)
	)
	(zone
		(layer "In1.Cu")
		(hatch none 0.5)
		(connect_pads
			(clearance 0)
		)
		(min_thickness 0.25)
		(keepout
			(tracks not_allowed)
			(vias allowed)
			(pads allowed)
			(copperpour not_allowed)
			(footprints allowed)
		)
		(placement
			(enabled no)
			(sheetname "")
		)
		(fill
			(thermal_gap 0.5)
			(thermal_bridge_width 0.5)
			(island_removal_mode 0)
		)
		(polygon
			(pts
				(arc
					(start 353.51847 -391.822686)
					(mid 353.64547 -391.949686)
					(end 353.77247 -391.822686)
				)
				(arc
					(start 353.77247 -391.746486)
					(mid 353.64547 -391.619486)
					(end 353.51847 -391.746486)
				)
			)
		)
	)
	(zone
		(layer "In1.Cu")
		(hatch none 0.5)
		(connect_pads
			(clearance 0)
		)
		(min_thickness 0.25)
		(keepout
			(tracks not_allowed)
			(vias allowed)
			(pads allowed)
			(copperpour not_allowed)
			(footprints allowed)
		)
		(placement
			(enabled no)
			(sheetname "")
		)
		(fill
			(thermal_gap 0.5)
			(thermal_bridge_width 0.5)
			(island_removal_mode 0)
		)
		(polygon
			(pts
				(arc
					(start 195.353432 -316.582552)
					(mid 195.349712 -316.591532)
					(end 195.340732 -316.595252)
				)
				(arc
					(start 193.867532 -316.595252)
					(mid 193.858552 -316.591532)
					(end 193.854832 -316.582552)
				)
				(arc
					(start 193.854832 -316.088014)
					(mid 193.858552 -316.079034)
					(end 193.867532 -316.075314)
				)
				(arc
					(start 195.340732 -316.075314)
					(mid 195.349712 -316.079034)
					(end 195.353432 -316.088014)
				)
			)
		)
	)
	(zone
		(layer "In1.Cu")
		(hatch none 0.5)
		(connect_pads
			(clearance 0)
		)
		(min_thickness 0.25)
		(keepout
			(tracks not_allowed)
			(vias allowed)
			(pads allowed)
			(copperpour not_allowed)
			(footprints allowed)
		)
		(placement
			(enabled no)
			(sheetname "")
		)
		(fill
			(thermal_gap 0.5)
			(thermal_bridge_width 0.5)
			(island_removal_mode 0)
		)
		(polygon
			(pts
				(arc
					(start 184.365392 -233.28249)
					(mid 184.361672 -233.29147)
					(end 184.352692 -233.29519)
				)
				(arc
					(start 182.879492 -233.29519)
					(mid 182.870512 -233.29147)
					(end 182.866792 -233.28249)
				)
				(arc
					(start 182.866792 -232.787952)
					(mid 182.870512 -232.778972)
					(end 182.879492 -232.775252)
				)
				(arc
					(start 184.352692 -232.775252)
					(mid 184.361672 -232.778972)
					(end 184.365392 -232.787952)
				)
			)
		)
	)
	(zone
		(layer "In1.Cu")
		(hatch none 0.5)
		(connect_pads
			(clearance 0)
		)
		(min_thickness 0.25)
		(keepout
			(tracks not_allowed)
			(vias allowed)
			(pads allowed)
			(copperpour not_allowed)
			(footprints allowed)
		)
		(placement
			(enabled no)
			(sheetname "")
		)
		(fill
			(thermal_gap 0.5)
			(thermal_bridge_width 0.5)
			(island_removal_mode 0)
		)
		(polygon
			(pts
				(arc
					(start 273.841464 -202.682094)
					(mid 273.837744 -202.691074)
					(end 273.828764 -202.694794)
				)
				(arc
					(start 272.355564 -202.694794)
					(mid 272.346584 -202.691074)
					(end 272.342864 -202.682094)
				)
				(arc
					(start 272.342864 -202.187556)
					(mid 272.346584 -202.178576)
					(end 272.355564 -202.174856)
				)
				(arc
					(start 273.828764 -202.174856)
					(mid 273.837744 -202.178576)
					(end 273.841464 -202.187556)
				)
			)
		)
	)
	(zone
		(layer "In1.Cu")
		(hatch none 0.5)
		(connect_pads
			(clearance 0)
		)
		(min_thickness 0.25)
		(keepout
			(tracks not_allowed)
			(vias allowed)
			(pads allowed)
			(copperpour not_allowed)
			(footprints allowed)
		)
		(placement
			(enabled no)
			(sheetname "")
		)
		(fill
			(thermal_gap 0.5)
			(thermal_bridge_width 0.5)
			(island_removal_mode 0)
		)
		(polygon
			(pts
				(arc
					(start 195.353432 -230.732584)
					(mid 195.349712 -230.741564)
					(end 195.340732 -230.745284)
				)
				(arc
					(start 193.867532 -230.745284)
					(mid 193.858552 -230.741564)
					(end 193.854832 -230.732584)
				)
				(arc
					(start 193.854832 -230.238046)
					(mid 193.858552 -230.229066)
					(end 193.867532 -230.225346)
				)
				(arc
					(start 195.340732 -230.225346)
					(mid 195.349712 -230.229066)
					(end 195.353432 -230.238046)
				)
			)
		)
	)
	(zone
		(layer "In1.Cu")
		(hatch none 0.5)
		(connect_pads
			(clearance 0)
		)
		(min_thickness 0.25)
		(keepout
			(tracks not_allowed)
			(vias allowed)
			(pads allowed)
			(copperpour not_allowed)
			(footprints allowed)
		)
		(placement
			(enabled no)
			(sheetname "")
		)
		(fill
			(thermal_gap 0.5)
			(thermal_bridge_width 0.5)
			(island_removal_mode 0)
		)
		(polygon
			(pts
				(arc
					(start 270.397478 -199.282304)
					(mid 270.393758 -199.291284)
					(end 270.384778 -199.295004)
				)
				(arc
					(start 268.911578 -199.295004)
					(mid 268.902598 -199.291284)
					(end 268.898878 -199.282304)
				)
				(arc
					(start 268.898878 -198.787766)
					(mid 268.902598 -198.778786)
					(end 268.911578 -198.775066)
				)
				(arc
					(start 270.384778 -198.775066)
					(mid 270.393758 -198.778786)
					(end 270.397478 -198.787766)
				)
			)
		)
	)
	(zone
		(layer "In1.Cu")
		(hatch none 0.5)
		(connect_pads
			(clearance 0)
		)
		(min_thickness 0.25)
		(keepout
			(tracks not_allowed)
			(vias allowed)
			(pads allowed)
			(copperpour not_allowed)
			(footprints allowed)
		)
		(placement
			(enabled no)
			(sheetname "")
		)
		(fill
			(thermal_gap 0.5)
			(thermal_bridge_width 0.5)
			(island_removal_mode 0)
		)
		(polygon
			(pts
				(arc
					(start 376.56135 -397.156432)
					(mid 376.18035 -397.156432)
					(end 376.56135 -397.156432)
				)
			)
		)
	)
	(zone
		(layer "In1.Cu")
		(hatch none 0.5)
		(connect_pads
			(clearance 0)
		)
		(min_thickness 0.25)
		(keepout
			(tracks not_allowed)
			(vias allowed)
			(pads allowed)
			(copperpour not_allowed)
			(footprints allowed)
		)
		(placement
			(enabled no)
			(sheetname "")
		)
		(fill
			(thermal_gap 0.5)
			(thermal_bridge_width 0.5)
			(island_removal_mode 0)
		)
		(polygon
			(pts
				(arc
					(start 135.95985 -36.962334)
					(mid 135.905968 -36.940016)
					(end 135.88365 -36.886134)
				)
				(arc
					(start 135.88365 -36.460684)
					(mid 135.905968 -36.406802)
					(end 135.95985 -36.384484)
				)
				(arc
					(start 137.12825 -36.384484)
					(mid 137.182132 -36.406802)
					(end 137.20445 -36.460684)
				)
				(arc
					(start 137.20445 -36.886134)
					(mid 137.182132 -36.940016)
					(end 137.12825 -36.962334)
				)
			)
		)
	)
	(zone
		(layer "In1.Cu")
		(hatch none 0.5)
		(connect_pads
			(clearance 0)
		)
		(min_thickness 0.25)
		(keepout
			(tracks not_allowed)
			(vias allowed)
			(pads allowed)
			(copperpour not_allowed)
			(footprints allowed)
		)
		(placement
			(enabled no)
			(sheetname "")
		)
		(fill
			(thermal_gap 0.5)
			(thermal_bridge_width 0.5)
			(island_removal_mode 0)
		)
		(polygon
			(pts
				(arc
					(start 273.841464 -254.53213)
					(mid 273.837744 -254.54111)
					(end 273.828764 -254.54483)
				)
				(arc
					(start 272.355564 -254.54483)
					(mid 272.346584 -254.54111)
					(end 272.342864 -254.53213)
				)
				(arc
					(start 272.342864 -254.037592)
					(mid 272.346584 -254.028612)
					(end 272.355564 -254.024892)
				)
				(arc
					(start 273.828764 -254.024892)
					(mid 273.837744 -254.028612)
					(end 273.841464 -254.037592)
				)
			)
		)
	)
	(zone
		(layer "In1.Cu")
		(hatch none 0.5)
		(connect_pads
			(clearance 0)
		)
		(min_thickness 0.25)
		(keepout
			(tracks not_allowed)
			(vias allowed)
			(pads allowed)
			(copperpour not_allowed)
			(footprints allowed)
		)
		(placement
			(enabled no)
			(sheetname "")
		)
		(fill
			(thermal_gap 0.5)
			(thermal_bridge_width 0.5)
			(island_removal_mode 0)
		)
		(polygon
			(pts
				(arc
					(start 165.177216 -254.532384)
					(mid 165.173496 -254.541364)
					(end 165.164516 -254.545084)
				)
				(arc
					(start 163.691316 -254.545084)
					(mid 163.682336 -254.541364)
					(end 163.678616 -254.532384)
				)
				(arc
					(start 163.678616 -254.037846)
					(mid 163.682336 -254.028866)
					(end 163.691316 -254.025146)
				)
				(arc
					(start 165.164516 -254.025146)
					(mid 165.173496 -254.028866)
					(end 165.177216 -254.037846)
				)
			)
		)
	)
	(zone
		(layer "In1.Cu")
		(hatch none 0.5)
		(connect_pads
			(clearance 0)
		)
		(min_thickness 0.25)
		(keepout
			(tracks not_allowed)
			(vias allowed)
			(pads allowed)
			(copperpour not_allowed)
			(footprints allowed)
		)
		(placement
			(enabled no)
			(sheetname "")
		)
		(fill
			(thermal_gap 0.5)
			(thermal_bridge_width 0.5)
			(island_removal_mode 0)
		)
		(polygon
			(pts
				(arc
					(start 406.218644 -391.822686)
					(mid 406.345644 -391.949686)
					(end 406.472644 -391.822686)
				)
				(arc
					(start 406.472644 -391.746486)
					(mid 406.345644 -391.619486)
					(end 406.218644 -391.746486)
				)
			)
		)
	)
	(zone
		(layer "In1.Cu")
		(hatch none 0.5)
		(connect_pads
			(clearance 0)
		)
		(min_thickness 0.25)
		(keepout
			(tracks not_allowed)
			(vias allowed)
			(pads allowed)
			(copperpour not_allowed)
			(footprints allowed)
		)
		(placement
			(enabled no)
			(sheetname "")
		)
		(fill
			(thermal_gap 0.5)
			(thermal_bridge_width 0.5)
			(island_removal_mode 0)
		)
		(polygon
			(pts
				(arc
					(start 176.821338 -247.73255)
					(mid 176.817618 -247.74153)
					(end 176.808638 -247.74525)
				)
				(arc
					(start 175.335438 -247.74525)
					(mid 175.326458 -247.74153)
					(end 175.322738 -247.73255)
				)
				(arc
					(start 175.322738 -247.238012)
					(mid 175.326458 -247.229032)
					(end 175.335438 -247.225312)
				)
				(arc
					(start 176.808638 -247.225312)
					(mid 176.817618 -247.229032)
					(end 176.821338 -247.238012)
				)
			)
		)
	)
	(zone
		(layer "In1.Cu")
		(hatch none 0.5)
		(connect_pads
			(clearance 0)
		)
		(min_thickness 0.25)
		(keepout
			(tracks not_allowed)
			(vias allowed)
			(pads allowed)
			(copperpour not_allowed)
			(footprints allowed)
		)
		(placement
			(enabled no)
			(sheetname "")
		)
		(fill
			(thermal_gap 0.5)
			(thermal_bridge_width 0.5)
			(island_removal_mode 0)
		)
		(polygon
			(pts
				(arc
					(start 277.941532 -308.082188)
					(mid 277.937812 -308.091168)
					(end 277.928832 -308.094888)
				)
				(arc
					(start 276.455632 -308.094888)
					(mid 276.446652 -308.091168)
					(end 276.442932 -308.082188)
				)
				(arc
					(start 276.442932 -307.58765)
					(mid 276.446652 -307.57867)
					(end 276.455632 -307.57495)
				)
				(arc
					(start 277.928832 -307.57495)
					(mid 277.937812 -307.57867)
					(end 277.941532 -307.58765)
				)
			)
		)
	)
	(zone
		(layer "In1.Cu")
		(hatch none 0.5)
		(connect_pads
			(clearance 0)
		)
		(min_thickness 0.25)
		(keepout
			(tracks not_allowed)
			(vias allowed)
			(pads allowed)
			(copperpour not_allowed)
			(footprints allowed)
		)
		(placement
			(enabled no)
			(sheetname "")
		)
		(fill
			(thermal_gap 0.5)
			(thermal_bridge_width 0.5)
			(island_removal_mode 0)
		)
		(polygon
			(pts
				(arc
					(start 18.357342 -204.38237)
					(mid 18.353622 -204.39135)
					(end 18.344642 -204.39507)
				)
				(arc
					(start 16.871442 -204.39507)
					(mid 16.862462 -204.39135)
					(end 16.858742 -204.38237)
				)
				(arc
					(start 16.858742 -203.887832)
					(mid 16.862462 -203.878852)
					(end 16.871442 -203.875132)
				)
				(arc
					(start 18.344642 -203.875132)
					(mid 18.353622 -203.878852)
					(end 18.357342 -203.887832)
				)
			)
		)
	)
	(zone
		(layer "In1.Cu")
		(hatch none 0.5)
		(connect_pads
			(clearance 0)
		)
		(min_thickness 0.25)
		(keepout
			(tracks not_allowed)
			(vias allowed)
			(pads allowed)
			(copperpour not_allowed)
			(footprints allowed)
		)
		(placement
			(enabled no)
			(sheetname "")
		)
		(fill
			(thermal_gap 0.5)
			(thermal_bridge_width 0.5)
			(island_removal_mode 0)
		)
		(polygon
			(pts
				(arc
					(start 417.217352 -298.732194)
					(mid 417.213632 -298.741174)
					(end 417.204652 -298.744894)
				)
				(arc
					(start 415.731452 -298.744894)
					(mid 415.722472 -298.741174)
					(end 415.718752 -298.732194)
				)
				(arc
					(start 415.718752 -298.237656)
					(mid 415.722472 -298.228676)
					(end 415.731452 -298.224956)
				)
				(arc
					(start 417.204652 -298.224956)
					(mid 417.213632 -298.228676)
					(end 417.217352 -298.237656)
				)
			)
		)
	)
	(zone
		(layer "In1.Cu")
		(hatch none 0.5)
		(connect_pads
			(clearance 0)
		)
		(min_thickness 0.25)
		(keepout
			(tracks not_allowed)
			(vias allowed)
			(pads allowed)
			(copperpour not_allowed)
			(footprints allowed)
		)
		(placement
			(enabled no)
			(sheetname "")
		)
		(fill
			(thermal_gap 0.5)
			(thermal_bridge_width 0.5)
			(island_removal_mode 0)
		)
		(polygon
			(pts
				(arc
					(start 153.488898 -389.467344)
					(mid 153.107898 -389.467344)
					(end 153.488898 -389.467344)
				)
			)
		)
	)
	(zone
		(layer "In1.Cu")
		(hatch none 0.5)
		(connect_pads
			(clearance 0)
		)
		(min_thickness 0.25)
		(keepout
			(tracks not_allowed)
			(vias allowed)
			(pads allowed)
			(copperpour not_allowed)
			(footprints allowed)
		)
		(placement
			(enabled no)
			(sheetname "")
		)
		(fill
			(thermal_gap 0.5)
			(thermal_bridge_width 0.5)
			(island_removal_mode 0)
		)
		(polygon
			(pts
				(arc
					(start 379.360938 -397.849344)
					(mid 378.979938 -397.849344)
					(end 379.360938 -397.849344)
				)
			)
		)
	)
	(zone
		(layer "In1.Cu")
		(hatch none 0.5)
		(connect_pads
			(clearance 0)
		)
		(min_thickness 0.25)
		(keepout
			(tracks not_allowed)
			(vias allowed)
			(pads allowed)
			(copperpour not_allowed)
			(footprints allowed)
		)
		(placement
			(enabled no)
			(sheetname "")
		)
		(fill
			(thermal_gap 0.5)
			(thermal_bridge_width 0.5)
			(island_removal_mode 0)
		)
		(polygon
			(pts
				(arc
					(start 285.485332 -315.73216)
					(mid 285.481612 -315.74114)
					(end 285.472632 -315.74486)
				)
				(arc
					(start 283.999432 -315.74486)
					(mid 283.990452 -315.74114)
					(end 283.986732 -315.73216)
				)
				(arc
					(start 283.986732 -315.237622)
					(mid 283.990452 -315.228642)
					(end 283.999432 -315.224922)
				)
				(arc
					(start 285.472632 -315.224922)
					(mid 285.481612 -315.228642)
					(end 285.485332 -315.237622)
				)
			)
		)
	)
	(zone
		(layer "In1.Cu")
		(hatch none 0.5)
		(connect_pads
			(clearance 0)
		)
		(min_thickness 0.25)
		(keepout
			(tracks not_allowed)
			(vias allowed)
			(pads allowed)
			(copperpour not_allowed)
			(footprints allowed)
		)
		(placement
			(enabled no)
			(sheetname "")
		)
		(fill
			(thermal_gap 0.5)
			(thermal_bridge_width 0.5)
			(island_removal_mode 0)
		)
		(polygon
			(pts
				(arc
					(start 202.897232 -307.232558)
					(mid 202.893512 -307.241538)
					(end 202.884532 -307.245258)
				)
				(arc
					(start 201.411332 -307.245258)
					(mid 201.402352 -307.241538)
					(end 201.398632 -307.232558)
				)
				(arc
					(start 201.398632 -306.73802)
					(mid 201.402352 -306.72904)
					(end 201.411332 -306.72532)
				)
				(arc
					(start 202.884532 -306.72532)
					(mid 202.893512 -306.72904)
					(end 202.897232 -306.73802)
				)
			)
		)
	)
	(zone
		(layer "In1.Cu")
		(hatch none 0.5)
		(connect_pads
			(clearance 0)
		)
		(min_thickness 0.25)
		(keepout
			(tracks not_allowed)
			(vias allowed)
			(pads allowed)
			(copperpour not_allowed)
			(footprints allowed)
		)
		(placement
			(enabled no)
			(sheetname "")
		)
		(fill
			(thermal_gap 0.5)
			(thermal_bridge_width 0.5)
			(island_removal_mode 0)
		)
		(polygon
			(pts
				(arc
					(start 304.017426 -232.432098)
					(mid 304.013706 -232.441078)
					(end 304.004726 -232.444798)
				)
				(arc
					(start 302.531526 -232.444798)
					(mid 302.522546 -232.441078)
					(end 302.518826 -232.432098)
				)
				(arc
					(start 302.518826 -231.93756)
					(mid 302.522546 -231.92858)
					(end 302.531526 -231.92486)
				)
				(arc
					(start 304.004726 -231.92486)
					(mid 304.013706 -231.92858)
					(end 304.017426 -231.93756)
				)
			)
		)
	)
	(zone
		(layer "In1.Cu")
		(hatch none 0.5)
		(connect_pads
			(clearance 0)
		)
		(min_thickness 0.25)
		(keepout
			(tracks not_allowed)
			(vias allowed)
			(pads allowed)
			(copperpour not_allowed)
			(footprints allowed)
		)
		(placement
			(enabled no)
			(sheetname "")
		)
		(fill
			(thermal_gap 0.5)
			(thermal_bridge_width 0.5)
			(island_removal_mode 0)
		)
		(polygon
			(pts
				(arc
					(start 154.288998 -388.774432)
					(mid 153.907998 -388.774432)
					(end 154.288998 -388.774432)
				)
			)
		)
	)
	(zone
		(layer "In1.Cu")
		(hatch none 0.5)
		(connect_pads
			(clearance 0)
		)
		(min_thickness 0.25)
		(keepout
			(tracks not_allowed)
			(vias allowed)
			(pads allowed)
			(copperpour not_allowed)
			(footprints allowed)
		)
		(placement
			(enabled no)
			(sheetname "")
		)
		(fill
			(thermal_gap 0.5)
			(thermal_bridge_width 0.5)
			(island_removal_mode 0)
		)
		(polygon
			(pts
				(arc
					(start 30.001464 -300.43247)
					(mid 29.997744 -300.44145)
					(end 29.988764 -300.44517)
				)
				(arc
					(start 28.515564 -300.44517)
					(mid 28.506584 -300.44145)
					(end 28.502864 -300.43247)
				)
				(arc
					(start 28.502864 -299.937932)
					(mid 28.506584 -299.928952)
					(end 28.515564 -299.925232)
				)
				(arc
					(start 29.988764 -299.925232)
					(mid 29.997744 -299.928952)
					(end 30.001464 -299.937932)
				)
			)
		)
	)
	(zone
		(layer "In1.Cu")
		(hatch none 0.5)
		(connect_pads
			(clearance 0)
		)
		(min_thickness 0.25)
		(keepout
			(tracks not_allowed)
			(vias allowed)
			(pads allowed)
			(copperpour not_allowed)
			(footprints allowed)
		)
		(placement
			(enabled no)
			(sheetname "")
		)
		(fill
			(thermal_gap 0.5)
			(thermal_bridge_width 0.5)
			(island_removal_mode 0)
		)
		(polygon
			(pts
				(arc
					(start 273.841464 -201.83221)
					(mid 273.837744 -201.84119)
					(end 273.828764 -201.84491)
				)
				(arc
					(start 272.355564 -201.84491)
					(mid 272.346584 -201.84119)
					(end 272.342864 -201.83221)
				)
				(arc
					(start 272.342864 -201.337672)
					(mid 272.346584 -201.328692)
					(end 272.355564 -201.324972)
				)
				(arc
					(start 273.828764 -201.324972)
					(mid 273.837744 -201.328692)
					(end 273.841464 -201.337672)
				)
			)
		)
	)
	(zone
		(layer "In1.Cu")
		(hatch none 0.5)
		(connect_pads
			(clearance 0)
		)
		(min_thickness 0.25)
		(keepout
			(tracks not_allowed)
			(vias allowed)
			(pads allowed)
			(copperpour not_allowed)
			(footprints allowed)
		)
		(placement
			(enabled no)
			(sheetname "")
		)
		(fill
			(thermal_gap 0.5)
			(thermal_bridge_width 0.5)
			(island_removal_mode 0)
		)
		(polygon
			(pts
				(arc
					(start 191.909446 -294.48252)
					(mid 191.905726 -294.4915)
					(end 191.896746 -294.49522)
				)
				(arc
					(start 190.423546 -294.49522)
					(mid 190.414566 -294.4915)
					(end 190.410846 -294.48252)
				)
				(arc
					(start 190.410846 -293.987982)
					(mid 190.414566 -293.979002)
					(end 190.423546 -293.975282)
				)
				(arc
					(start 191.896746 -293.975282)
					(mid 191.905726 -293.979002)
					(end 191.909446 -293.987982)
				)
			)
		)
	)
	(zone
		(layer "In1.Cu")
		(hatch none 0.5)
		(connect_pads
			(clearance 0)
		)
		(min_thickness 0.25)
		(keepout
			(tracks not_allowed)
			(vias allowed)
			(pads allowed)
			(copperpour not_allowed)
			(footprints allowed)
		)
		(placement
			(enabled no)
			(sheetname "")
		)
		(fill
			(thermal_gap 0.5)
			(thermal_bridge_width 0.5)
			(island_removal_mode 0)
		)
		(polygon
			(pts
				(arc
					(start 18.109692 -17.967198)
					(mid 18.13201 -18.02108)
					(end 18.185892 -18.043398)
				)
				(arc
					(start 18.381472 -18.043398)
					(mid 18.403348 -18.040266)
					(end 18.423382 -18.030952)
				)
				(arc
					(start 18.717006 -17.83842)
					(mid 18.758662 -17.826018)
					(end 18.800318 -17.83842)
				)
				(arc
					(start 19.095212 -18.030952)
					(mid 19.115136 -18.040188)
					(end 19.136868 -18.043398)
				)
				(arc
					(start 19.331432 -18.043398)
					(mid 19.385314 -18.02108)
					(end 19.407632 -17.967198)
				)
				(arc
					(start 19.407632 -17.281398)
					(mid 19.385314 -17.227516)
					(end 19.331432 -17.205198)
				)
				(arc
					(start 19.136868 -17.205198)
					(mid 19.115124 -17.208366)
					(end 19.095212 -17.217644)
				)
				(arc
					(start 18.799048 -17.41043)
					(mid 18.757364 -17.422652)
					(end 18.715736 -17.410176)
				)
				(arc
					(start 18.422112 -17.217644)
					(mid 18.402188 -17.208408)
					(end 18.380456 -17.205198)
				)
				(arc
					(start 18.185892 -17.205198)
					(mid 18.13201 -17.227516)
					(end 18.109692 -17.281398)
				)
			)
		)
	)
	(zone
		(layer "In1.Cu")
		(hatch none 0.5)
		(connect_pads
			(clearance 0)
		)
		(min_thickness 0.25)
		(keepout
			(tracks not_allowed)
			(vias allowed)
			(pads allowed)
			(copperpour not_allowed)
			(footprints allowed)
		)
		(placement
			(enabled no)
			(sheetname "")
		)
		(fill
			(thermal_gap 0.5)
			(thermal_bridge_width 0.5)
			(island_removal_mode 0)
		)
		(polygon
			(pts
				(arc
					(start 336.09788 -392.30427)
					(mid 335.79308 -392.30427)
					(end 336.09788 -392.30427)
				)
			)
		)
	)
	(zone
		(layer "In1.Cu")
		(hatch none 0.5)
		(connect_pads
			(clearance 0)
		)
		(min_thickness 0.25)
		(keepout
			(tracks not_allowed)
			(vias allowed)
			(pads allowed)
			(copperpour not_allowed)
			(footprints allowed)
		)
		(placement
			(enabled no)
			(sheetname "")
		)
		(fill
			(thermal_gap 0.5)
			(thermal_bridge_width 0.5)
			(island_removal_mode 0)
		)
		(polygon
			(pts
				(arc
					(start 277.941532 -315.73216)
					(mid 277.937812 -315.74114)
					(end 277.928832 -315.74486)
				)
				(arc
					(start 276.455632 -315.74486)
					(mid 276.446652 -315.74114)
					(end 276.442932 -315.73216)
				)
				(arc
					(start 276.442932 -315.237622)
					(mid 276.446652 -315.228642)
					(end 276.455632 -315.224922)
				)
				(arc
					(start 277.928832 -315.224922)
					(mid 277.937812 -315.228642)
					(end 277.941532 -315.237622)
				)
			)
		)
	)
	(zone
		(layer "In1.Cu")
		(hatch none 0.5)
		(connect_pads
			(clearance 0)
		)
		(min_thickness 0.25)
		(keepout
			(tracks not_allowed)
			(vias allowed)
			(pads allowed)
			(copperpour not_allowed)
			(footprints allowed)
		)
		(placement
			(enabled no)
			(sheetname "")
		)
		(fill
			(thermal_gap 0.5)
			(thermal_bridge_width 0.5)
			(island_removal_mode 0)
		)
		(polygon
			(pts
				(arc
					(start 22.45741 -219.682568)
					(mid 22.45369 -219.691548)
					(end 22.44471 -219.695268)
				)
				(arc
					(start 20.97151 -219.695268)
					(mid 20.96253 -219.691548)
					(end 20.95881 -219.682568)
				)
				(arc
					(start 20.95881 -219.18803)
					(mid 20.96253 -219.17905)
					(end 20.97151 -219.17533)
				)
				(arc
					(start 22.44471 -219.17533)
					(mid 22.45369 -219.17905)
					(end 22.45741 -219.18803)
				)
			)
		)
	)
	(zone
		(layer "In1.Cu")
		(hatch none 0.5)
		(connect_pads
			(clearance 0)
		)
		(min_thickness 0.25)
		(keepout
			(tracks not_allowed)
			(vias allowed)
			(pads allowed)
			(copperpour not_allowed)
			(footprints allowed)
		)
		(placement
			(enabled no)
			(sheetname "")
		)
		(fill
			(thermal_gap 0.5)
			(thermal_bridge_width 0.5)
			(island_removal_mode 0)
		)
		(polygon
			(pts
				(arc
					(start 270.397478 -297.032172)
					(mid 270.393758 -297.041152)
					(end 270.384778 -297.044872)
				)
				(arc
					(start 268.911578 -297.044872)
					(mid 268.902598 -297.041152)
					(end 268.898878 -297.032172)
				)
				(arc
					(start 268.898878 -296.537634)
					(mid 268.902598 -296.528654)
					(end 268.911578 -296.524934)
				)
				(arc
					(start 270.384778 -296.524934)
					(mid 270.393758 -296.528654)
					(end 270.397478 -296.537634)
				)
			)
		)
	)
	(zone
		(layer "In1.Cu")
		(hatch none 0.5)
		(connect_pads
			(clearance 0)
		)
		(min_thickness 0.25)
		(keepout
			(tracks not_allowed)
			(vias allowed)
			(pads allowed)
			(copperpour not_allowed)
			(footprints allowed)
		)
		(placement
			(enabled no)
			(sheetname "")
		)
		(fill
			(thermal_gap 0.5)
			(thermal_bridge_width 0.5)
			(island_removal_mode 0)
		)
		(polygon
			(pts
				(arc
					(start 300.57344 -229.882192)
					(mid 300.56972 -229.891172)
					(end 300.56074 -229.894892)
				)
				(arc
					(start 299.08754 -229.894892)
					(mid 299.07856 -229.891172)
					(end 299.07484 -229.882192)
				)
				(arc
					(start 299.07484 -229.387654)
					(mid 299.07856 -229.378674)
					(end 299.08754 -229.374954)
				)
				(arc
					(start 300.56074 -229.374954)
					(mid 300.56972 -229.378674)
					(end 300.57344 -229.387654)
				)
			)
		)
	)
	(zone
		(layer "In1.Cu")
		(hatch none 0.5)
		(connect_pads
			(clearance 0)
		)
		(min_thickness 0.25)
		(keepout
			(tracks not_allowed)
			(vias allowed)
			(pads allowed)
			(copperpour not_allowed)
			(footprints allowed)
		)
		(placement
			(enabled no)
			(sheetname "")
		)
		(fill
			(thermal_gap 0.5)
			(thermal_bridge_width 0.5)
			(island_removal_mode 0)
		)
		(polygon
			(pts
				(arc
					(start 40.98925 -224.78238)
					(mid 40.98553 -224.79136)
					(end 40.97655 -224.79508)
				)
				(arc
					(start 39.50335 -224.79508)
					(mid 39.49437 -224.79136)
					(end 39.49065 -224.78238)
				)
				(arc
					(start 39.49065 -224.287842)
					(mid 39.49437 -224.278862)
					(end 39.50335 -224.275142)
				)
				(arc
					(start 40.97655 -224.275142)
					(mid 40.98553 -224.278862)
					(end 40.98925 -224.287842)
				)
			)
		)
	)
	(zone
		(layer "In1.Cu")
		(hatch none 0.5)
		(connect_pads
			(clearance 0)
		)
		(min_thickness 0.25)
		(keepout
			(tracks not_allowed)
			(vias allowed)
			(pads allowed)
			(copperpour not_allowed)
			(footprints allowed)
		)
		(placement
			(enabled no)
			(sheetname "")
		)
		(fill
			(thermal_gap 0.5)
			(thermal_bridge_width 0.5)
			(island_removal_mode 0)
		)
		(polygon
			(pts
				(arc
					(start 30.001464 -285.132526)
					(mid 29.997744 -285.141506)
					(end 29.988764 -285.145226)
				)
				(arc
					(start 28.515564 -285.145226)
					(mid 28.506584 -285.141506)
					(end 28.502864 -285.132526)
				)
				(arc
					(start 28.502864 -284.637988)
					(mid 28.506584 -284.629008)
					(end 28.515564 -284.625288)
				)
				(arc
					(start 29.988764 -284.625288)
					(mid 29.997744 -284.629008)
					(end 30.001464 -284.637988)
				)
			)
		)
	)
	(zone
		(layer "In1.Cu")
		(hatch none 0.5)
		(connect_pads
			(clearance 0)
		)
		(min_thickness 0.25)
		(keepout
			(tracks not_allowed)
			(vias allowed)
			(pads allowed)
			(copperpour not_allowed)
			(footprints allowed)
		)
		(placement
			(enabled no)
			(sheetname "")
		)
		(fill
			(thermal_gap 0.5)
			(thermal_bridge_width 0.5)
			(island_removal_mode 0)
		)
		(polygon
			(pts
				(arc
					(start 270.397478 -201.83221)
					(mid 270.393758 -201.84119)
					(end 270.384778 -201.84491)
				)
				(arc
					(start 268.911578 -201.84491)
					(mid 268.902598 -201.84119)
					(end 268.898878 -201.83221)
				)
				(arc
					(start 268.898878 -201.337672)
					(mid 268.902598 -201.328692)
					(end 268.911578 -201.324972)
				)
				(arc
					(start 270.384778 -201.324972)
					(mid 270.393758 -201.328692)
					(end 270.397478 -201.337672)
				)
			)
		)
	)
	(zone
		(layer "In1.Cu")
		(hatch none 0.5)
		(connect_pads
			(clearance 0)
		)
		(min_thickness 0.25)
		(keepout
			(tracks not_allowed)
			(vias allowed)
			(pads allowed)
			(copperpour not_allowed)
			(footprints allowed)
		)
		(placement
			(enabled no)
			(sheetname "")
		)
		(fill
			(thermal_gap 0.5)
			(thermal_bridge_width 0.5)
			(island_removal_mode 0)
		)
		(polygon
			(pts
				(arc
					(start 191.909446 -251.13234)
					(mid 191.905726 -251.14132)
					(end 191.896746 -251.14504)
				)
				(arc
					(start 190.423546 -251.14504)
					(mid 190.414566 -251.14132)
					(end 190.410846 -251.13234)
				)
				(arc
					(start 190.410846 -250.637802)
					(mid 190.414566 -250.628822)
					(end 190.423546 -250.625102)
				)
				(arc
					(start 191.896746 -250.625102)
					(mid 191.905726 -250.628822)
					(end 191.909446 -250.637802)
				)
			)
		)
	)
	(zone
		(layer "In1.Cu")
		(hatch none 0.5)
		(connect_pads
			(clearance 0)
		)
		(min_thickness 0.25)
		(keepout
			(tracks not_allowed)
			(vias allowed)
			(pads allowed)
			(copperpour not_allowed)
			(footprints allowed)
		)
		(placement
			(enabled no)
			(sheetname "")
		)
		(fill
			(thermal_gap 0.5)
			(thermal_bridge_width 0.5)
			(island_removal_mode 0)
		)
		(polygon
			(pts
				(arc
					(start 454.937368 -261.332218)
					(mid 454.933648 -261.341198)
					(end 454.924668 -261.344918)
				)
				(arc
					(start 453.451468 -261.344918)
					(mid 453.442488 -261.341198)
					(end 453.438768 -261.332218)
				)
				(arc
					(start 453.438768 -260.83768)
					(mid 453.442488 -260.8287)
					(end 453.451468 -260.82498)
				)
				(arc
					(start 454.924668 -260.82498)
					(mid 454.933648 -260.8287)
					(end 454.937368 -260.83768)
				)
			)
		)
	)
	(zone
		(layer "In1.Cu")
		(hatch none 0.5)
		(connect_pads
			(clearance 0)
		)
		(min_thickness 0.25)
		(keepout
			(tracks not_allowed)
			(vias allowed)
			(pads allowed)
			(copperpour not_allowed)
			(footprints allowed)
		)
		(placement
			(enabled no)
			(sheetname "")
		)
		(fill
			(thermal_gap 0.5)
			(thermal_bridge_width 0.5)
			(island_removal_mode 0)
		)
		(polygon
			(pts
				(arc
					(start 450.8373 -215.432132)
					(mid 450.83358 -215.441112)
					(end 450.8246 -215.444832)
				)
				(arc
					(start 449.3514 -215.444832)
					(mid 449.34242 -215.441112)
					(end 449.3387 -215.432132)
				)
				(arc
					(start 449.3387 -214.937594)
					(mid 449.34242 -214.928614)
					(end 449.3514 -214.924894)
				)
				(arc
					(start 450.8246 -214.924894)
					(mid 450.83358 -214.928614)
					(end 450.8373 -214.937594)
				)
			)
		)
	)
	(zone
		(layer "In1.Cu")
		(hatch none 0.5)
		(connect_pads
			(clearance 0)
		)
		(min_thickness 0.25)
		(keepout
			(tracks not_allowed)
			(vias allowed)
			(pads allowed)
			(copperpour not_allowed)
			(footprints allowed)
		)
		(placement
			(enabled no)
			(sheetname "")
		)
		(fill
			(thermal_gap 0.5)
			(thermal_bridge_width 0.5)
			(island_removal_mode 0)
		)
		(polygon
			(pts
				(arc
					(start 169.277284 -214.582502)
					(mid 169.273564 -214.591482)
					(end 169.264584 -214.595202)
				)
				(arc
					(start 167.791384 -214.595202)
					(mid 167.782404 -214.591482)
					(end 167.778684 -214.582502)
				)
				(arc
					(start 167.778684 -214.087964)
					(mid 167.782404 -214.078984)
					(end 167.791384 -214.075264)
				)
				(arc
					(start 169.264584 -214.075264)
					(mid 169.273564 -214.078984)
					(end 169.277284 -214.087964)
				)
			)
		)
	)
	(zone
		(layer "In1.Cu")
		(hatch none 0.5)
		(connect_pads
			(clearance 0)
		)
		(min_thickness 0.25)
		(keepout
			(tracks not_allowed)
			(vias allowed)
			(pads allowed)
			(copperpour not_allowed)
			(footprints allowed)
		)
		(placement
			(enabled no)
			(sheetname "")
		)
		(fill
			(thermal_gap 0.5)
			(thermal_bridge_width 0.5)
			(island_removal_mode 0)
		)
		(polygon
			(pts
				(arc
					(start 18.357342 -200.132442)
					(mid 18.353622 -200.141422)
					(end 18.344642 -200.145142)
				)
				(arc
					(start 16.871442 -200.145142)
					(mid 16.862462 -200.141422)
					(end 16.858742 -200.132442)
				)
				(arc
					(start 16.858742 -199.637904)
					(mid 16.862462 -199.628924)
					(end 16.871442 -199.625204)
				)
				(arc
					(start 18.344642 -199.625204)
					(mid 18.353622 -199.628924)
					(end 18.357342 -199.637904)
				)
			)
		)
	)
	(zone
		(layer "In1.Cu")
		(hatch none 0.5)
		(connect_pads
			(clearance 0)
		)
		(min_thickness 0.25)
		(keepout
			(tracks not_allowed)
			(vias allowed)
			(pads allowed)
			(copperpour not_allowed)
			(footprints allowed)
		)
		(placement
			(enabled no)
			(sheetname "")
		)
		(fill
			(thermal_gap 0.5)
			(thermal_bridge_width 0.5)
			(island_removal_mode 0)
		)
		(polygon
			(pts
				(arc
					(start 202.897232 -314.88253)
					(mid 202.893512 -314.89151)
					(end 202.884532 -314.89523)
				)
				(arc
					(start 201.411332 -314.89523)
					(mid 201.402352 -314.89151)
					(end 201.398632 -314.88253)
				)
				(arc
					(start 201.398632 -314.387992)
					(mid 201.402352 -314.379012)
					(end 201.411332 -314.375292)
				)
				(arc
					(start 202.884532 -314.375292)
					(mid 202.893512 -314.379012)
					(end 202.897232 -314.387992)
				)
			)
		)
	)
	(zone
		(layer "In1.Cu")
		(hatch none 0.5)
		(connect_pads
			(clearance 0)
		)
		(min_thickness 0.25)
		(keepout
			(tracks not_allowed)
			(vias allowed)
			(pads allowed)
			(copperpour not_allowed)
			(footprints allowed)
		)
		(placement
			(enabled no)
			(sheetname "")
		)
		(fill
			(thermal_gap 0.5)
			(thermal_bridge_width 0.5)
			(island_removal_mode 0)
		)
		(polygon
			(pts
				(arc
					(start 407.888948 -397.156432)
					(mid 407.507948 -397.156432)
					(end 407.888948 -397.156432)
				)
			)
		)
	)
	(zone
		(layer "In1.Cu")
		(hatch none 0.5)
		(connect_pads
			(clearance 0)
		)
		(min_thickness 0.25)
		(keepout
			(tracks not_allowed)
			(vias allowed)
			(pads allowed)
			(copperpour not_allowed)
			(footprints allowed)
		)
		(placement
			(enabled no)
			(sheetname "")
		)
		(fill
			(thermal_gap 0.5)
			(thermal_bridge_width 0.5)
			(island_removal_mode 0)
		)
		(polygon
			(pts
				(arc
					(start 206.9973 -297.032426)
					(mid 206.99358 -297.041406)
					(end 206.9846 -297.045126)
				)
				(arc
					(start 205.5114 -297.045126)
					(mid 205.50242 -297.041406)
					(end 205.4987 -297.032426)
				)
				(arc
					(start 205.4987 -296.537888)
					(mid 205.50242 -296.528908)
					(end 205.5114 -296.525188)
				)
				(arc
					(start 206.9846 -296.525188)
					(mid 206.99358 -296.528908)
					(end 206.9973 -296.537888)
				)
			)
		)
	)
	(zone
		(layer "In1.Cu")
		(hatch none 0.5)
		(connect_pads
			(clearance 0)
		)
		(min_thickness 0.25)
		(keepout
			(tracks not_allowed)
			(vias allowed)
			(pads allowed)
			(copperpour not_allowed)
			(footprints allowed)
		)
		(placement
			(enabled no)
			(sheetname "")
		)
		(fill
			(thermal_gap 0.5)
			(thermal_bridge_width 0.5)
			(island_removal_mode 0)
		)
		(polygon
			(pts
				(arc
					(start 304.017426 -263.882124)
					(mid 304.013706 -263.891104)
					(end 304.004726 -263.894824)
				)
				(arc
					(start 302.531526 -263.894824)
					(mid 302.522546 -263.891104)
					(end 302.518826 -263.882124)
				)
				(arc
					(start 302.518826 -263.387586)
					(mid 302.522546 -263.378606)
					(end 302.531526 -263.374886)
				)
				(arc
					(start 304.004726 -263.374886)
					(mid 304.013706 -263.378606)
					(end 304.017426 -263.387586)
				)
			)
		)
	)
	(zone
		(layer "In1.Cu")
		(hatch none 0.5)
		(connect_pads
			(clearance 0)
		)
		(min_thickness 0.25)
		(keepout
			(tracks not_allowed)
			(vias allowed)
			(pads allowed)
			(copperpour not_allowed)
			(footprints allowed)
		)
		(placement
			(enabled no)
			(sheetname "")
		)
		(fill
			(thermal_gap 0.5)
			(thermal_bridge_width 0.5)
			(island_removal_mode 0)
		)
		(polygon
			(pts
				(arc
					(start 202.897232 -293.632382)
					(mid 202.893512 -293.641362)
					(end 202.884532 -293.645082)
				)
				(arc
					(start 201.411332 -293.645082)
					(mid 201.402352 -293.641362)
					(end 201.398632 -293.632382)
				)
				(arc
					(start 201.398632 -293.137844)
					(mid 201.402352 -293.128864)
					(end 201.411332 -293.125144)
				)
				(arc
					(start 202.884532 -293.125144)
					(mid 202.893512 -293.128864)
					(end 202.897232 -293.137844)
				)
			)
		)
	)
	(zone
		(layer "In1.Cu")
		(hatch none 0.5)
		(connect_pads
			(clearance 0)
		)
		(min_thickness 0.25)
		(keepout
			(tracks not_allowed)
			(vias allowed)
			(pads allowed)
			(copperpour not_allowed)
			(footprints allowed)
		)
		(placement
			(enabled no)
			(sheetname "")
		)
		(fill
			(thermal_gap 0.5)
			(thermal_bridge_width 0.5)
			(island_removal_mode 0)
		)
		(polygon
			(pts
				(arc
					(start 30.001464 -268.13256)
					(mid 29.997744 -268.14154)
					(end 29.988764 -268.14526)
				)
				(arc
					(start 28.515564 -268.14526)
					(mid 28.506584 -268.14154)
					(end 28.502864 -268.13256)
				)
				(arc
					(start 28.502864 -267.638022)
					(mid 28.506584 -267.629042)
					(end 28.515564 -267.625322)
				)
				(arc
					(start 29.988764 -267.625322)
					(mid 29.997744 -267.629042)
					(end 30.001464 -267.638022)
				)
			)
		)
	)
	(zone
		(layer "In1.Cu")
		(hatch none 0.5)
		(connect_pads
			(clearance 0)
		)
		(min_thickness 0.25)
		(keepout
			(tracks not_allowed)
			(vias allowed)
			(pads allowed)
			(copperpour not_allowed)
			(footprints allowed)
		)
		(placement
			(enabled no)
			(sheetname "")
		)
		(fill
			(thermal_gap 0.5)
			(thermal_bridge_width 0.5)
			(island_removal_mode 0)
		)
		(polygon
			(pts
				(arc
					(start 413.117284 -232.432098)
					(mid 413.113564 -232.441078)
					(end 413.104584 -232.444798)
				)
				(arc
					(start 411.631384 -232.444798)
					(mid 411.622404 -232.441078)
					(end 411.618684 -232.432098)
				)
				(arc
					(start 411.618684 -231.93756)
					(mid 411.622404 -231.92858)
					(end 411.631384 -231.92486)
				)
				(arc
					(start 413.104584 -231.92486)
					(mid 413.113564 -231.92858)
					(end 413.117284 -231.93756)
				)
			)
		)
	)
	(zone
		(layer "In1.Cu")
		(hatch none 0.5)
		(connect_pads
			(clearance 0)
		)
		(min_thickness 0.25)
		(keepout
			(tracks not_allowed)
			(vias allowed)
			(pads allowed)
			(copperpour not_allowed)
			(footprints allowed)
		)
		(placement
			(enabled no)
			(sheetname "")
		)
		(fill
			(thermal_gap 0.5)
			(thermal_bridge_width 0.5)
			(island_removal_mode 0)
		)
		(polygon
			(pts
				(arc
					(start 435.749446 -290.232338)
					(mid 435.745726 -290.241318)
					(end 435.736746 -290.245038)
				)
				(arc
					(start 434.263546 -290.245038)
					(mid 434.254566 -290.241318)
					(end 434.250846 -290.232338)
				)
				(arc
					(start 434.250846 -289.7378)
					(mid 434.254566 -289.72882)
					(end 434.263546 -289.7251)
				)
				(arc
					(start 435.736746 -289.7251)
					(mid 435.745726 -289.72882)
					(end 435.749446 -289.7378)
				)
			)
		)
	)
	(zone
		(layer "In1.Cu")
		(hatch none 0.5)
		(connect_pads
			(clearance 0)
		)
		(min_thickness 0.25)
		(keepout
			(tracks not_allowed)
			(vias allowed)
			(pads allowed)
			(copperpour not_allowed)
			(footprints allowed)
		)
		(placement
			(enabled no)
			(sheetname "")
		)
		(fill
			(thermal_gap 0.5)
			(thermal_bridge_width 0.5)
			(island_removal_mode 0)
		)
		(polygon
			(pts
				(arc
					(start 432.30546 -291.082222)
					(mid 432.30174 -291.091202)
					(end 432.29276 -291.094922)
				)
				(arc
					(start 430.81956 -291.094922)
					(mid 430.81058 -291.091202)
					(end 430.80686 -291.082222)
				)
				(arc
					(start 430.80686 -290.587684)
					(mid 430.81058 -290.578704)
					(end 430.81956 -290.574984)
				)
				(arc
					(start 432.29276 -290.574984)
					(mid 432.30174 -290.578704)
					(end 432.30546 -290.587684)
				)
			)
		)
	)
	(zone
		(layer "In1.Cu")
		(hatch none 0.5)
		(connect_pads
			(clearance 0)
		)
		(min_thickness 0.25)
		(keepout
			(tracks not_allowed)
			(vias allowed)
			(pads allowed)
			(copperpour not_allowed)
			(footprints allowed)
		)
		(placement
			(enabled no)
			(sheetname "")
		)
		(fill
			(thermal_gap 0.5)
			(thermal_bridge_width 0.5)
			(island_removal_mode 0)
		)
		(polygon
			(pts
				(arc
					(start 420.661338 -277.4823)
					(mid 420.657618 -277.49128)
					(end 420.648638 -277.495)
				)
				(arc
					(start 419.175438 -277.495)
					(mid 419.166458 -277.49128)
					(end 419.162738 -277.4823)
				)
				(arc
					(start 419.162738 -276.987762)
					(mid 419.166458 -276.978782)
					(end 419.175438 -276.975062)
				)
				(arc
					(start 420.648638 -276.975062)
					(mid 420.657618 -276.978782)
					(end 420.661338 -276.987762)
				)
			)
		)
	)
	(zone
		(layer "In1.Cu")
		(hatch none 0.5)
		(connect_pads
			(clearance 0)
		)
		(min_thickness 0.25)
		(keepout
			(tracks not_allowed)
			(vias allowed)
			(pads allowed)
			(copperpour not_allowed)
			(footprints allowed)
		)
		(placement
			(enabled no)
			(sheetname "")
		)
		(fill
			(thermal_gap 0.5)
			(thermal_bridge_width 0.5)
			(island_removal_mode 0)
		)
		(polygon
			(pts
				(arc
					(start 84.318856 -383.440686)
					(mid 84.445856 -383.567686)
					(end 84.572856 -383.440686)
				)
				(arc
					(start 84.572856 -383.364486)
					(mid 84.445856 -383.237486)
					(end 84.318856 -383.364486)
				)
			)
		)
	)
	(zone
		(layer "In1.Cu")
		(hatch none 0.5)
		(connect_pads
			(clearance 0)
		)
		(min_thickness 0.25)
		(keepout
			(tracks not_allowed)
			(vias allowed)
			(pads allowed)
			(copperpour not_allowed)
			(footprints allowed)
		)
		(placement
			(enabled no)
			(sheetname "")
		)
		(fill
			(thermal_gap 0.5)
			(thermal_bridge_width 0.5)
			(island_removal_mode 0)
		)
		(polygon
			(pts
				(arc
					(start 308.117494 -229.032308)
					(mid 308.113774 -229.041288)
					(end 308.104794 -229.045008)
				)
				(arc
					(start 306.631594 -229.045008)
					(mid 306.622614 -229.041288)
					(end 306.618894 -229.032308)
				)
				(arc
					(start 306.618894 -228.53777)
					(mid 306.622614 -228.52879)
					(end 306.631594 -228.52507)
				)
				(arc
					(start 308.104794 -228.52507)
					(mid 308.113774 -228.52879)
					(end 308.117494 -228.53777)
				)
			)
		)
	)
	(zone
		(layer "In1.Cu")
		(hatch none 0.5)
		(connect_pads
			(clearance 0)
		)
		(min_thickness 0.25)
		(keepout
			(tracks not_allowed)
			(vias allowed)
			(pads allowed)
			(copperpour not_allowed)
			(footprints allowed)
		)
		(placement
			(enabled no)
			(sheetname "")
		)
		(fill
			(thermal_gap 0.5)
			(thermal_bridge_width 0.5)
			(island_removal_mode 0)
		)
		(polygon
			(pts
				(arc
					(start 300.57344 -238.382302)
					(mid 300.56972 -238.391282)
					(end 300.56074 -238.395002)
				)
				(arc
					(start 299.08754 -238.395002)
					(mid 299.07856 -238.391282)
					(end 299.07484 -238.382302)
				)
				(arc
					(start 299.07484 -237.887764)
					(mid 299.07856 -237.878784)
					(end 299.08754 -237.875064)
				)
				(arc
					(start 300.56074 -237.875064)
					(mid 300.56972 -237.878784)
					(end 300.57344 -237.887764)
				)
			)
		)
	)
	(zone
		(layer "In1.Cu")
		(hatch none 0.5)
		(connect_pads
			(clearance 0)
		)
		(min_thickness 0.25)
		(keepout
			(tracks not_allowed)
			(vias allowed)
			(pads allowed)
			(copperpour not_allowed)
			(footprints allowed)
		)
		(placement
			(enabled no)
			(sheetname "")
		)
		(fill
			(thermal_gap 0.5)
			(thermal_bridge_width 0.5)
			(island_removal_mode 0)
		)
		(polygon
			(pts
				(arc
					(start 266.29741 -302.982122)
					(mid 266.29369 -302.991102)
					(end 266.28471 -302.994822)
				)
				(arc
					(start 264.81151 -302.994822)
					(mid 264.80253 -302.991102)
					(end 264.79881 -302.982122)
				)
				(arc
					(start 264.79881 -302.487584)
					(mid 264.80253 -302.478604)
					(end 264.81151 -302.474884)
				)
				(arc
					(start 266.28471 -302.474884)
					(mid 266.29369 -302.478604)
					(end 266.29741 -302.487584)
				)
			)
		)
	)
	(zone
		(layer "In1.Cu")
		(hatch none 0.5)
		(connect_pads
			(clearance 0)
		)
		(min_thickness 0.25)
		(keepout
			(tracks not_allowed)
			(vias allowed)
			(pads allowed)
			(copperpour not_allowed)
			(footprints allowed)
		)
		(placement
			(enabled no)
			(sheetname "")
		)
		(fill
			(thermal_gap 0.5)
			(thermal_bridge_width 0.5)
			(island_removal_mode 0)
		)
		(polygon
			(pts
				(arc
					(start 195.353432 -209.482436)
					(mid 195.349712 -209.491416)
					(end 195.340732 -209.495136)
				)
				(arc
					(start 193.867532 -209.495136)
					(mid 193.858552 -209.491416)
					(end 193.854832 -209.482436)
				)
				(arc
					(start 193.854832 -208.987898)
					(mid 193.858552 -208.978918)
					(end 193.867532 -208.975198)
				)
				(arc
					(start 195.340732 -208.975198)
					(mid 195.349712 -208.978918)
					(end 195.353432 -208.987898)
				)
			)
		)
	)
	(zone
		(layer "In1.Cu")
		(hatch none 0.5)
		(connect_pads
			(clearance 0)
		)
		(min_thickness 0.25)
		(keepout
			(tracks not_allowed)
			(vias allowed)
			(pads allowed)
			(copperpour not_allowed)
			(footprints allowed)
		)
		(placement
			(enabled no)
			(sheetname "")
		)
		(fill
			(thermal_gap 0.5)
			(thermal_bridge_width 0.5)
			(island_removal_mode 0)
		)
		(polygon
			(pts
				(arc
					(start 265.87831 -313.784996)
					(mid 265.21791 -313.784996)
					(end 265.87831 -313.784996)
				)
			)
		)
	)
	(zone
		(layer "In1.Cu")
		(hatch none 0.5)
		(connect_pads
			(clearance 0)
		)
		(min_thickness 0.25)
		(keepout
			(tracks not_allowed)
			(vias allowed)
			(pads allowed)
			(copperpour not_allowed)
			(footprints allowed)
		)
		(placement
			(enabled no)
			(sheetname "")
		)
		(fill
			(thermal_gap 0.5)
			(thermal_bridge_width 0.5)
			(island_removal_mode 0)
		)
		(polygon
			(pts
				(arc
					(start 22.45741 -269.832582)
					(mid 22.45369 -269.841562)
					(end 22.44471 -269.845282)
				)
				(arc
					(start 20.97151 -269.845282)
					(mid 20.96253 -269.841562)
					(end 20.95881 -269.832582)
				)
				(arc
					(start 20.95881 -269.338044)
					(mid 20.96253 -269.329064)
					(end 20.97151 -269.325344)
				)
				(arc
					(start 22.44471 -269.325344)
					(mid 22.45369 -269.329064)
					(end 22.45741 -269.338044)
				)
			)
		)
	)
	(zone
		(layer "In1.Cu")
		(hatch none 0.5)
		(connect_pads
			(clearance 0)
		)
		(min_thickness 0.25)
		(keepout
			(tracks not_allowed)
			(vias allowed)
			(pads allowed)
			(copperpour not_allowed)
			(footprints allowed)
		)
		(placement
			(enabled no)
			(sheetname "")
		)
		(fill
			(thermal_gap 0.5)
			(thermal_bridge_width 0.5)
			(island_removal_mode 0)
		)
		(polygon
			(pts
				(arc
					(start 439.849514 -231.582214)
					(mid 439.845794 -231.591194)
					(end 439.836814 -231.594914)
				)
				(arc
					(start 438.363614 -231.594914)
					(mid 438.354634 -231.591194)
					(end 438.350914 -231.582214)
				)
				(arc
					(start 438.350914 -231.087676)
					(mid 438.354634 -231.078696)
					(end 438.363614 -231.074976)
				)
				(arc
					(start 439.836814 -231.074976)
					(mid 439.845794 -231.078696)
					(end 439.849514 -231.087676)
				)
			)
		)
	)
	(zone
		(layer "In1.Cu")
		(hatch none 0.5)
		(connect_pads
			(clearance 0)
		)
		(min_thickness 0.25)
		(keepout
			(tracks not_allowed)
			(vias allowed)
			(pads allowed)
			(copperpour not_allowed)
			(footprints allowed)
		)
		(placement
			(enabled no)
			(sheetname "")
		)
		(fill
			(thermal_gap 0.5)
			(thermal_bridge_width 0.5)
			(island_removal_mode 0)
		)
		(polygon
			(pts
				(arc
					(start 94.49816 -390.761474)
					(mid 94.19336 -390.761474)
					(end 94.49816 -390.761474)
				)
			)
		)
	)
	(zone
		(layer "In1.Cu")
		(hatch none 0.5)
		(connect_pads
			(clearance 0)
		)
		(min_thickness 0.25)
		(keepout
			(tracks not_allowed)
			(vias allowed)
			(pads allowed)
			(copperpour not_allowed)
			(footprints allowed)
		)
		(placement
			(enabled no)
			(sheetname "")
		)
		(fill
			(thermal_gap 0.5)
			(thermal_bridge_width 0.5)
			(island_removal_mode 0)
		)
		(polygon
			(pts
				(arc
					(start 52.633372 -225.632518)
					(mid 52.629652 -225.641498)
					(end 52.620672 -225.645218)
				)
				(arc
					(start 51.147472 -225.645218)
					(mid 51.138492 -225.641498)
					(end 51.134772 -225.632518)
				)
				(arc
					(start 51.134772 -225.13798)
					(mid 51.138492 -225.129)
					(end 51.147472 -225.12528)
				)
				(arc
					(start 52.620672 -225.12528)
					(mid 52.629652 -225.129)
					(end 52.633372 -225.13798)
				)
			)
		)
	)
	(zone
		(layer "In1.Cu")
		(hatch none 0.5)
		(connect_pads
			(clearance 0)
		)
		(min_thickness 0.25)
		(keepout
			(tracks not_allowed)
			(vias allowed)
			(pads allowed)
			(copperpour not_allowed)
			(footprints allowed)
		)
		(placement
			(enabled no)
			(sheetname "")
		)
		(fill
			(thermal_gap 0.5)
			(thermal_bridge_width 0.5)
			(island_removal_mode 0)
		)
		(polygon
			(pts
				(arc
					(start 419.088824 -397.849344)
					(mid 418.707824 -397.849344)
					(end 419.088824 -397.849344)
				)
			)
		)
	)
	(zone
		(layer "In1.Cu")
		(hatch none 0.5)
		(connect_pads
			(clearance 0)
		)
		(min_thickness 0.25)
		(keepout
			(tracks not_allowed)
			(vias allowed)
			(pads allowed)
			(copperpour not_allowed)
			(footprints allowed)
		)
		(placement
			(enabled no)
			(sheetname "")
		)
		(fill
			(thermal_gap 0.5)
			(thermal_bridge_width 0.5)
			(island_removal_mode 0)
		)
		(polygon
			(pts
				(arc
					(start 25.901396 -307.232558)
					(mid 25.897676 -307.241538)
					(end 25.888696 -307.245258)
				)
				(arc
					(start 24.415496 -307.245258)
					(mid 24.406516 -307.241538)
					(end 24.402796 -307.232558)
				)
				(arc
					(start 24.402796 -306.73802)
					(mid 24.406516 -306.72904)
					(end 24.415496 -306.72532)
				)
				(arc
					(start 25.888696 -306.72532)
					(mid 25.897676 -306.72904)
					(end 25.901396 -306.73802)
				)
			)
		)
	)
	(zone
		(layer "In1.Cu")
		(hatch none 0.5)
		(connect_pads
			(clearance 0)
		)
		(min_thickness 0.25)
		(keepout
			(tracks not_allowed)
			(vias allowed)
			(pads allowed)
			(copperpour not_allowed)
			(footprints allowed)
		)
		(placement
			(enabled no)
			(sheetname "")
		)
		(fill
			(thermal_gap 0.5)
			(thermal_bridge_width 0.5)
			(island_removal_mode 0)
		)
		(polygon
			(pts
				(arc
					(start 169.277284 -291.082476)
					(mid 169.273564 -291.091456)
					(end 169.264584 -291.095176)
				)
				(arc
					(start 167.791384 -291.095176)
					(mid 167.782404 -291.091456)
					(end 167.778684 -291.082476)
				)
				(arc
					(start 167.778684 -290.587938)
					(mid 167.782404 -290.578958)
					(end 167.791384 -290.575238)
				)
				(arc
					(start 169.264584 -290.575238)
					(mid 169.273564 -290.578958)
					(end 169.277284 -290.587938)
				)
			)
		)
	)
	(zone
		(layer "In1.Cu")
		(hatch none 0.5)
		(connect_pads
			(clearance 0)
		)
		(min_thickness 0.25)
		(keepout
			(tracks not_allowed)
			(vias allowed)
			(pads allowed)
			(copperpour not_allowed)
			(footprints allowed)
		)
		(placement
			(enabled no)
			(sheetname "")
		)
		(fill
			(thermal_gap 0.5)
			(thermal_bridge_width 0.5)
			(island_removal_mode 0)
		)
		(polygon
			(pts
				(arc
					(start 45.089318 -283.432504)
					(mid 45.085598 -283.441484)
					(end 45.076618 -283.445204)
				)
				(arc
					(start 43.603418 -283.445204)
					(mid 43.594438 -283.441484)
					(end 43.590718 -283.432504)
				)
				(arc
					(start 43.590718 -282.937966)
					(mid 43.594438 -282.928986)
					(end 43.603418 -282.925266)
				)
				(arc
					(start 45.076618 -282.925266)
					(mid 45.085598 -282.928986)
					(end 45.089318 -282.937966)
				)
			)
		)
	)
	(zone
		(layer "In1.Cu")
		(hatch none 0.5)
		(connect_pads
			(clearance 0)
		)
		(min_thickness 0.25)
		(keepout
			(tracks not_allowed)
			(vias allowed)
			(pads allowed)
			(copperpour not_allowed)
			(footprints allowed)
		)
		(placement
			(enabled no)
			(sheetname "")
		)
		(fill
			(thermal_gap 0.5)
			(thermal_bridge_width 0.5)
			(island_removal_mode 0)
		)
		(polygon
			(pts
				(arc
					(start 169.277284 -203.532486)
					(mid 169.273564 -203.541466)
					(end 169.264584 -203.545186)
				)
				(arc
					(start 167.791384 -203.545186)
					(mid 167.782404 -203.541466)
					(end 167.778684 -203.532486)
				)
				(arc
					(start 167.778684 -203.037948)
					(mid 167.782404 -203.028968)
					(end 167.791384 -203.025248)
				)
				(arc
					(start 169.264584 -203.025248)
					(mid 169.273564 -203.028968)
					(end 169.277284 -203.037948)
				)
			)
		)
	)
	(zone
		(layer "In1.Cu")
		(hatch none 0.5)
		(connect_pads
			(clearance 0)
		)
		(min_thickness 0.25)
		(keepout
			(tracks not_allowed)
			(vias allowed)
			(pads allowed)
			(copperpour not_allowed)
			(footprints allowed)
		)
		(placement
			(enabled no)
			(sheetname "")
		)
		(fill
			(thermal_gap 0.5)
			(thermal_bridge_width 0.5)
			(island_removal_mode 0)
		)
		(polygon
			(pts
				(arc
					(start 33.445196 -213.732364)
					(mid 33.441476 -213.741344)
					(end 33.432496 -213.745064)
				)
				(arc
					(start 31.959296 -213.745064)
					(mid 31.950316 -213.741344)
					(end 31.946596 -213.732364)
				)
				(arc
					(start 31.946596 -213.237826)
					(mid 31.950316 -213.228846)
					(end 31.959296 -213.225126)
				)
				(arc
					(start 33.432496 -213.225126)
					(mid 33.441476 -213.228846)
					(end 33.445196 -213.237826)
				)
			)
		)
	)
	(zone
		(layer "In1.Cu")
		(hatch none 0.5)
		(connect_pads
			(clearance 0)
		)
		(min_thickness 0.25)
		(keepout
			(tracks not_allowed)
			(vias allowed)
			(pads allowed)
			(copperpour not_allowed)
			(footprints allowed)
		)
		(placement
			(enabled no)
			(sheetname "")
		)
		(fill
			(thermal_gap 0.5)
			(thermal_bridge_width 0.5)
			(island_removal_mode 0)
		)
		(polygon
			(pts
				(arc
					(start 119.470424 -383.92227)
					(mid 119.165624 -383.92227)
					(end 119.470424 -383.92227)
				)
			)
		)
	)
	(zone
		(layer "In1.Cu")
		(hatch none 0.5)
		(connect_pads
			(clearance 0)
		)
		(min_thickness 0.25)
		(keepout
			(tracks not_allowed)
			(vias allowed)
			(pads allowed)
			(copperpour not_allowed)
			(footprints allowed)
		)
		(placement
			(enabled no)
			(sheetname "")
		)
		(fill
			(thermal_gap 0.5)
			(thermal_bridge_width 0.5)
			(island_removal_mode 0)
		)
		(polygon
			(pts
				(arc
					(start 428.205392 -215.432132)
					(mid 428.201672 -215.441112)
					(end 428.192692 -215.444832)
				)
				(arc
					(start 426.719492 -215.444832)
					(mid 426.710512 -215.441112)
					(end 426.706792 -215.432132)
				)
				(arc
					(start 426.706792 -214.937594)
					(mid 426.710512 -214.928614)
					(end 426.719492 -214.924894)
				)
				(arc
					(start 428.192692 -214.924894)
					(mid 428.201672 -214.928614)
					(end 428.205392 -214.937594)
				)
			)
		)
	)
	(zone
		(layer "In1.Cu")
		(hatch none 0.5)
		(connect_pads
			(clearance 0)
		)
		(min_thickness 0.25)
		(keepout
			(tracks not_allowed)
			(vias allowed)
			(pads allowed)
			(copperpour not_allowed)
			(footprints allowed)
		)
		(placement
			(enabled no)
			(sheetname "")
		)
		(fill
			(thermal_gap 0.5)
			(thermal_bridge_width 0.5)
			(island_removal_mode 0)
		)
		(polygon
			(pts
				(arc
					(start 428.205392 -230.73233)
					(mid 428.201672 -230.74131)
					(end 428.192692 -230.74503)
				)
				(arc
					(start 426.719492 -230.74503)
					(mid 426.710512 -230.74131)
					(end 426.706792 -230.73233)
				)
				(arc
					(start 426.706792 -230.237792)
					(mid 426.710512 -230.228812)
					(end 426.719492 -230.225092)
				)
				(arc
					(start 428.192692 -230.225092)
					(mid 428.201672 -230.228812)
					(end 428.205392 -230.237792)
				)
			)
		)
	)
	(zone
		(layer "In1.Cu")
		(hatch none 0.5)
		(connect_pads
			(clearance 0)
		)
		(min_thickness 0.25)
		(keepout
			(tracks not_allowed)
			(vias allowed)
			(pads allowed)
			(copperpour not_allowed)
			(footprints allowed)
		)
		(placement
			(enabled no)
			(sheetname "")
		)
		(fill
			(thermal_gap 0.5)
			(thermal_bridge_width 0.5)
			(island_removal_mode 0)
		)
		(polygon
			(pts
				(arc
					(start 300.57344 -291.082222)
					(mid 300.56972 -291.091202)
					(end 300.56074 -291.094922)
				)
				(arc
					(start 299.08754 -291.094922)
					(mid 299.07856 -291.091202)
					(end 299.07484 -291.082222)
				)
				(arc
					(start 299.07484 -290.587684)
					(mid 299.07856 -290.578704)
					(end 299.08754 -290.574984)
				)
				(arc
					(start 300.56074 -290.574984)
					(mid 300.56972 -290.578704)
					(end 300.57344 -290.587684)
				)
			)
		)
	)
	(zone
		(layer "In1.Cu")
		(hatch none 0.5)
		(connect_pads
			(clearance 0)
		)
		(min_thickness 0.25)
		(keepout
			(tracks not_allowed)
			(vias allowed)
			(pads allowed)
			(copperpour not_allowed)
			(footprints allowed)
		)
		(placement
			(enabled no)
			(sheetname "")
		)
		(fill
			(thermal_gap 0.5)
			(thermal_bridge_width 0.5)
			(island_removal_mode 0)
		)
		(polygon
			(pts
				(arc
					(start 60.177426 -268.13256)
					(mid 60.173706 -268.14154)
					(end 60.164726 -268.14526)
				)
				(arc
					(start 58.691526 -268.14526)
					(mid 58.682546 -268.14154)
					(end 58.678826 -268.13256)
				)
				(arc
					(start 58.678826 -267.638022)
					(mid 58.682546 -267.629042)
					(end 58.691526 -267.625322)
				)
				(arc
					(start 60.164726 -267.625322)
					(mid 60.173706 -267.629042)
					(end 60.177426 -267.638022)
				)
			)
		)
	)
	(zone
		(layer "In1.Cu")
		(hatch none 0.5)
		(connect_pads
			(clearance 0)
		)
		(min_thickness 0.25)
		(keepout
			(tracks not_allowed)
			(vias allowed)
			(pads allowed)
			(copperpour not_allowed)
			(footprints allowed)
		)
		(placement
			(enabled no)
			(sheetname "")
		)
		(fill
			(thermal_gap 0.5)
			(thermal_bridge_width 0.5)
			(island_removal_mode 0)
		)
		(polygon
			(pts
				(arc
					(start 265.87831 -268.735048)
					(mid 265.21791 -268.735048)
					(end 265.87831 -268.735048)
				)
			)
		)
	)
	(zone
		(layer "In1.Cu")
		(hatch none 0.5)
		(connect_pads
			(clearance 0)
		)
		(min_thickness 0.25)
		(keepout
			(tracks not_allowed)
			(vias allowed)
			(pads allowed)
			(copperpour not_allowed)
			(footprints allowed)
		)
		(placement
			(enabled no)
			(sheetname "")
		)
		(fill
			(thermal_gap 0.5)
			(thermal_bridge_width 0.5)
			(island_removal_mode 0)
		)
		(polygon
			(pts
				(arc
					(start 56.077358 -318.282574)
					(mid 56.073638 -318.291554)
					(end 56.064658 -318.295274)
				)
				(arc
					(start 54.591458 -318.295274)
					(mid 54.582478 -318.291554)
					(end 54.578758 -318.282574)
				)
				(arc
					(start 54.578758 -317.788036)
					(mid 54.582478 -317.779056)
					(end 54.591458 -317.775336)
				)
				(arc
					(start 56.064658 -317.775336)
					(mid 56.073638 -317.779056)
					(end 56.077358 -317.788036)
				)
			)
		)
	)
	(zone
		(layer "In1.Cu")
		(hatch none 0.5)
		(connect_pads
			(clearance 0)
		)
		(min_thickness 0.25)
		(keepout
			(tracks not_allowed)
			(vias allowed)
			(pads allowed)
			(copperpour not_allowed)
			(footprints allowed)
		)
		(placement
			(enabled no)
			(sheetname "")
		)
		(fill
			(thermal_gap 0.5)
			(thermal_bridge_width 0.5)
			(island_removal_mode 0)
		)
		(polygon
			(pts
				(arc
					(start 87.189056 -385.31038)
					(mid 86.808056 -385.31038)
					(end 87.189056 -385.31038)
				)
			)
		)
	)
	(zone
		(layer "In1.Cu")
		(hatch none 0.5)
		(connect_pads
			(clearance 0)
		)
		(min_thickness 0.25)
		(keepout
			(tracks not_allowed)
			(vias allowed)
			(pads allowed)
			(copperpour not_allowed)
			(footprints allowed)
		)
		(placement
			(enabled no)
			(sheetname "")
		)
		(fill
			(thermal_gap 0.5)
			(thermal_bridge_width 0.5)
			(island_removal_mode 0)
		)
		(polygon
			(pts
				(arc
					(start 206.9973 -210.332574)
					(mid 206.99358 -210.341554)
					(end 206.9846 -210.345274)
				)
				(arc
					(start 205.5114 -210.345274)
					(mid 205.50242 -210.341554)
					(end 205.4987 -210.332574)
				)
				(arc
					(start 205.4987 -209.838036)
					(mid 205.50242 -209.829056)
					(end 205.5114 -209.825336)
				)
				(arc
					(start 206.9846 -209.825336)
					(mid 206.99358 -209.829056)
					(end 206.9973 -209.838036)
				)
			)
		)
	)
	(zone
		(layer "In1.Cu")
		(hatch none 0.5)
		(connect_pads
			(clearance 0)
		)
		(min_thickness 0.25)
		(keepout
			(tracks not_allowed)
			(vias allowed)
			(pads allowed)
			(copperpour not_allowed)
			(footprints allowed)
		)
		(placement
			(enabled no)
			(sheetname "")
		)
		(fill
			(thermal_gap 0.5)
			(thermal_bridge_width 0.5)
			(island_removal_mode 0)
		)
		(polygon
			(pts
				(arc
					(start 417.217352 -211.182204)
					(mid 417.213632 -211.191184)
					(end 417.204652 -211.194904)
				)
				(arc
					(start 415.731452 -211.194904)
					(mid 415.722472 -211.191184)
					(end 415.718752 -211.182204)
				)
				(arc
					(start 415.718752 -210.687666)
					(mid 415.722472 -210.678686)
					(end 415.731452 -210.674966)
				)
				(arc
					(start 417.204652 -210.674966)
					(mid 417.213632 -210.678686)
					(end 417.217352 -210.687666)
				)
			)
		)
	)
	(zone
		(layer "In1.Cu")
		(hatch none 0.5)
		(connect_pads
			(clearance 0)
		)
		(min_thickness 0.25)
		(keepout
			(tracks not_allowed)
			(vias allowed)
			(pads allowed)
			(copperpour not_allowed)
			(footprints allowed)
		)
		(placement
			(enabled no)
			(sheetname "")
		)
		(fill
			(thermal_gap 0.5)
			(thermal_bridge_width 0.5)
			(island_removal_mode 0)
		)
		(polygon
			(pts
				(arc
					(start 187.809378 -241.782346)
					(mid 187.805658 -241.791326)
					(end 187.796678 -241.795046)
				)
				(arc
					(start 186.323478 -241.795046)
					(mid 186.314498 -241.791326)
					(end 186.310778 -241.782346)
				)
				(arc
					(start 186.310778 -241.287808)
					(mid 186.314498 -241.278828)
					(end 186.323478 -241.275108)
				)
				(arc
					(start 187.796678 -241.275108)
					(mid 187.805658 -241.278828)
					(end 187.809378 -241.287808)
				)
			)
		)
	)
	(zone
		(layer "In1.Cu")
		(hatch none 0.5)
		(connect_pads
			(clearance 0)
		)
		(min_thickness 0.25)
		(keepout
			(tracks not_allowed)
			(vias allowed)
			(pads allowed)
			(copperpour not_allowed)
			(footprints allowed)
		)
		(placement
			(enabled no)
			(sheetname "")
		)
		(fill
			(thermal_gap 0.5)
			(thermal_bridge_width 0.5)
			(island_removal_mode 0)
		)
		(polygon
			(pts
				(arc
					(start 20.652232 -7.672324)
					(mid 20.67455 -7.618442)
					(end 20.728432 -7.596124)
				)
				(arc
					(start 21.765006 -7.596124)
					(mid 21.818888 -7.618442)
					(end 21.841206 -7.672324)
				)
				(arc
					(start 21.841206 -9.071864)
					(mid 21.818888 -9.125746)
					(end 21.765006 -9.148064)
				)
				(arc
					(start 20.728432 -9.148064)
					(mid 20.67455 -9.125746)
					(end 20.652232 -9.071864)
				)
			)
		)
	)
	(zone
		(layer "In1.Cu")
		(hatch none 0.5)
		(connect_pads
			(clearance 0)
		)
		(min_thickness 0.25)
		(keepout
			(tracks not_allowed)
			(vias allowed)
			(pads allowed)
			(copperpour not_allowed)
			(footprints allowed)
		)
		(placement
			(enabled no)
			(sheetname "")
		)
		(fill
			(thermal_gap 0.5)
			(thermal_bridge_width 0.5)
			(island_removal_mode 0)
		)
		(polygon
			(pts
				(arc
					(start 37.545264 -276.632416)
					(mid 37.541544 -276.641396)
					(end 37.532564 -276.645116)
				)
				(arc
					(start 36.059364 -276.645116)
					(mid 36.050384 -276.641396)
					(end 36.046664 -276.632416)
				)
				(arc
					(start 36.046664 -276.137878)
					(mid 36.050384 -276.128898)
					(end 36.059364 -276.125178)
				)
				(arc
					(start 37.532564 -276.125178)
					(mid 37.541544 -276.128898)
					(end 37.545264 -276.137878)
				)
			)
		)
	)
	(zone
		(layer "In1.Cu")
		(hatch none 0.5)
		(connect_pads
			(clearance 0)
		)
		(min_thickness 0.25)
		(keepout
			(tracks not_allowed)
			(vias allowed)
			(pads allowed)
			(copperpour not_allowed)
			(footprints allowed)
		)
		(placement
			(enabled no)
			(sheetname "")
		)
		(fill
			(thermal_gap 0.5)
			(thermal_bridge_width 0.5)
			(island_removal_mode 0)
		)
		(polygon
			(pts
				(arc
					(start 447.393568 -287.682178)
					(mid 447.389848 -287.691158)
					(end 447.380868 -287.694878)
				)
				(arc
					(start 445.907668 -287.694878)
					(mid 445.898688 -287.691158)
					(end 445.894968 -287.682178)
				)
				(arc
					(start 445.894968 -287.18764)
					(mid 445.898688 -287.17866)
					(end 445.907668 -287.17494)
				)
				(arc
					(start 447.380868 -287.17494)
					(mid 447.389848 -287.17866)
					(end 447.393568 -287.18764)
				)
			)
		)
	)
	(zone
		(layer "In1.Cu")
		(hatch none 0.5)
		(connect_pads
			(clearance 0)
		)
		(min_thickness 0.25)
		(keepout
			(tracks not_allowed)
			(vias allowed)
			(pads allowed)
			(copperpour not_allowed)
			(footprints allowed)
		)
		(placement
			(enabled no)
			(sheetname "")
		)
		(fill
			(thermal_gap 0.5)
			(thermal_bridge_width 0.5)
			(island_removal_mode 0)
		)
		(polygon
			(pts
				(arc
					(start 447.393568 -227.332286)
					(mid 447.389848 -227.341266)
					(end 447.380868 -227.344986)
				)
				(arc
					(start 445.907668 -227.344986)
					(mid 445.898688 -227.341266)
					(end 445.894968 -227.332286)
				)
				(arc
					(start 445.894968 -226.837748)
					(mid 445.898688 -226.828768)
					(end 445.907668 -226.825048)
				)
				(arc
					(start 447.380868 -226.825048)
					(mid 447.389848 -226.828768)
					(end 447.393568 -226.837748)
				)
			)
		)
	)
	(zone
		(layer "In1.Cu")
		(hatch none 0.5)
		(connect_pads
			(clearance 0)
		)
		(min_thickness 0.25)
		(keepout
			(tracks not_allowed)
			(vias allowed)
			(pads allowed)
			(copperpour not_allowed)
			(footprints allowed)
		)
		(placement
			(enabled no)
			(sheetname "")
		)
		(fill
			(thermal_gap 0.5)
			(thermal_bridge_width 0.5)
			(island_removal_mode 0)
		)
		(polygon
			(pts
				(arc
					(start 454.937368 -317.432182)
					(mid 454.933648 -317.441162)
					(end 454.924668 -317.444882)
				)
				(arc
					(start 453.451468 -317.444882)
					(mid 453.442488 -317.441162)
					(end 453.438768 -317.432182)
				)
				(arc
					(start 453.438768 -316.937644)
					(mid 453.442488 -316.928664)
					(end 453.451468 -316.924944)
				)
				(arc
					(start 454.924668 -316.924944)
					(mid 454.933648 -316.928664)
					(end 454.937368 -316.937644)
				)
			)
		)
	)
	(zone
		(layer "In1.Cu")
		(hatch none 0.5)
		(connect_pads
			(clearance 0)
		)
		(min_thickness 0.25)
		(keepout
			(tracks not_allowed)
			(vias allowed)
			(pads allowed)
			(copperpour not_allowed)
			(footprints allowed)
		)
		(placement
			(enabled no)
			(sheetname "")
		)
		(fill
			(thermal_gap 0.5)
			(thermal_bridge_width 0.5)
			(island_removal_mode 0)
		)
		(polygon
			(pts
				(arc
					(start 443.2935 -206.082138)
					(mid 443.28978 -206.091118)
					(end 443.2808 -206.094838)
				)
				(arc
					(start 441.8076 -206.094838)
					(mid 441.79862 -206.091118)
					(end 441.7949 -206.082138)
				)
				(arc
					(start 441.7949 -205.5876)
					(mid 441.79862 -205.57862)
					(end 441.8076 -205.5749)
				)
				(arc
					(start 443.2808 -205.5749)
					(mid 443.28978 -205.57862)
					(end 443.2935 -205.5876)
				)
			)
		)
	)
	(zone
		(layer "In1.Cu")
		(hatch none 0.5)
		(connect_pads
			(clearance 0)
		)
		(min_thickness 0.25)
		(keepout
			(tracks not_allowed)
			(vias allowed)
			(pads allowed)
			(copperpour not_allowed)
			(footprints allowed)
		)
		(placement
			(enabled no)
			(sheetname "")
		)
		(fill
			(thermal_gap 0.5)
			(thermal_bridge_width 0.5)
			(island_removal_mode 0)
		)
		(polygon
			(pts
				(arc
					(start 266.29741 -215.432132)
					(mid 266.29369 -215.441112)
					(end 266.28471 -215.444832)
				)
				(arc
					(start 264.81151 -215.444832)
					(mid 264.80253 -215.441112)
					(end 264.79881 -215.432132)
				)
				(arc
					(start 264.79881 -214.937594)
					(mid 264.80253 -214.928614)
					(end 264.81151 -214.924894)
				)
				(arc
					(start 266.28471 -214.924894)
					(mid 266.29369 -214.928614)
					(end 266.29741 -214.937594)
				)
			)
		)
	)
	(zone
		(layer "In1.Cu")
		(hatch none 0.5)
		(connect_pads
			(clearance 0)
		)
		(min_thickness 0.25)
		(keepout
			(tracks not_allowed)
			(vias allowed)
			(pads allowed)
			(copperpour not_allowed)
			(footprints allowed)
		)
		(placement
			(enabled no)
			(sheetname "")
		)
		(fill
			(thermal_gap 0.5)
			(thermal_bridge_width 0.5)
			(island_removal_mode 0)
		)
		(polygon
			(pts
				(arc
					(start 439.849514 -292.782244)
					(mid 439.845794 -292.791224)
					(end 439.836814 -292.794944)
				)
				(arc
					(start 438.363614 -292.794944)
					(mid 438.354634 -292.791224)
					(end 438.350914 -292.782244)
				)
				(arc
					(start 438.350914 -292.287706)
					(mid 438.354634 -292.278726)
					(end 438.363614 -292.275006)
				)
				(arc
					(start 439.836814 -292.275006)
					(mid 439.845794 -292.278726)
					(end 439.849514 -292.287706)
				)
			)
		)
	)
	(zone
		(layer "In1.Cu")
		(hatch none 0.5)
		(connect_pads
			(clearance 0)
		)
		(min_thickness 0.25)
		(keepout
			(tracks not_allowed)
			(vias allowed)
			(pads allowed)
			(copperpour not_allowed)
			(footprints allowed)
		)
		(placement
			(enabled no)
			(sheetname "")
		)
		(fill
			(thermal_gap 0.5)
			(thermal_bridge_width 0.5)
			(island_removal_mode 0)
		)
		(polygon
			(pts
				(arc
					(start 304.017426 -239.232186)
					(mid 304.013706 -239.241166)
					(end 304.004726 -239.244886)
				)
				(arc
					(start 302.531526 -239.244886)
					(mid 302.522546 -239.241166)
					(end 302.518826 -239.232186)
				)
				(arc
					(start 302.518826 -238.737648)
					(mid 302.522546 -238.728668)
					(end 302.531526 -238.724948)
				)
				(arc
					(start 304.004726 -238.724948)
					(mid 304.013706 -238.728668)
					(end 304.017426 -238.737648)
				)
			)
		)
	)
	(zone
		(layer "In1.Cu")
		(hatch none 0.5)
		(connect_pads
			(clearance 0)
		)
		(min_thickness 0.25)
		(keepout
			(tracks not_allowed)
			(vias allowed)
			(pads allowed)
			(copperpour not_allowed)
			(footprints allowed)
		)
		(placement
			(enabled no)
			(sheetname "")
		)
		(fill
			(thermal_gap 0.5)
			(thermal_bridge_width 0.5)
			(island_removal_mode 0)
		)
		(polygon
			(pts
				(arc
					(start 300.57344 -308.082188)
					(mid 300.56972 -308.091168)
					(end 300.56074 -308.094888)
				)
				(arc
					(start 299.08754 -308.094888)
					(mid 299.07856 -308.091168)
					(end 299.07484 -308.082188)
				)
				(arc
					(start 299.07484 -307.58765)
					(mid 299.07856 -307.57867)
					(end 299.08754 -307.57495)
				)
				(arc
					(start 300.56074 -307.57495)
					(mid 300.56972 -307.57867)
					(end 300.57344 -307.58765)
				)
			)
		)
	)
	(zone
		(layer "In1.Cu")
		(hatch none 0.5)
		(connect_pads
			(clearance 0)
		)
		(min_thickness 0.25)
		(keepout
			(tracks not_allowed)
			(vias allowed)
			(pads allowed)
			(copperpour not_allowed)
			(footprints allowed)
		)
		(placement
			(enabled no)
			(sheetname "")
		)
		(fill
			(thermal_gap 0.5)
			(thermal_bridge_width 0.5)
			(island_removal_mode 0)
		)
		(polygon
			(pts
				(arc
					(start 130.161284 -385.31038)
					(mid 129.780284 -385.31038)
					(end 130.161284 -385.31038)
				)
			)
		)
	)
	(zone
		(layer "In1.Cu")
		(hatch none 0.5)
		(connect_pads
			(clearance 0)
		)
		(min_thickness 0.25)
		(keepout
			(tracks not_allowed)
			(vias allowed)
			(pads allowed)
			(copperpour not_allowed)
			(footprints allowed)
		)
		(placement
			(enabled no)
			(sheetname "")
		)
		(fill
			(thermal_gap 0.5)
			(thermal_bridge_width 0.5)
			(island_removal_mode 0)
		)
		(polygon
			(pts
				(arc
					(start 304.017426 -251.982224)
					(mid 304.013706 -251.991204)
					(end 304.004726 -251.994924)
				)
				(arc
					(start 302.531526 -251.994924)
					(mid 302.522546 -251.991204)
					(end 302.518826 -251.982224)
				)
				(arc
					(start 302.518826 -251.487686)
					(mid 302.522546 -251.478706)
					(end 302.531526 -251.474986)
				)
				(arc
					(start 304.004726 -251.474986)
					(mid 304.013706 -251.478706)
					(end 304.017426 -251.487686)
				)
			)
		)
	)
	(zone
		(layer "In1.Cu")
		(hatch none 0.5)
		(connect_pads
			(clearance 0)
		)
		(min_thickness 0.25)
		(keepout
			(tracks not_allowed)
			(vias allowed)
			(pads allowed)
			(copperpour not_allowed)
			(footprints allowed)
		)
		(placement
			(enabled no)
			(sheetname "")
		)
		(fill
			(thermal_gap 0.5)
			(thermal_bridge_width 0.5)
			(island_removal_mode 0)
		)
		(polygon
			(pts
				(arc
					(start 22.45741 -222.232474)
					(mid 22.45369 -222.241454)
					(end 22.44471 -222.245174)
				)
				(arc
					(start 20.97151 -222.245174)
					(mid 20.96253 -222.241454)
					(end 20.95881 -222.232474)
				)
				(arc
					(start 20.95881 -221.737936)
					(mid 20.96253 -221.728956)
					(end 20.97151 -221.725236)
				)
				(arc
					(start 22.44471 -221.725236)
					(mid 22.45369 -221.728956)
					(end 22.45741 -221.737936)
				)
			)
		)
	)
	(zone
		(layer "In1.Cu")
		(hatch none 0.5)
		(connect_pads
			(clearance 0)
		)
		(min_thickness 0.25)
		(keepout
			(tracks not_allowed)
			(vias allowed)
			(pads allowed)
			(copperpour not_allowed)
			(footprints allowed)
		)
		(placement
			(enabled no)
			(sheetname "")
		)
		(fill
			(thermal_gap 0.5)
			(thermal_bridge_width 0.5)
			(island_removal_mode 0)
		)
		(polygon
			(pts
				(arc
					(start 172.72127 -215.432386)
					(mid 172.71755 -215.441366)
					(end 172.70857 -215.445086)
				)
				(arc
					(start 171.23537 -215.445086)
					(mid 171.22639 -215.441366)
					(end 171.22267 -215.432386)
				)
				(arc
					(start 171.22267 -214.937848)
					(mid 171.22639 -214.928868)
					(end 171.23537 -214.925148)
				)
				(arc
					(start 172.70857 -214.925148)
					(mid 172.71755 -214.928868)
					(end 172.72127 -214.937848)
				)
			)
		)
	)
	(zone
		(layer "In1.Cu")
		(hatch none 0.5)
		(connect_pads
			(clearance 0)
		)
		(min_thickness 0.25)
		(keepout
			(tracks not_allowed)
			(vias allowed)
			(pads allowed)
			(copperpour not_allowed)
			(footprints allowed)
		)
		(placement
			(enabled no)
			(sheetname "")
		)
		(fill
			(thermal_gap 0.5)
			(thermal_bridge_width 0.5)
			(island_removal_mode 0)
		)
		(polygon
			(pts
				(arc
					(start 307.170074 -399.143474)
					(mid 306.865274 -399.143474)
					(end 307.170074 -399.143474)
				)
			)
		)
	)
	(zone
		(layer "In1.Cu")
		(hatch none 0.5)
		(connect_pads
			(clearance 0)
		)
		(min_thickness 0.25)
		(keepout
			(tracks not_allowed)
			(vias allowed)
			(pads allowed)
			(copperpour not_allowed)
			(footprints allowed)
		)
		(placement
			(enabled no)
			(sheetname "")
		)
		(fill
			(thermal_gap 0.5)
			(thermal_bridge_width 0.5)
			(island_removal_mode 0)
		)
		(polygon
			(pts
				(arc
					(start 165.177216 -200.132442)
					(mid 165.173496 -200.141422)
					(end 165.164516 -200.145142)
				)
				(arc
					(start 163.691316 -200.145142)
					(mid 163.682336 -200.141422)
					(end 163.678616 -200.132442)
				)
				(arc
					(start 163.678616 -199.637904)
					(mid 163.682336 -199.628924)
					(end 163.691316 -199.625204)
				)
				(arc
					(start 165.164516 -199.625204)
					(mid 165.173496 -199.628924)
					(end 165.177216 -199.637904)
				)
			)
		)
	)
	(zone
		(layer "In1.Cu")
		(hatch none 0.5)
		(connect_pads
			(clearance 0)
		)
		(min_thickness 0.25)
		(keepout
			(tracks not_allowed)
			(vias allowed)
			(pads allowed)
			(copperpour not_allowed)
			(footprints allowed)
		)
		(placement
			(enabled no)
			(sheetname "")
		)
		(fill
			(thermal_gap 0.5)
			(thermal_bridge_width 0.5)
			(island_removal_mode 0)
		)
		(polygon
			(pts
				(arc
					(start 165.177216 -312.33237)
					(mid 165.173496 -312.34135)
					(end 165.164516 -312.34507)
				)
				(arc
					(start 163.691316 -312.34507)
					(mid 163.682336 -312.34135)
					(end 163.678616 -312.33237)
				)
				(arc
					(start 163.678616 -311.837832)
					(mid 163.682336 -311.828852)
					(end 163.691316 -311.825132)
				)
				(arc
					(start 165.164516 -311.825132)
					(mid 165.173496 -311.828852)
					(end 165.177216 -311.837832)
				)
			)
		)
	)
	(zone
		(layer "In1.Cu")
		(hatch none 0.5)
		(connect_pads
			(clearance 0)
		)
		(min_thickness 0.25)
		(keepout
			(tracks not_allowed)
			(vias allowed)
			(pads allowed)
			(copperpour not_allowed)
			(footprints allowed)
		)
		(placement
			(enabled no)
			(sheetname "")
		)
		(fill
			(thermal_gap 0.5)
			(thermal_bridge_width 0.5)
			(island_removal_mode 0)
		)
		(polygon
			(pts
				(arc
					(start 428.205392 -221.382082)
					(mid 428.201672 -221.391062)
					(end 428.192692 -221.394782)
				)
				(arc
					(start 426.719492 -221.394782)
					(mid 426.710512 -221.391062)
					(end 426.706792 -221.382082)
				)
				(arc
					(start 426.706792 -220.887544)
					(mid 426.710512 -220.878564)
					(end 426.719492 -220.874844)
				)
				(arc
					(start 428.192692 -220.874844)
					(mid 428.201672 -220.878564)
					(end 428.205392 -220.887544)
				)
			)
		)
	)
	(zone
		(layer "In1.Cu")
		(hatch none 0.5)
		(connect_pads
			(clearance 0)
		)
		(min_thickness 0.25)
		(keepout
			(tracks not_allowed)
			(vias allowed)
			(pads allowed)
			(copperpour not_allowed)
			(footprints allowed)
		)
		(placement
			(enabled no)
			(sheetname "")
		)
		(fill
			(thermal_gap 0.5)
			(thermal_bridge_width 0.5)
			(island_removal_mode 0)
		)
		(polygon
			(pts
				(arc
					(start 172.72127 -285.98241)
					(mid 172.71755 -285.99139)
					(end 172.70857 -285.99511)
				)
				(arc
					(start 171.23537 -285.99511)
					(mid 171.22639 -285.99139)
					(end 171.22267 -285.98241)
				)
				(arc
					(start 171.22267 -285.487872)
					(mid 171.22639 -285.478892)
					(end 171.23537 -285.475172)
				)
				(arc
					(start 172.70857 -285.475172)
					(mid 172.71755 -285.478892)
					(end 172.72127 -285.487872)
				)
			)
		)
	)
	(zone
		(layer "In1.Cu")
		(hatch none 0.5)
		(connect_pads
			(clearance 0)
		)
		(min_thickness 0.25)
		(keepout
			(tracks not_allowed)
			(vias allowed)
			(pads allowed)
			(copperpour not_allowed)
			(footprints allowed)
		)
		(placement
			(enabled no)
			(sheetname "")
		)
		(fill
			(thermal_gap 0.5)
			(thermal_bridge_width 0.5)
			(island_removal_mode 0)
		)
		(polygon
			(pts
				(arc
					(start 417.217352 -206.932276)
					(mid 417.213632 -206.941256)
					(end 417.204652 -206.944976)
				)
				(arc
					(start 415.731452 -206.944976)
					(mid 415.722472 -206.941256)
					(end 415.718752 -206.932276)
				)
				(arc
					(start 415.718752 -206.437738)
					(mid 415.722472 -206.428758)
					(end 415.731452 -206.425038)
				)
				(arc
					(start 417.204652 -206.425038)
					(mid 417.213632 -206.428758)
					(end 417.217352 -206.437738)
				)
			)
		)
	)
	(zone
		(layer "In1.Cu")
		(hatch none 0.5)
		(connect_pads
			(clearance 0)
		)
		(min_thickness 0.25)
		(keepout
			(tracks not_allowed)
			(vias allowed)
			(pads allowed)
			(copperpour not_allowed)
			(footprints allowed)
		)
		(placement
			(enabled no)
			(sheetname "")
		)
		(fill
			(thermal_gap 0.5)
			(thermal_bridge_width 0.5)
			(island_removal_mode 0)
		)
		(polygon
			(pts
				(arc
					(start 281.385264 -268.98219)
					(mid 281.381544 -268.99117)
					(end 281.372564 -268.99489)
				)
				(arc
					(start 279.899364 -268.99489)
					(mid 279.890384 -268.99117)
					(end 279.886664 -268.98219)
				)
				(arc
					(start 279.886664 -268.487652)
					(mid 279.890384 -268.478672)
					(end 279.899364 -268.474952)
				)
				(arc
					(start 281.372564 -268.474952)
					(mid 281.381544 -268.478672)
					(end 281.385264 -268.487652)
				)
			)
		)
	)
	(zone
		(layer "In1.Cu")
		(hatch none 0.5)
		(connect_pads
			(clearance 0)
		)
		(min_thickness 0.25)
		(keepout
			(tracks not_allowed)
			(vias allowed)
			(pads allowed)
			(copperpour not_allowed)
			(footprints allowed)
		)
		(placement
			(enabled no)
			(sheetname "")
		)
		(fill
			(thermal_gap 0.5)
			(thermal_bridge_width 0.5)
			(island_removal_mode 0)
		)
		(polygon
			(pts
				(arc
					(start 40.98925 -198.43242)
					(mid 40.98553 -198.4414)
					(end 40.97655 -198.44512)
				)
				(arc
					(start 39.50335 -198.44512)
					(mid 39.49437 -198.4414)
					(end 39.49065 -198.43242)
				)
				(arc
					(start 39.49065 -197.937882)
					(mid 39.49437 -197.928902)
					(end 39.50335 -197.925182)
				)
				(arc
					(start 40.97655 -197.925182)
					(mid 40.98553 -197.928902)
					(end 40.98925 -197.937882)
				)
			)
		)
	)
	(zone
		(layer "In1.Cu")
		(hatch none 0.5)
		(connect_pads
			(clearance 0)
		)
		(min_thickness 0.25)
		(keepout
			(tracks not_allowed)
			(vias allowed)
			(pads allowed)
			(copperpour not_allowed)
			(footprints allowed)
		)
		(placement
			(enabled no)
			(sheetname "")
		)
		(fill
			(thermal_gap 0.5)
			(thermal_bridge_width 0.5)
			(island_removal_mode 0)
		)
		(polygon
			(pts
				(arc
					(start 206.9973 -242.632484)
					(mid 206.99358 -242.641464)
					(end 206.9846 -242.645184)
				)
				(arc
					(start 205.5114 -242.645184)
					(mid 205.50242 -242.641464)
					(end 205.4987 -242.632484)
				)
				(arc
					(start 205.4987 -242.137946)
					(mid 205.50242 -242.128966)
					(end 205.5114 -242.125246)
				)
				(arc
					(start 206.9846 -242.125246)
					(mid 206.99358 -242.128966)
					(end 206.9973 -242.137946)
				)
			)
		)
	)
	(zone
		(layer "In1.Cu")
		(hatch none 0.5)
		(connect_pads
			(clearance 0)
		)
		(min_thickness 0.25)
		(keepout
			(tracks not_allowed)
			(vias allowed)
			(pads allowed)
			(copperpour not_allowed)
			(footprints allowed)
		)
		(placement
			(enabled no)
			(sheetname "")
		)
		(fill
			(thermal_gap 0.5)
			(thermal_bridge_width 0.5)
			(island_removal_mode 0)
		)
		(polygon
			(pts
				(arc
					(start 373.36095 -394.385292)
					(mid 372.97995 -394.385292)
					(end 373.36095 -394.385292)
				)
			)
		)
	)
	(zone
		(layer "In1.Cu")
		(hatch none 0.5)
		(connect_pads
			(clearance 0)
		)
		(min_thickness 0.25)
		(keepout
			(tracks not_allowed)
			(vias allowed)
			(pads allowed)
			(copperpour not_allowed)
			(footprints allowed)
		)
		(placement
			(enabled no)
			(sheetname "")
		)
		(fill
			(thermal_gap 0.5)
			(thermal_bridge_width 0.5)
			(island_removal_mode 0)
		)
		(polygon
			(pts
				(arc
					(start 37.545264 -211.182458)
					(mid 37.541544 -211.191438)
					(end 37.532564 -211.195158)
				)
				(arc
					(start 36.059364 -211.195158)
					(mid 36.050384 -211.191438)
					(end 36.046664 -211.182458)
				)
				(arc
					(start 36.046664 -210.68792)
					(mid 36.050384 -210.67894)
					(end 36.059364 -210.67522)
				)
				(arc
					(start 37.532564 -210.67522)
					(mid 37.541544 -210.67894)
					(end 37.545264 -210.68792)
				)
			)
		)
	)
	(zone
		(layer "In1.Cu")
		(hatch none 0.5)
		(connect_pads
			(clearance 0)
		)
		(min_thickness 0.25)
		(keepout
			(tracks not_allowed)
			(vias allowed)
			(pads allowed)
			(copperpour not_allowed)
			(footprints allowed)
		)
		(placement
			(enabled no)
			(sheetname "")
		)
		(fill
			(thermal_gap 0.5)
			(thermal_bridge_width 0.5)
			(island_removal_mode 0)
		)
		(polygon
			(pts
				(arc
					(start 22.45741 -304.682398)
					(mid 22.45369 -304.691378)
					(end 22.44471 -304.695098)
				)
				(arc
					(start 20.97151 -304.695098)
					(mid 20.96253 -304.691378)
					(end 20.95881 -304.682398)
				)
				(arc
					(start 20.95881 -304.18786)
					(mid 20.96253 -304.17888)
					(end 20.97151 -304.17516)
				)
				(arc
					(start 22.44471 -304.17516)
					(mid 22.45369 -304.17888)
					(end 22.45741 -304.18786)
				)
			)
		)
	)
	(zone
		(layer "In1.Cu")
		(hatch none 0.5)
		(connect_pads
			(clearance 0)
		)
		(min_thickness 0.25)
		(keepout
			(tracks not_allowed)
			(vias allowed)
			(pads allowed)
			(copperpour not_allowed)
			(footprints allowed)
		)
		(placement
			(enabled no)
			(sheetname "")
		)
		(fill
			(thermal_gap 0.5)
			(thermal_bridge_width 0.5)
			(island_removal_mode 0)
		)
		(polygon
			(pts
				(arc
					(start 206.5782 -276.385274)
					(mid 205.9178 -276.385274)
					(end 206.5782 -276.385274)
				)
			)
		)
	)
	(zone
		(layer "In1.Cu")
		(hatch none 0.5)
		(connect_pads
			(clearance 0)
		)
		(min_thickness 0.25)
		(keepout
			(tracks not_allowed)
			(vias allowed)
			(pads allowed)
			(copperpour not_allowed)
			(footprints allowed)
		)
		(placement
			(enabled no)
			(sheetname "")
		)
		(fill
			(thermal_gap 0.5)
			(thermal_bridge_width 0.5)
			(island_removal_mode 0)
		)
		(polygon
			(pts
				(arc
					(start 33.445196 -200.132442)
					(mid 33.441476 -200.141422)
					(end 33.432496 -200.145142)
				)
				(arc
					(start 31.959296 -200.145142)
					(mid 31.950316 -200.141422)
					(end 31.946596 -200.132442)
				)
				(arc
					(start 31.946596 -199.637904)
					(mid 31.950316 -199.628924)
					(end 31.959296 -199.625204)
				)
				(arc
					(start 33.432496 -199.625204)
					(mid 33.441476 -199.628924)
					(end 33.445196 -199.637904)
				)
			)
		)
	)
	(zone
		(layer "In1.Cu")
		(hatch none 0.5)
		(connect_pads
			(clearance 0)
		)
		(min_thickness 0.25)
		(keepout
			(tracks not_allowed)
			(vias allowed)
			(pads allowed)
			(copperpour not_allowed)
			(footprints allowed)
		)
		(placement
			(enabled no)
			(sheetname "")
		)
		(fill
			(thermal_gap 0.5)
			(thermal_bridge_width 0.5)
			(island_removal_mode 0)
		)
		(polygon
			(pts
				(arc
					(start 336.09788 -399.143474)
					(mid 335.79308 -399.143474)
					(end 336.09788 -399.143474)
				)
			)
		)
	)
	(zone
		(layer "In1.Cu")
		(hatch none 0.5)
		(connect_pads
			(clearance 0)
		)
		(min_thickness 0.25)
		(keepout
			(tracks not_allowed)
			(vias allowed)
			(pads allowed)
			(copperpour not_allowed)
			(footprints allowed)
		)
		(placement
			(enabled no)
			(sheetname "")
		)
		(fill
			(thermal_gap 0.5)
			(thermal_bridge_width 0.5)
			(island_removal_mode 0)
		)
		(polygon
			(pts
				(arc
					(start 382.561338 -393.69238)
					(mid 382.180338 -393.69238)
					(end 382.561338 -393.69238)
				)
			)
		)
	)
	(zone
		(layer "In1.Cu")
		(hatch none 0.5)
		(connect_pads
			(clearance 0)
		)
		(min_thickness 0.25)
		(keepout
			(tracks not_allowed)
			(vias allowed)
			(pads allowed)
			(copperpour not_allowed)
			(footprints allowed)
		)
		(placement
			(enabled no)
			(sheetname "")
		)
		(fill
			(thermal_gap 0.5)
			(thermal_bridge_width 0.5)
			(island_removal_mode 0)
		)
		(polygon
			(pts
				(arc
					(start 202.897232 -290.232592)
					(mid 202.893512 -290.241572)
					(end 202.884532 -290.245292)
				)
				(arc
					(start 201.411332 -290.245292)
					(mid 201.402352 -290.241572)
					(end 201.398632 -290.232592)
				)
				(arc
					(start 201.398632 -289.738054)
					(mid 201.402352 -289.729074)
					(end 201.411332 -289.725354)
				)
				(arc
					(start 202.884532 -289.725354)
					(mid 202.893512 -289.729074)
					(end 202.897232 -289.738054)
				)
			)
		)
	)
	(zone
		(layer "In1.Cu")
		(hatch none 0.5)
		(connect_pads
			(clearance 0)
		)
		(min_thickness 0.25)
		(keepout
			(tracks not_allowed)
			(vias allowed)
			(pads allowed)
			(copperpour not_allowed)
			(footprints allowed)
		)
		(placement
			(enabled no)
			(sheetname "")
		)
		(fill
			(thermal_gap 0.5)
			(thermal_bridge_width 0.5)
			(island_removal_mode 0)
		)
		(polygon
			(pts
				(arc
					(start 450.8373 -223.082104)
					(mid 450.83358 -223.091084)
					(end 450.8246 -223.094804)
				)
				(arc
					(start 449.3514 -223.094804)
					(mid 449.34242 -223.091084)
					(end 449.3387 -223.082104)
				)
				(arc
					(start 449.3387 -222.587566)
					(mid 449.34242 -222.578586)
					(end 449.3514 -222.574866)
				)
				(arc
					(start 450.8246 -222.574866)
					(mid 450.83358 -222.578586)
					(end 450.8373 -222.587566)
				)
			)
		)
	)
	(zone
		(layer "In1.Cu")
		(hatch none 0.5)
		(connect_pads
			(clearance 0)
		)
		(min_thickness 0.25)
		(keepout
			(tracks not_allowed)
			(vias allowed)
			(pads allowed)
			(copperpour not_allowed)
			(footprints allowed)
		)
		(placement
			(enabled no)
			(sheetname "")
		)
		(fill
			(thermal_gap 0.5)
			(thermal_bridge_width 0.5)
			(island_removal_mode 0)
		)
		(polygon
			(pts
				(arc
					(start 420.661338 -299.582332)
					(mid 420.657618 -299.591312)
					(end 420.648638 -299.595032)
				)
				(arc
					(start 419.175438 -299.595032)
					(mid 419.166458 -299.591312)
					(end 419.162738 -299.582332)
				)
				(arc
					(start 419.162738 -299.087794)
					(mid 419.166458 -299.078814)
					(end 419.175438 -299.075094)
				)
				(arc
					(start 420.648638 -299.075094)
					(mid 420.657618 -299.078814)
					(end 420.661338 -299.087794)
				)
			)
		)
	)
	(zone
		(layer "In1.Cu")
		(hatch none 0.5)
		(connect_pads
			(clearance 0)
		)
		(min_thickness 0.25)
		(keepout
			(tracks not_allowed)
			(vias allowed)
			(pads allowed)
			(copperpour not_allowed)
			(footprints allowed)
		)
		(placement
			(enabled no)
			(sheetname "")
		)
		(fill
			(thermal_gap 0.5)
			(thermal_bridge_width 0.5)
			(island_removal_mode 0)
		)
		(polygon
			(pts
				(arc
					(start 82.78876 -386.003292)
					(mid 82.40776 -386.003292)
					(end 82.78876 -386.003292)
				)
			)
		)
	)
	(zone
		(layer "In1.Cu")
		(hatch none 0.5)
		(connect_pads
			(clearance 0)
		)
		(min_thickness 0.25)
		(keepout
			(tracks not_allowed)
			(vias allowed)
			(pads allowed)
			(copperpour not_allowed)
			(footprints allowed)
		)
		(placement
			(enabled no)
			(sheetname "")
		)
		(fill
			(thermal_gap 0.5)
			(thermal_bridge_width 0.5)
			(island_removal_mode 0)
		)
		(polygon
			(pts
				(arc
					(start 56.261 -386.003292)
					(mid 55.88 -386.003292)
					(end 56.261 -386.003292)
				)
			)
		)
	)
	(zone
		(layer "In1.Cu")
		(hatch none 0.5)
		(connect_pads
			(clearance 0)
		)
		(min_thickness 0.25)
		(keepout
			(tracks not_allowed)
			(vias allowed)
			(pads allowed)
			(copperpour not_allowed)
			(footprints allowed)
		)
		(placement
			(enabled no)
			(sheetname "")
		)
		(fill
			(thermal_gap 0.5)
			(thermal_bridge_width 0.5)
			(island_removal_mode 0)
		)
		(polygon
			(pts
				(arc
					(start 277.941532 -247.732296)
					(mid 277.937812 -247.741276)
					(end 277.928832 -247.744996)
				)
				(arc
					(start 276.455632 -247.744996)
					(mid 276.446652 -247.741276)
					(end 276.442932 -247.732296)
				)
				(arc
					(start 276.442932 -247.237758)
					(mid 276.446652 -247.228778)
					(end 276.455632 -247.225058)
				)
				(arc
					(start 277.928832 -247.225058)
					(mid 277.937812 -247.228778)
					(end 277.941532 -247.237758)
				)
			)
		)
	)
	(zone
		(layer "In1.Cu")
		(hatch none 0.5)
		(connect_pads
			(clearance 0)
		)
		(min_thickness 0.25)
		(keepout
			(tracks not_allowed)
			(vias allowed)
			(pads allowed)
			(copperpour not_allowed)
			(footprints allowed)
		)
		(placement
			(enabled no)
			(sheetname "")
		)
		(fill
			(thermal_gap 0.5)
			(thermal_bridge_width 0.5)
			(island_removal_mode 0)
		)
		(polygon
			(pts
				(arc
					(start 25.901396 -301.282354)
					(mid 25.897676 -301.291334)
					(end 25.888696 -301.295054)
				)
				(arc
					(start 24.415496 -301.295054)
					(mid 24.406516 -301.291334)
					(end 24.402796 -301.282354)
				)
				(arc
					(start 24.402796 -300.787816)
					(mid 24.406516 -300.778836)
					(end 24.415496 -300.775116)
				)
				(arc
					(start 25.888696 -300.775116)
					(mid 25.897676 -300.778836)
					(end 25.901396 -300.787816)
				)
			)
		)
	)
	(zone
		(layer "In1.Cu")
		(hatch none 0.5)
		(connect_pads
			(clearance 0)
		)
		(min_thickness 0.25)
		(keepout
			(tracks not_allowed)
			(vias allowed)
			(pads allowed)
			(copperpour not_allowed)
			(footprints allowed)
		)
		(placement
			(enabled no)
			(sheetname "")
		)
		(fill
			(thermal_gap 0.5)
			(thermal_bridge_width 0.5)
			(island_removal_mode 0)
		)
		(polygon
			(pts
				(arc
					(start 341.188548 -397.849344)
					(mid 340.807548 -397.849344)
					(end 341.188548 -397.849344)
				)
			)
		)
	)
	(zone
		(layer "In1.Cu")
		(hatch none 0.5)
		(connect_pads
			(clearance 0)
		)
		(min_thickness 0.25)
		(keepout
			(tracks not_allowed)
			(vias allowed)
			(pads allowed)
			(copperpour not_allowed)
			(footprints allowed)
		)
		(placement
			(enabled no)
			(sheetname "")
		)
		(fill
			(thermal_gap 0.5)
			(thermal_bridge_width 0.5)
			(island_removal_mode 0)
		)
		(polygon
			(pts
				(arc
					(start 172.72127 -293.632382)
					(mid 172.71755 -293.641362)
					(end 172.70857 -293.645082)
				)
				(arc
					(start 171.23537 -293.645082)
					(mid 171.22639 -293.641362)
					(end 171.22267 -293.632382)
				)
				(arc
					(start 171.22267 -293.137844)
					(mid 171.22639 -293.128864)
					(end 171.23537 -293.125144)
				)
				(arc
					(start 172.70857 -293.125144)
					(mid 172.71755 -293.128864)
					(end 172.72127 -293.137844)
				)
			)
		)
	)
	(zone
		(layer "In1.Cu")
		(hatch none 0.5)
		(connect_pads
			(clearance 0)
		)
		(min_thickness 0.25)
		(keepout
			(tracks not_allowed)
			(vias allowed)
			(pads allowed)
			(copperpour not_allowed)
			(footprints allowed)
		)
		(placement
			(enabled no)
			(sheetname "")
		)
		(fill
			(thermal_gap 0.5)
			(thermal_bridge_width 0.5)
			(island_removal_mode 0)
		)
		(polygon
			(pts
				(arc
					(start 184.365392 -313.182508)
					(mid 184.361672 -313.191488)
					(end 184.352692 -313.195208)
				)
				(arc
					(start 182.879492 -313.195208)
					(mid 182.870512 -313.191488)
					(end 182.866792 -313.182508)
				)
				(arc
					(start 182.866792 -312.68797)
					(mid 182.870512 -312.67899)
					(end 182.879492 -312.67527)
				)
				(arc
					(start 184.352692 -312.67527)
					(mid 184.361672 -312.67899)
					(end 184.365392 -312.68797)
				)
			)
		)
	)
	(zone
		(layer "In1.Cu")
		(hatch none 0.5)
		(connect_pads
			(clearance 0)
		)
		(min_thickness 0.25)
		(keepout
			(tracks not_allowed)
			(vias allowed)
			(pads allowed)
			(copperpour not_allowed)
			(footprints allowed)
		)
		(placement
			(enabled no)
			(sheetname "")
		)
		(fill
			(thermal_gap 0.5)
			(thermal_bridge_width 0.5)
			(island_removal_mode 0)
		)
		(polygon
			(pts
				(arc
					(start 266.29741 -232.432098)
					(mid 266.29369 -232.441078)
					(end 266.28471 -232.444798)
				)
				(arc
					(start 264.81151 -232.444798)
					(mid 264.80253 -232.441078)
					(end 264.79881 -232.432098)
				)
				(arc
					(start 264.79881 -231.93756)
					(mid 264.80253 -231.92858)
					(end 264.81151 -231.92486)
				)
				(arc
					(start 266.28471 -231.92486)
					(mid 266.29369 -231.92858)
					(end 266.29741 -231.93756)
				)
			)
		)
	)
	(zone
		(layer "In1.Cu")
		(hatch none 0.5)
		(connect_pads
			(clearance 0)
		)
		(min_thickness 0.25)
		(keepout
			(tracks not_allowed)
			(vias allowed)
			(pads allowed)
			(copperpour not_allowed)
			(footprints allowed)
		)
		(placement
			(enabled no)
			(sheetname "")
		)
		(fill
			(thermal_gap 0.5)
			(thermal_bridge_width 0.5)
			(island_removal_mode 0)
		)
		(polygon
			(pts
				(arc
					(start 172.72127 -223.082358)
					(mid 172.71755 -223.091338)
					(end 172.70857 -223.095058)
				)
				(arc
					(start 171.23537 -223.095058)
					(mid 171.22639 -223.091338)
					(end 171.22267 -223.082358)
				)
				(arc
					(start 171.22267 -222.58782)
					(mid 171.22639 -222.57884)
					(end 171.23537 -222.57512)
				)
				(arc
					(start 172.70857 -222.57512)
					(mid 172.71755 -222.57884)
					(end 172.72127 -222.58782)
				)
			)
		)
	)
	(zone
		(layer "In1.Cu")
		(hatch none 0.5)
		(connect_pads
			(clearance 0)
		)
		(min_thickness 0.25)
		(keepout
			(tracks not_allowed)
			(vias allowed)
			(pads allowed)
			(copperpour not_allowed)
			(footprints allowed)
		)
		(placement
			(enabled no)
			(sheetname "")
		)
		(fill
			(thermal_gap 0.5)
			(thermal_bridge_width 0.5)
			(island_removal_mode 0)
		)
		(polygon
			(pts
				(arc
					(start 169.277284 -313.182508)
					(mid 169.273564 -313.191488)
					(end 169.264584 -313.195208)
				)
				(arc
					(start 167.791384 -313.195208)
					(mid 167.782404 -313.191488)
					(end 167.778684 -313.182508)
				)
				(arc
					(start 167.778684 -312.68797)
					(mid 167.782404 -312.67899)
					(end 167.791384 -312.67527)
				)
				(arc
					(start 169.264584 -312.67527)
					(mid 169.273564 -312.67899)
					(end 169.277284 -312.68797)
				)
			)
		)
	)
	(zone
		(layer "In1.Cu")
		(hatch none 0.5)
		(connect_pads
			(clearance 0)
		)
		(min_thickness 0.25)
		(keepout
			(tracks not_allowed)
			(vias allowed)
			(pads allowed)
			(copperpour not_allowed)
			(footprints allowed)
		)
		(placement
			(enabled no)
			(sheetname "")
		)
		(fill
			(thermal_gap 0.5)
			(thermal_bridge_width 0.5)
			(island_removal_mode 0)
		)
		(polygon
			(pts
				(arc
					(start 288.929318 -285.982156)
					(mid 288.925598 -285.991136)
					(end 288.916618 -285.994856)
				)
				(arc
					(start 287.443418 -285.994856)
					(mid 287.434438 -285.991136)
					(end 287.430718 -285.982156)
				)
				(arc
					(start 287.430718 -285.487618)
					(mid 287.434438 -285.478638)
					(end 287.443418 -285.474918)
				)
				(arc
					(start 288.916618 -285.474918)
					(mid 288.925598 -285.478638)
					(end 288.929318 -285.487618)
				)
			)
		)
	)
	(zone
		(layer "In1.Cu")
		(hatch none 0.5)
		(connect_pads
			(clearance 0)
		)
		(min_thickness 0.25)
		(keepout
			(tracks not_allowed)
			(vias allowed)
			(pads allowed)
			(copperpour not_allowed)
			(footprints allowed)
		)
		(placement
			(enabled no)
			(sheetname "")
		)
		(fill
			(thermal_gap 0.5)
			(thermal_bridge_width 0.5)
			(island_removal_mode 0)
		)
		(polygon
			(pts
				(arc
					(start 118.161308 -388.774432)
					(mid 117.780308 -388.774432)
					(end 118.161308 -388.774432)
				)
			)
		)
	)
	(zone
		(layer "In1.Cu")
		(hatch none 0.5)
		(connect_pads
			(clearance 0)
		)
		(min_thickness 0.25)
		(keepout
			(tracks not_allowed)
			(vias allowed)
			(pads allowed)
			(copperpour not_allowed)
			(footprints allowed)
		)
		(placement
			(enabled no)
			(sheetname "")
		)
		(fill
			(thermal_gap 0.5)
			(thermal_bridge_width 0.5)
			(island_removal_mode 0)
		)
		(polygon
			(pts
				(arc
					(start 381.361188 -397.156432)
					(mid 380.980188 -397.156432)
					(end 381.361188 -397.156432)
				)
			)
		)
	)
	(zone
		(layer "In1.Cu")
		(hatch none 0.5)
		(connect_pads
			(clearance 0)
		)
		(min_thickness 0.25)
		(keepout
			(tracks not_allowed)
			(vias allowed)
			(pads allowed)
			(copperpour not_allowed)
			(footprints allowed)
		)
		(placement
			(enabled no)
			(sheetname "")
		)
		(fill
			(thermal_gap 0.5)
			(thermal_bridge_width 0.5)
			(island_removal_mode 0)
		)
		(polygon
			(pts
				(arc
					(start 288.929318 -204.382116)
					(mid 288.925598 -204.391096)
					(end 288.916618 -204.394816)
				)
				(arc
					(start 287.443418 -204.394816)
					(mid 287.434438 -204.391096)
					(end 287.430718 -204.382116)
				)
				(arc
					(start 287.430718 -203.887578)
					(mid 287.434438 -203.878598)
					(end 287.443418 -203.874878)
				)
				(arc
					(start 288.916618 -203.874878)
					(mid 288.925598 -203.878598)
					(end 288.929318 -203.887578)
				)
			)
		)
	)
	(zone
		(layer "In1.Cu")
		(hatch none 0.5)
		(connect_pads
			(clearance 0)
		)
		(min_thickness 0.25)
		(keepout
			(tracks not_allowed)
			(vias allowed)
			(pads allowed)
			(copperpour not_allowed)
			(footprints allowed)
		)
		(placement
			(enabled no)
			(sheetname "")
		)
		(fill
			(thermal_gap 0.5)
			(thermal_bridge_width 0.5)
			(island_removal_mode 0)
		)
		(polygon
			(pts
				(arc
					(start 86.098126 -383.92227)
					(mid 85.793326 -383.92227)
					(end 86.098126 -383.92227)
				)
			)
		)
	)
	(zone
		(layer "In1.Cu")
		(hatch none 0.5)
		(connect_pads
			(clearance 0)
		)
		(min_thickness 0.25)
		(keepout
			(tracks not_allowed)
			(vias allowed)
			(pads allowed)
			(copperpour not_allowed)
			(footprints allowed)
		)
		(placement
			(enabled no)
			(sheetname "")
		)
		(fill
			(thermal_gap 0.5)
			(thermal_bridge_width 0.5)
			(island_removal_mode 0)
		)
		(polygon
			(pts
				(arc
					(start 18.357342 -207.782414)
					(mid 18.353622 -207.791394)
					(end 18.344642 -207.795114)
				)
				(arc
					(start 16.871442 -207.795114)
					(mid 16.862462 -207.791394)
					(end 16.858742 -207.782414)
				)
				(arc
					(start 16.858742 -207.287876)
					(mid 16.862462 -207.278896)
					(end 16.871442 -207.275176)
				)
				(arc
					(start 18.344642 -207.275176)
					(mid 18.353622 -207.278896)
					(end 18.357342 -207.287876)
				)
			)
		)
	)
	(zone
		(layer "In1.Cu")
		(hatch none 0.5)
		(connect_pads
			(clearance 0)
		)
		(min_thickness 0.25)
		(keepout
			(tracks not_allowed)
			(vias allowed)
			(pads allowed)
			(copperpour not_allowed)
			(footprints allowed)
		)
		(placement
			(enabled no)
			(sheetname "")
		)
		(fill
			(thermal_gap 0.5)
			(thermal_bridge_width 0.5)
			(island_removal_mode 0)
		)
		(polygon
			(pts
				(arc
					(start 450.8373 -297.88231)
					(mid 450.83358 -297.89129)
					(end 450.8246 -297.89501)
				)
				(arc
					(start 449.3514 -297.89501)
					(mid 449.34242 -297.89129)
					(end 449.3387 -297.88231)
				)
				(arc
					(start 449.3387 -297.387772)
					(mid 449.34242 -297.378792)
					(end 449.3514 -297.375072)
				)
				(arc
					(start 450.8246 -297.375072)
					(mid 450.83358 -297.378792)
					(end 450.8373 -297.387772)
				)
			)
		)
	)
	(zone
		(layer "In1.Cu")
		(hatch none 0.5)
		(connect_pads
			(clearance 0)
		)
		(min_thickness 0.25)
		(keepout
			(tracks not_allowed)
			(vias allowed)
			(pads allowed)
			(copperpour not_allowed)
			(footprints allowed)
		)
		(placement
			(enabled no)
			(sheetname "")
		)
		(fill
			(thermal_gap 0.5)
			(thermal_bridge_width 0.5)
			(island_removal_mode 0)
		)
		(polygon
			(pts
				(arc
					(start 304.8889 -384.288284)
					(mid 304.908824 -384.29752)
					(end 304.930556 -384.30073)
				)
				(arc
					(start 305.12512 -384.30073)
					(mid 305.179002 -384.278412)
					(end 305.20132 -384.22453)
				)
				(arc
					(start 305.20132 -383.53873)
					(mid 305.179002 -383.484848)
					(end 305.12512 -383.46253)
				)
				(arc
					(start 304.930556 -383.46253)
					(mid 304.908812 -383.465698)
					(end 304.8889 -383.474976)
				)
				(arc
					(start 304.592736 -383.667762)
					(mid 304.551052 -383.679984)
					(end 304.509424 -383.667508)
				)
				(arc
					(start 304.2158 -383.474976)
					(mid 304.195876 -383.46574)
					(end 304.174144 -383.46253)
				)
				(arc
					(start 303.97958 -383.46253)
					(mid 303.925698 -383.484848)
					(end 303.90338 -383.53873)
				)
				(arc
					(start 303.90338 -384.22453)
					(mid 303.925698 -384.278412)
					(end 303.97958 -384.30073)
				)
				(arc
					(start 304.175414 -384.30073)
					(mid 304.197158 -384.297562)
					(end 304.21707 -384.288284)
				)
				(arc
					(start 304.510694 -384.095752)
					(mid 304.55235 -384.08335)
					(end 304.594006 -384.095752)
				)
			)
		)
	)
	(zone
		(layer "In1.Cu")
		(hatch none 0.5)
		(connect_pads
			(clearance 0)
		)
		(min_thickness 0.25)
		(keepout
			(tracks not_allowed)
			(vias allowed)
			(pads allowed)
			(copperpour not_allowed)
			(footprints allowed)
		)
		(placement
			(enabled no)
			(sheetname "")
		)
		(fill
			(thermal_gap 0.5)
			(thermal_bridge_width 0.5)
			(island_removal_mode 0)
		)
		(polygon
			(pts
				(arc
					(start 45.089318 -240.932462)
					(mid 45.085598 -240.941442)
					(end 45.076618 -240.945162)
				)
				(arc
					(start 43.603418 -240.945162)
					(mid 43.594438 -240.941442)
					(end 43.590718 -240.932462)
				)
				(arc
					(start 43.590718 -240.437924)
					(mid 43.594438 -240.428944)
					(end 43.603418 -240.425224)
				)
				(arc
					(start 45.076618 -240.425224)
					(mid 45.085598 -240.428944)
					(end 45.089318 -240.437924)
				)
			)
		)
	)
	(zone
		(layer "In1.Cu")
		(hatch none 0.5)
		(connect_pads
			(clearance 0)
		)
		(min_thickness 0.25)
		(keepout
			(tracks not_allowed)
			(vias allowed)
			(pads allowed)
			(copperpour not_allowed)
			(footprints allowed)
		)
		(placement
			(enabled no)
			(sheetname "")
		)
		(fill
			(thermal_gap 0.5)
			(thermal_bridge_width 0.5)
			(island_removal_mode 0)
		)
		(polygon
			(pts
				(arc
					(start 417.217352 -317.432182)
					(mid 417.213632 -317.441162)
					(end 417.204652 -317.444882)
				)
				(arc
					(start 415.731452 -317.444882)
					(mid 415.722472 -317.441162)
					(end 415.718752 -317.432182)
				)
				(arc
					(start 415.718752 -316.937644)
					(mid 415.722472 -316.928664)
					(end 415.731452 -316.924944)
				)
				(arc
					(start 417.204652 -316.924944)
					(mid 417.213632 -316.928664)
					(end 417.217352 -316.937644)
				)
			)
		)
	)
	(zone
		(layer "In1.Cu")
		(hatch none 0.5)
		(connect_pads
			(clearance 0)
		)
		(min_thickness 0.25)
		(keepout
			(tracks not_allowed)
			(vias allowed)
			(pads allowed)
			(copperpour not_allowed)
			(footprints allowed)
		)
		(placement
			(enabled no)
			(sheetname "")
		)
		(fill
			(thermal_gap 0.5)
			(thermal_bridge_width 0.5)
			(island_removal_mode 0)
		)
		(polygon
			(pts
				(arc
					(start 191.909446 -291.082476)
					(mid 191.905726 -291.091456)
					(end 191.896746 -291.095176)
				)
				(arc
					(start 190.423546 -291.095176)
					(mid 190.414566 -291.091456)
					(end 190.410846 -291.082476)
				)
				(arc
					(start 190.410846 -290.587938)
					(mid 190.414566 -290.578958)
					(end 190.423546 -290.575238)
				)
				(arc
					(start 191.896746 -290.575238)
					(mid 191.905726 -290.578958)
					(end 191.909446 -290.587938)
				)
			)
		)
	)
	(zone
		(layer "In1.Cu")
		(hatch none 0.5)
		(connect_pads
			(clearance 0)
		)
		(min_thickness 0.25)
		(keepout
			(tracks not_allowed)
			(vias allowed)
			(pads allowed)
			(copperpour not_allowed)
			(footprints allowed)
		)
		(placement
			(enabled no)
			(sheetname "")
		)
		(fill
			(thermal_gap 0.5)
			(thermal_bridge_width 0.5)
			(island_removal_mode 0)
		)
		(polygon
			(pts
				(arc
					(start 199.4535 -308.082442)
					(mid 199.44978 -308.091422)
					(end 199.4408 -308.095142)
				)
				(arc
					(start 197.9676 -308.095142)
					(mid 197.95862 -308.091422)
					(end 197.9549 -308.082442)
				)
				(arc
					(start 197.9549 -307.587904)
					(mid 197.95862 -307.578924)
					(end 197.9676 -307.575204)
				)
				(arc
					(start 199.4408 -307.575204)
					(mid 199.44978 -307.578924)
					(end 199.4535 -307.587904)
				)
			)
		)
	)
	(zone
		(layer "In1.Cu")
		(hatch none 0.5)
		(connect_pads
			(clearance 0)
		)
		(min_thickness 0.25)
		(keepout
			(tracks not_allowed)
			(vias allowed)
			(pads allowed)
			(copperpour not_allowed)
			(footprints allowed)
		)
		(placement
			(enabled no)
			(sheetname "")
		)
		(fill
			(thermal_gap 0.5)
			(thermal_bridge_width 0.5)
			(island_removal_mode 0)
		)
		(polygon
			(pts
				(arc
					(start 420.661338 -254.53213)
					(mid 420.657618 -254.54111)
					(end 420.648638 -254.54483)
				)
				(arc
					(start 419.175438 -254.54483)
					(mid 419.166458 -254.54111)
					(end 419.162738 -254.53213)
				)
				(arc
					(start 419.162738 -254.037592)
					(mid 419.166458 -254.028612)
					(end 419.175438 -254.024892)
				)
				(arc
					(start 420.648638 -254.024892)
					(mid 420.657618 -254.028612)
					(end 420.661338 -254.037592)
				)
			)
		)
	)
	(zone
		(layer "In1.Cu")
		(hatch none 0.5)
		(connect_pads
			(clearance 0)
		)
		(min_thickness 0.25)
		(keepout
			(tracks not_allowed)
			(vias allowed)
			(pads allowed)
			(copperpour not_allowed)
			(footprints allowed)
		)
		(placement
			(enabled no)
			(sheetname "")
		)
		(fill
			(thermal_gap 0.5)
			(thermal_bridge_width 0.5)
			(island_removal_mode 0)
		)
		(polygon
			(pts
				(arc
					(start 342.718644 -391.822686)
					(mid 342.845644 -391.949686)
					(end 342.972644 -391.822686)
				)
				(arc
					(start 342.972644 -391.746486)
					(mid 342.845644 -391.619486)
					(end 342.718644 -391.746486)
				)
			)
		)
	)
	(zone
		(layer "In1.Cu")
		(hatch none 0.5)
		(connect_pads
			(clearance 0)
		)
		(min_thickness 0.25)
		(keepout
			(tracks not_allowed)
			(vias allowed)
			(pads allowed)
			(copperpour not_allowed)
			(footprints allowed)
		)
		(placement
			(enabled no)
			(sheetname "")
		)
		(fill
			(thermal_gap 0.5)
			(thermal_bridge_width 0.5)
			(island_removal_mode 0)
		)
		(polygon
			(pts
				(arc
					(start 432.30546 -210.33232)
					(mid 432.30174 -210.3413)
					(end 432.29276 -210.34502)
				)
				(arc
					(start 430.81956 -210.34502)
					(mid 430.81058 -210.3413)
					(end 430.80686 -210.33232)
				)
				(arc
					(start 430.80686 -209.837782)
					(mid 430.81058 -209.828802)
					(end 430.81956 -209.825082)
				)
				(arc
					(start 432.29276 -209.825082)
					(mid 432.30174 -209.828802)
					(end 432.30546 -209.837782)
				)
			)
		)
	)
	(zone
		(layer "In1.Cu")
		(hatch none 0.5)
		(connect_pads
			(clearance 0)
		)
		(min_thickness 0.25)
		(keepout
			(tracks not_allowed)
			(vias allowed)
			(pads allowed)
			(copperpour not_allowed)
			(footprints allowed)
		)
		(placement
			(enabled no)
			(sheetname "")
		)
		(fill
			(thermal_gap 0.5)
			(thermal_bridge_width 0.5)
			(island_removal_mode 0)
		)
		(polygon
			(pts
				(arc
					(start 281.385264 -229.882192)
					(mid 281.381544 -229.891172)
					(end 281.372564 -229.894892)
				)
				(arc
					(start 279.899364 -229.894892)
					(mid 279.890384 -229.891172)
					(end 279.886664 -229.882192)
				)
				(arc
					(start 279.886664 -229.387654)
					(mid 279.890384 -229.378674)
					(end 279.899364 -229.374954)
				)
				(arc
					(start 281.372564 -229.374954)
					(mid 281.381544 -229.378674)
					(end 281.385264 -229.387654)
				)
			)
		)
	)
	(zone
		(layer "In1.Cu")
		(hatch none 0.5)
		(connect_pads
			(clearance 0)
		)
		(min_thickness 0.25)
		(keepout
			(tracks not_allowed)
			(vias allowed)
			(pads allowed)
			(copperpour not_allowed)
			(footprints allowed)
		)
		(placement
			(enabled no)
			(sheetname "")
		)
		(fill
			(thermal_gap 0.5)
			(thermal_bridge_width 0.5)
			(island_removal_mode 0)
		)
		(polygon
			(pts
				(arc
					(start 180.265324 -221.382336)
					(mid 180.261604 -221.391316)
					(end 180.252624 -221.395036)
				)
				(arc
					(start 178.779424 -221.395036)
					(mid 178.770444 -221.391316)
					(end 178.766724 -221.382336)
				)
				(arc
					(start 178.766724 -220.887798)
					(mid 178.770444 -220.878818)
					(end 178.779424 -220.875098)
				)
				(arc
					(start 180.252624 -220.875098)
					(mid 180.261604 -220.878818)
					(end 180.265324 -220.887798)
				)
			)
		)
	)
	(zone
		(layer "In1.Cu")
		(hatch none 0.5)
		(connect_pads
			(clearance 0)
		)
		(min_thickness 0.25)
		(keepout
			(tracks not_allowed)
			(vias allowed)
			(pads allowed)
			(copperpour not_allowed)
			(footprints allowed)
		)
		(placement
			(enabled no)
			(sheetname "")
		)
		(fill
			(thermal_gap 0.5)
			(thermal_bridge_width 0.5)
			(island_removal_mode 0)
		)
		(polygon
			(pts
				(arc
					(start 45.089318 -203.532486)
					(mid 45.085598 -203.541466)
					(end 45.076618 -203.545186)
				)
				(arc
					(start 43.603418 -203.545186)
					(mid 43.594438 -203.541466)
					(end 43.590718 -203.532486)
				)
				(arc
					(start 43.590718 -203.037948)
					(mid 43.594438 -203.028968)
					(end 43.603418 -203.025248)
				)
				(arc
					(start 45.076618 -203.025248)
					(mid 45.085598 -203.028968)
					(end 45.089318 -203.037948)
				)
			)
		)
	)
	(zone
		(layer "In1.Cu")
		(hatch none 0.5)
		(connect_pads
			(clearance 0)
		)
		(min_thickness 0.25)
		(keepout
			(tracks not_allowed)
			(vias allowed)
			(pads allowed)
			(copperpour not_allowed)
			(footprints allowed)
		)
		(placement
			(enabled no)
			(sheetname "")
		)
		(fill
			(thermal_gap 0.5)
			(thermal_bridge_width 0.5)
			(island_removal_mode 0)
		)
		(polygon
			(pts
				(arc
					(start 266.29741 -230.73233)
					(mid 266.29369 -230.74131)
					(end 266.28471 -230.74503)
				)
				(arc
					(start 264.81151 -230.74503)
					(mid 264.80253 -230.74131)
					(end 264.79881 -230.73233)
				)
				(arc
					(start 264.79881 -230.237792)
					(mid 264.80253 -230.228812)
					(end 264.81151 -230.225092)
				)
				(arc
					(start 266.28471 -230.225092)
					(mid 266.29369 -230.228812)
					(end 266.29741 -230.237792)
				)
			)
		)
	)
	(zone
		(layer "In1.Cu")
		(hatch none 0.5)
		(connect_pads
			(clearance 0)
		)
		(min_thickness 0.25)
		(keepout
			(tracks not_allowed)
			(vias allowed)
			(pads allowed)
			(copperpour not_allowed)
			(footprints allowed)
		)
		(placement
			(enabled no)
			(sheetname "")
		)
		(fill
			(thermal_gap 0.5)
			(thermal_bridge_width 0.5)
			(island_removal_mode 0)
		)
		(polygon
			(pts
				(arc
					(start 30.001464 -303.832514)
					(mid 29.997744 -303.841494)
					(end 29.988764 -303.845214)
				)
				(arc
					(start 28.515564 -303.845214)
					(mid 28.506584 -303.841494)
					(end 28.502864 -303.832514)
				)
				(arc
					(start 28.502864 -303.337976)
					(mid 28.506584 -303.328996)
					(end 28.515564 -303.325276)
				)
				(arc
					(start 29.988764 -303.325276)
					(mid 29.997744 -303.328996)
					(end 30.001464 -303.337976)
				)
			)
		)
	)
	(zone
		(layer "In1.Cu")
		(hatch none 0.5)
		(connect_pads
			(clearance 0)
		)
		(min_thickness 0.25)
		(keepout
			(tracks not_allowed)
			(vias allowed)
			(pads allowed)
			(copperpour not_allowed)
			(footprints allowed)
		)
		(placement
			(enabled no)
			(sheetname "")
		)
		(fill
			(thermal_gap 0.5)
			(thermal_bridge_width 0.5)
			(island_removal_mode 0)
		)
		(polygon
			(pts
				(arc
					(start 48.533304 -217.132408)
					(mid 48.529584 -217.141388)
					(end 48.520604 -217.145108)
				)
				(arc
					(start 47.047404 -217.145108)
					(mid 47.038424 -217.141388)
					(end 47.034704 -217.132408)
				)
				(arc
					(start 47.034704 -216.63787)
					(mid 47.038424 -216.62889)
					(end 47.047404 -216.62517)
				)
				(arc
					(start 48.520604 -216.62517)
					(mid 48.529584 -216.62889)
					(end 48.533304 -216.63787)
				)
			)
		)
	)
	(zone
		(layer "In1.Cu")
		(hatch none 0.5)
		(connect_pads
			(clearance 0)
		)
		(min_thickness 0.25)
		(keepout
			(tracks not_allowed)
			(vias allowed)
			(pads allowed)
			(copperpour not_allowed)
			(footprints allowed)
		)
		(placement
			(enabled no)
			(sheetname "")
		)
		(fill
			(thermal_gap 0.5)
			(thermal_bridge_width 0.5)
			(island_removal_mode 0)
		)
		(polygon
			(pts
				(arc
					(start 25.901396 -201.832464)
					(mid 25.897676 -201.841444)
					(end 25.888696 -201.845164)
				)
				(arc
					(start 24.415496 -201.845164)
					(mid 24.406516 -201.841444)
					(end 24.402796 -201.832464)
				)
				(arc
					(start 24.402796 -201.337926)
					(mid 24.406516 -201.328946)
					(end 24.415496 -201.325226)
				)
				(arc
					(start 25.888696 -201.325226)
					(mid 25.897676 -201.328946)
					(end 25.901396 -201.337926)
				)
			)
		)
	)
	(zone
		(layer "In1.Cu")
		(hatch none 0.5)
		(connect_pads
			(clearance 0)
		)
		(min_thickness 0.25)
		(keepout
			(tracks not_allowed)
			(vias allowed)
			(pads allowed)
			(copperpour not_allowed)
			(footprints allowed)
		)
		(placement
			(enabled no)
			(sheetname "")
		)
		(fill
			(thermal_gap 0.5)
			(thermal_bridge_width 0.5)
			(island_removal_mode 0)
		)
		(polygon
			(pts
				(arc
					(start 424.761406 -240.932208)
					(mid 424.757686 -240.941188)
					(end 424.748706 -240.944908)
				)
				(arc
					(start 423.275506 -240.944908)
					(mid 423.266526 -240.941188)
					(end 423.262806 -240.932208)
				)
				(arc
					(start 423.262806 -240.43767)
					(mid 423.266526 -240.42869)
					(end 423.275506 -240.42497)
				)
				(arc
					(start 424.748706 -240.42497)
					(mid 424.757686 -240.42869)
					(end 424.761406 -240.43767)
				)
			)
		)
	)
	(zone
		(layer "In1.Cu")
		(hatch none 0.5)
		(connect_pads
			(clearance 0)
		)
		(min_thickness 0.25)
		(keepout
			(tracks not_allowed)
			(vias allowed)
			(pads allowed)
			(copperpour not_allowed)
			(footprints allowed)
		)
		(placement
			(enabled no)
			(sheetname "")
		)
		(fill
			(thermal_gap 0.5)
			(thermal_bridge_width 0.5)
			(island_removal_mode 0)
		)
		(polygon
			(pts
				(arc
					(start 288.929318 -274.93214)
					(mid 288.925598 -274.94112)
					(end 288.916618 -274.94484)
				)
				(arc
					(start 287.443418 -274.94484)
					(mid 287.434438 -274.94112)
					(end 287.430718 -274.93214)
				)
				(arc
					(start 287.430718 -274.437602)
					(mid 287.434438 -274.428622)
					(end 287.443418 -274.424902)
				)
				(arc
					(start 288.916618 -274.424902)
					(mid 288.925598 -274.428622)
					(end 288.929318 -274.437602)
				)
			)
		)
	)
	(zone
		(layer "In1.Cu")
		(hatch none 0.5)
		(connect_pads
			(clearance 0)
		)
		(min_thickness 0.25)
		(keepout
			(tracks not_allowed)
			(vias allowed)
			(pads allowed)
			(copperpour not_allowed)
			(footprints allowed)
		)
		(placement
			(enabled no)
			(sheetname "")
		)
		(fill
			(thermal_gap 0.5)
			(thermal_bridge_width 0.5)
			(island_removal_mode 0)
		)
		(polygon
			(pts
				(arc
					(start 450.8373 -211.182204)
					(mid 450.83358 -211.191184)
					(end 450.8246 -211.194904)
				)
				(arc
					(start 449.3514 -211.194904)
					(mid 449.34242 -211.191184)
					(end 449.3387 -211.182204)
				)
				(arc
					(start 449.3387 -210.687666)
					(mid 449.34242 -210.678686)
					(end 449.3514 -210.674966)
				)
				(arc
					(start 450.8246 -210.674966)
					(mid 450.83358 -210.678686)
					(end 450.8373 -210.687666)
				)
			)
		)
	)
	(zone
		(layer "In1.Cu")
		(hatch none 0.5)
		(connect_pads
			(clearance 0)
		)
		(min_thickness 0.25)
		(keepout
			(tracks not_allowed)
			(vias allowed)
			(pads allowed)
			(copperpour not_allowed)
			(footprints allowed)
		)
		(placement
			(enabled no)
			(sheetname "")
		)
		(fill
			(thermal_gap 0.5)
			(thermal_bridge_width 0.5)
			(island_removal_mode 0)
		)
		(polygon
			(pts
				(arc
					(start 37.545264 -233.28249)
					(mid 37.541544 -233.29147)
					(end 37.532564 -233.29519)
				)
				(arc
					(start 36.059364 -233.29519)
					(mid 36.050384 -233.29147)
					(end 36.046664 -233.28249)
				)
				(arc
					(start 36.046664 -232.787952)
					(mid 36.050384 -232.778972)
					(end 36.059364 -232.775252)
				)
				(arc
					(start 37.532564 -232.775252)
					(mid 37.541544 -232.778972)
					(end 37.545264 -232.787952)
				)
			)
		)
	)
	(zone
		(layer "In1.Cu")
		(hatch none 0.5)
		(connect_pads
			(clearance 0)
		)
		(min_thickness 0.25)
		(keepout
			(tracks not_allowed)
			(vias allowed)
			(pads allowed)
			(copperpour not_allowed)
			(footprints allowed)
		)
		(placement
			(enabled no)
			(sheetname "")
		)
		(fill
			(thermal_gap 0.5)
			(thermal_bridge_width 0.5)
			(island_removal_mode 0)
		)
		(polygon
			(pts
				(arc
					(start 55.061104 -386.003292)
					(mid 54.680104 -386.003292)
					(end 55.061104 -386.003292)
				)
			)
		)
	)
	(zone
		(layer "In1.Cu")
		(hatch none 0.5)
		(connect_pads
			(clearance 0)
		)
		(min_thickness 0.25)
		(keepout
			(tracks not_allowed)
			(vias allowed)
			(pads allowed)
			(copperpour not_allowed)
			(footprints allowed)
		)
		(placement
			(enabled no)
			(sheetname "")
		)
		(fill
			(thermal_gap 0.5)
			(thermal_bridge_width 0.5)
			(island_removal_mode 0)
		)
		(polygon
			(pts
				(arc
					(start 206.9973 -222.232474)
					(mid 206.99358 -222.241454)
					(end 206.9846 -222.245174)
				)
				(arc
					(start 205.5114 -222.245174)
					(mid 205.50242 -222.241454)
					(end 205.4987 -222.232474)
				)
				(arc
					(start 205.4987 -221.737936)
					(mid 205.50242 -221.728956)
					(end 205.5114 -221.725236)
				)
				(arc
					(start 206.9846 -221.725236)
					(mid 206.99358 -221.728956)
					(end 206.9973 -221.737936)
				)
			)
		)
	)
	(zone
		(layer "In1.Cu")
		(hatch none 0.5)
		(connect_pads
			(clearance 0)
		)
		(min_thickness 0.25)
		(keepout
			(tracks not_allowed)
			(vias allowed)
			(pads allowed)
			(copperpour not_allowed)
			(footprints allowed)
		)
		(placement
			(enabled no)
			(sheetname "")
		)
		(fill
			(thermal_gap 0.5)
			(thermal_bridge_width 0.5)
			(island_removal_mode 0)
		)
		(polygon
			(pts
				(arc
					(start 52.633372 -276.632416)
					(mid 52.629652 -276.641396)
					(end 52.620672 -276.645116)
				)
				(arc
					(start 51.147472 -276.645116)
					(mid 51.138492 -276.641396)
					(end 51.134772 -276.632416)
				)
				(arc
					(start 51.134772 -276.137878)
					(mid 51.138492 -276.128898)
					(end 51.147472 -276.125178)
				)
				(arc
					(start 52.620672 -276.125178)
					(mid 52.629652 -276.128898)
					(end 52.633372 -276.137878)
				)
			)
		)
	)
	(zone
		(layer "In1.Cu")
		(hatch none 0.5)
		(connect_pads
			(clearance 0)
		)
		(min_thickness 0.25)
		(keepout
			(tracks not_allowed)
			(vias allowed)
			(pads allowed)
			(copperpour not_allowed)
			(footprints allowed)
		)
		(placement
			(enabled no)
			(sheetname "")
		)
		(fill
			(thermal_gap 0.5)
			(thermal_bridge_width 0.5)
			(island_removal_mode 0)
		)
		(polygon
			(pts
				(arc
					(start 180.265324 -251.982478)
					(mid 180.261604 -251.991458)
					(end 180.252624 -251.995178)
				)
				(arc
					(start 178.779424 -251.995178)
					(mid 178.770444 -251.991458)
					(end 178.766724 -251.982478)
				)
				(arc
					(start 178.766724 -251.48794)
					(mid 178.770444 -251.47896)
					(end 178.779424 -251.47524)
				)
				(arc
					(start 180.252624 -251.47524)
					(mid 180.261604 -251.47896)
					(end 180.265324 -251.48794)
				)
			)
		)
	)
	(zone
		(layer "In1.Cu")
		(hatch none 0.5)
		(connect_pads
			(clearance 0)
		)
		(min_thickness 0.25)
		(keepout
			(tracks not_allowed)
			(vias allowed)
			(pads allowed)
			(copperpour not_allowed)
			(footprints allowed)
		)
		(placement
			(enabled no)
			(sheetname "")
		)
		(fill
			(thermal_gap 0.5)
			(thermal_bridge_width 0.5)
			(island_removal_mode 0)
		)
		(polygon
			(pts
				(arc
					(start 206.9973 -217.982546)
					(mid 206.99358 -217.991526)
					(end 206.9846 -217.995246)
				)
				(arc
					(start 205.5114 -217.995246)
					(mid 205.50242 -217.991526)
					(end 205.4987 -217.982546)
				)
				(arc
					(start 205.4987 -217.488008)
					(mid 205.50242 -217.479028)
					(end 205.5114 -217.475308)
				)
				(arc
					(start 206.9846 -217.475308)
					(mid 206.99358 -217.479028)
					(end 206.9973 -217.488008)
				)
			)
		)
	)
	(zone
		(layer "In1.Cu")
		(hatch none 0.5)
		(connect_pads
			(clearance 0)
		)
		(min_thickness 0.25)
		(keepout
			(tracks not_allowed)
			(vias allowed)
			(pads allowed)
			(copperpour not_allowed)
			(footprints allowed)
		)
		(placement
			(enabled no)
			(sheetname "")
		)
		(fill
			(thermal_gap 0.5)
			(thermal_bridge_width 0.5)
			(island_removal_mode 0)
		)
		(polygon
			(pts
				(arc
					(start 281.385264 -290.232338)
					(mid 281.381544 -290.241318)
					(end 281.372564 -290.245038)
				)
				(arc
					(start 279.899364 -290.245038)
					(mid 279.890384 -290.241318)
					(end 279.886664 -290.232338)
				)
				(arc
					(start 279.886664 -289.7378)
					(mid 279.890384 -289.72882)
					(end 279.899364 -289.7251)
				)
				(arc
					(start 281.372564 -289.7251)
					(mid 281.381544 -289.72882)
					(end 281.385264 -289.7378)
				)
			)
		)
	)
	(zone
		(layer "In1.Cu")
		(hatch none 0.5)
		(connect_pads
			(clearance 0)
		)
		(min_thickness 0.25)
		(keepout
			(tracks not_allowed)
			(vias allowed)
			(pads allowed)
			(copperpour not_allowed)
			(footprints allowed)
		)
		(placement
			(enabled no)
			(sheetname "")
		)
		(fill
			(thermal_gap 0.5)
			(thermal_bridge_width 0.5)
			(island_removal_mode 0)
		)
		(polygon
			(pts
				(arc
					(start 48.533304 -263.882378)
					(mid 48.529584 -263.891358)
					(end 48.520604 -263.895078)
				)
				(arc
					(start 47.047404 -263.895078)
					(mid 47.038424 -263.891358)
					(end 47.034704 -263.882378)
				)
				(arc
					(start 47.034704 -263.38784)
					(mid 47.038424 -263.37886)
					(end 47.047404 -263.37514)
				)
				(arc
					(start 48.520604 -263.37514)
					(mid 48.529584 -263.37886)
					(end 48.533304 -263.38784)
				)
			)
		)
	)
	(zone
		(layer "In1.Cu")
		(hatch none 0.5)
		(connect_pads
			(clearance 0)
		)
		(min_thickness 0.25)
		(keepout
			(tracks not_allowed)
			(vias allowed)
			(pads allowed)
			(copperpour not_allowed)
			(footprints allowed)
		)
		(placement
			(enabled no)
			(sheetname "")
		)
		(fill
			(thermal_gap 0.5)
			(thermal_bridge_width 0.5)
			(island_removal_mode 0)
		)
		(polygon
			(pts
				(arc
					(start 52.633372 -278.332438)
					(mid 52.629652 -278.341418)
					(end 52.620672 -278.345138)
				)
				(arc
					(start 51.147472 -278.345138)
					(mid 51.138492 -278.341418)
					(end 51.134772 -278.332438)
				)
				(arc
					(start 51.134772 -277.8379)
					(mid 51.138492 -277.82892)
					(end 51.147472 -277.8252)
				)
				(arc
					(start 52.620672 -277.8252)
					(mid 52.629652 -277.82892)
					(end 52.633372 -277.8379)
				)
			)
		)
	)
	(zone
		(layer "In1.Cu")
		(hatch none 0.5)
		(connect_pads
			(clearance 0)
		)
		(min_thickness 0.25)
		(keepout
			(tracks not_allowed)
			(vias allowed)
			(pads allowed)
			(copperpour not_allowed)
			(footprints allowed)
		)
		(placement
			(enabled no)
			(sheetname "")
		)
		(fill
			(thermal_gap 0.5)
			(thermal_bridge_width 0.5)
			(island_removal_mode 0)
		)
		(polygon
			(pts
				(arc
					(start 417.217352 -275.782278)
					(mid 417.213632 -275.791258)
					(end 417.204652 -275.794978)
				)
				(arc
					(start 415.731452 -275.794978)
					(mid 415.722472 -275.791258)
					(end 415.718752 -275.782278)
				)
				(arc
					(start 415.718752 -275.28774)
					(mid 415.722472 -275.27876)
					(end 415.731452 -275.27504)
				)
				(arc
					(start 417.204652 -275.27504)
					(mid 417.213632 -275.27876)
					(end 417.217352 -275.28774)
				)
			)
		)
	)
	(zone
		(layer "In1.Cu")
		(hatch none 0.5)
		(connect_pads
			(clearance 0)
		)
		(min_thickness 0.25)
		(keepout
			(tracks not_allowed)
			(vias allowed)
			(pads allowed)
			(copperpour not_allowed)
			(footprints allowed)
		)
		(placement
			(enabled no)
			(sheetname "")
		)
		(fill
			(thermal_gap 0.5)
			(thermal_bridge_width 0.5)
			(island_removal_mode 0)
		)
		(polygon
			(pts
				(arc
					(start 277.941532 -212.882226)
					(mid 277.937812 -212.891206)
					(end 277.928832 -212.894926)
				)
				(arc
					(start 276.455632 -212.894926)
					(mid 276.446652 -212.891206)
					(end 276.442932 -212.882226)
				)
				(arc
					(start 276.442932 -212.387688)
					(mid 276.446652 -212.378708)
					(end 276.455632 -212.374988)
				)
				(arc
					(start 277.928832 -212.374988)
					(mid 277.937812 -212.378708)
					(end 277.941532 -212.387688)
				)
			)
		)
	)
	(zone
		(layer "In1.Cu")
		(hatch none 0.5)
		(connect_pads
			(clearance 0)
		)
		(min_thickness 0.25)
		(keepout
			(tracks not_allowed)
			(vias allowed)
			(pads allowed)
			(copperpour not_allowed)
			(footprints allowed)
		)
		(placement
			(enabled no)
			(sheetname "")
		)
		(fill
			(thermal_gap 0.5)
			(thermal_bridge_width 0.5)
			(island_removal_mode 0)
		)
		(polygon
			(pts
				(arc
					(start 439.849514 -285.132272)
					(mid 439.845794 -285.141252)
					(end 439.836814 -285.144972)
				)
				(arc
					(start 438.363614 -285.144972)
					(mid 438.354634 -285.141252)
					(end 438.350914 -285.132272)
				)
				(arc
					(start 438.350914 -284.637734)
					(mid 438.354634 -284.628754)
					(end 438.363614 -284.625034)
				)
				(arc
					(start 439.836814 -284.625034)
					(mid 439.845794 -284.628754)
					(end 439.849514 -284.637734)
				)
			)
		)
	)
	(zone
		(layer "In1.Cu")
		(hatch none 0.5)
		(connect_pads
			(clearance 0)
		)
		(min_thickness 0.25)
		(keepout
			(tracks not_allowed)
			(vias allowed)
			(pads allowed)
			(copperpour not_allowed)
			(footprints allowed)
		)
		(placement
			(enabled no)
			(sheetname "")
		)
		(fill
			(thermal_gap 0.5)
			(thermal_bridge_width 0.5)
			(island_removal_mode 0)
		)
		(polygon
			(pts
				(arc
					(start 163.998148 -383.92227)
					(mid 163.693348 -383.92227)
					(end 163.998148 -383.92227)
				)
			)
		)
	)
	(zone
		(layer "In1.Cu")
		(hatch none 0.5)
		(connect_pads
			(clearance 0)
		)
		(min_thickness 0.25)
		(keepout
			(tracks not_allowed)
			(vias allowed)
			(pads allowed)
			(copperpour not_allowed)
			(footprints allowed)
		)
		(placement
			(enabled no)
			(sheetname "")
		)
		(fill
			(thermal_gap 0.5)
			(thermal_bridge_width 0.5)
			(island_removal_mode 0)
		)
		(polygon
			(pts
				(arc
					(start 308.117494 -281.732228)
					(mid 308.113774 -281.741208)
					(end 308.104794 -281.744928)
				)
				(arc
					(start 306.631594 -281.744928)
					(mid 306.622614 -281.741208)
					(end 306.618894 -281.732228)
				)
				(arc
					(start 306.618894 -281.23769)
					(mid 306.622614 -281.22871)
					(end 306.631594 -281.22499)
				)
				(arc
					(start 308.104794 -281.22499)
					(mid 308.113774 -281.22871)
					(end 308.117494 -281.23769)
				)
			)
		)
	)
	(zone
		(layer "In1.Cu")
		(hatch none 0.5)
		(connect_pads
			(clearance 0)
		)
		(min_thickness 0.25)
		(keepout
			(tracks not_allowed)
			(vias allowed)
			(pads allowed)
			(copperpour not_allowed)
			(footprints allowed)
		)
		(placement
			(enabled no)
			(sheetname "")
		)
		(fill
			(thermal_gap 0.5)
			(thermal_bridge_width 0.5)
			(island_removal_mode 0)
		)
		(polygon
			(pts
				(arc
					(start 304.017426 -217.132154)
					(mid 304.013706 -217.141134)
					(end 304.004726 -217.144854)
				)
				(arc
					(start 302.531526 -217.144854)
					(mid 302.522546 -217.141134)
					(end 302.518826 -217.132154)
				)
				(arc
					(start 302.518826 -216.637616)
					(mid 302.522546 -216.628636)
					(end 302.531526 -216.624916)
				)
				(arc
					(start 304.004726 -216.624916)
					(mid 304.013706 -216.628636)
					(end 304.017426 -216.637616)
				)
			)
		)
	)
	(zone
		(layer "In1.Cu")
		(hatch none 0.5)
		(connect_pads
			(clearance 0)
		)
		(min_thickness 0.25)
		(keepout
			(tracks not_allowed)
			(vias allowed)
			(pads allowed)
			(copperpour not_allowed)
			(footprints allowed)
		)
		(placement
			(enabled no)
			(sheetname "")
		)
		(fill
			(thermal_gap 0.5)
			(thermal_bridge_width 0.5)
			(island_removal_mode 0)
		)
		(polygon
			(pts
				(arc
					(start 165.177216 -220.532452)
					(mid 165.173496 -220.541432)
					(end 165.164516 -220.545152)
				)
				(arc
					(start 163.691316 -220.545152)
					(mid 163.682336 -220.541432)
					(end 163.678616 -220.532452)
				)
				(arc
					(start 163.678616 -220.037914)
					(mid 163.682336 -220.028934)
					(end 163.691316 -220.025214)
				)
				(arc
					(start 165.164516 -220.025214)
					(mid 165.173496 -220.028934)
					(end 165.177216 -220.037914)
				)
			)
		)
	)
	(zone
		(layer "In1.Cu")
		(hatch none 0.5)
		(connect_pads
			(clearance 0)
		)
		(min_thickness 0.25)
		(keepout
			(tracks not_allowed)
			(vias allowed)
			(pads allowed)
			(copperpour not_allowed)
			(footprints allowed)
		)
		(placement
			(enabled no)
			(sheetname "")
		)
		(fill
			(thermal_gap 0.5)
			(thermal_bridge_width 0.5)
			(island_removal_mode 0)
		)
		(polygon
			(pts
				(arc
					(start 25.901396 -211.182458)
					(mid 25.897676 -211.191438)
					(end 25.888696 -211.195158)
				)
				(arc
					(start 24.415496 -211.195158)
					(mid 24.406516 -211.191438)
					(end 24.402796 -211.182458)
				)
				(arc
					(start 24.402796 -210.68792)
					(mid 24.406516 -210.67894)
					(end 24.415496 -210.67522)
				)
				(arc
					(start 25.888696 -210.67522)
					(mid 25.897676 -210.67894)
					(end 25.901396 -210.68792)
				)
			)
		)
	)
	(zone
		(layer "In1.Cu")
		(hatch none 0.5)
		(connect_pads
			(clearance 0)
		)
		(min_thickness 0.25)
		(keepout
			(tracks not_allowed)
			(vias allowed)
			(pads allowed)
			(copperpour not_allowed)
			(footprints allowed)
		)
		(placement
			(enabled no)
			(sheetname "")
		)
		(fill
			(thermal_gap 0.5)
			(thermal_bridge_width 0.5)
			(island_removal_mode 0)
		)
		(polygon
			(pts
				(arc
					(start 281.385264 -282.582112)
					(mid 281.381544 -282.591092)
					(end 281.372564 -282.594812)
				)
				(arc
					(start 279.899364 -282.594812)
					(mid 279.890384 -282.591092)
					(end 279.886664 -282.582112)
				)
				(arc
					(start 279.886664 -282.087574)
					(mid 279.890384 -282.078594)
					(end 279.899364 -282.074874)
				)
				(arc
					(start 281.372564 -282.074874)
					(mid 281.381544 -282.078594)
					(end 281.385264 -282.087574)
				)
			)
		)
	)
	(zone
		(layer "In1.Cu")
		(hatch none 0.5)
		(connect_pads
			(clearance 0)
		)
		(min_thickness 0.25)
		(keepout
			(tracks not_allowed)
			(vias allowed)
			(pads allowed)
			(copperpour not_allowed)
			(footprints allowed)
		)
		(placement
			(enabled no)
			(sheetname "")
		)
		(fill
			(thermal_gap 0.5)
			(thermal_bridge_width 0.5)
			(island_removal_mode 0)
		)
		(polygon
			(pts
				(arc
					(start 313.061096 -393.69238)
					(mid 312.680096 -393.69238)
					(end 313.061096 -393.69238)
				)
			)
		)
	)
	(zone
		(layer "In1.Cu")
		(hatch none 0.5)
		(connect_pads
			(clearance 0)
		)
		(min_thickness 0.25)
		(keepout
			(tracks not_allowed)
			(vias allowed)
			(pads allowed)
			(copperpour not_allowed)
			(footprints allowed)
		)
		(placement
			(enabled no)
			(sheetname "")
		)
		(fill
			(thermal_gap 0.5)
			(thermal_bridge_width 0.5)
			(island_removal_mode 0)
		)
		(polygon
			(pts
				(arc
					(start 454.937368 -285.132272)
					(mid 454.933648 -285.141252)
					(end 454.924668 -285.144972)
				)
				(arc
					(start 453.451468 -285.144972)
					(mid 453.442488 -285.141252)
					(end 453.438768 -285.132272)
				)
				(arc
					(start 453.438768 -284.637734)
					(mid 453.442488 -284.628754)
					(end 453.451468 -284.625034)
				)
				(arc
					(start 454.924668 -284.625034)
					(mid 454.933648 -284.628754)
					(end 454.937368 -284.637734)
				)
			)
		)
	)
	(zone
		(layer "In1.Cu")
		(hatch none 0.5)
		(connect_pads
			(clearance 0)
		)
		(min_thickness 0.25)
		(keepout
			(tracks not_allowed)
			(vias allowed)
			(pads allowed)
			(copperpour not_allowed)
			(footprints allowed)
		)
		(placement
			(enabled no)
			(sheetname "")
		)
		(fill
			(thermal_gap 0.5)
			(thermal_bridge_width 0.5)
			(island_removal_mode 0)
		)
		(polygon
			(pts
				(arc
					(start 191.909446 -238.382556)
					(mid 191.905726 -238.391536)
					(end 191.896746 -238.395256)
				)
				(arc
					(start 190.423546 -238.395256)
					(mid 190.414566 -238.391536)
					(end 190.410846 -238.382556)
				)
				(arc
					(start 190.410846 -237.888018)
					(mid 190.414566 -237.879038)
					(end 190.423546 -237.875318)
				)
				(arc
					(start 191.896746 -237.875318)
					(mid 191.905726 -237.879038)
					(end 191.909446 -237.888018)
				)
			)
		)
	)
	(zone
		(layer "In1.Cu")
		(hatch none 0.5)
		(connect_pads
			(clearance 0)
		)
		(min_thickness 0.25)
		(keepout
			(tracks not_allowed)
			(vias allowed)
			(pads allowed)
			(copperpour not_allowed)
			(footprints allowed)
		)
		(placement
			(enabled no)
			(sheetname "")
		)
		(fill
			(thermal_gap 0.5)
			(thermal_bridge_width 0.5)
			(island_removal_mode 0)
		)
		(polygon
			(pts
				(arc
					(start 30.001464 -313.182508)
					(mid 29.997744 -313.191488)
					(end 29.988764 -313.195208)
				)
				(arc
					(start 28.515564 -313.195208)
					(mid 28.506584 -313.191488)
					(end 28.502864 -313.182508)
				)
				(arc
					(start 28.502864 -312.68797)
					(mid 28.506584 -312.67899)
					(end 28.515564 -312.67527)
				)
				(arc
					(start 29.988764 -312.67527)
					(mid 29.997744 -312.67899)
					(end 30.001464 -312.68797)
				)
			)
		)
	)
	(zone
		(layer "In1.Cu")
		(hatch none 0.5)
		(connect_pads
			(clearance 0)
		)
		(min_thickness 0.25)
		(keepout
			(tracks not_allowed)
			(vias allowed)
			(pads allowed)
			(copperpour not_allowed)
			(footprints allowed)
		)
		(placement
			(enabled no)
			(sheetname "")
		)
		(fill
			(thermal_gap 0.5)
			(thermal_bridge_width 0.5)
			(island_removal_mode 0)
		)
		(polygon
			(pts
				(arc
					(start 454.937368 -201.83221)
					(mid 454.933648 -201.84119)
					(end 454.924668 -201.84491)
				)
				(arc
					(start 453.451468 -201.84491)
					(mid 453.442488 -201.84119)
					(end 453.438768 -201.83221)
				)
				(arc
					(start 453.438768 -201.337672)
					(mid 453.442488 -201.328692)
					(end 453.451468 -201.324972)
				)
				(arc
					(start 454.924668 -201.324972)
					(mid 454.933648 -201.328692)
					(end 454.937368 -201.337672)
				)
			)
		)
	)
	(zone
		(layer "In1.Cu")
		(hatch none 0.5)
		(connect_pads
			(clearance 0)
		)
		(min_thickness 0.25)
		(keepout
			(tracks not_allowed)
			(vias allowed)
			(pads allowed)
			(copperpour not_allowed)
			(footprints allowed)
		)
		(placement
			(enabled no)
			(sheetname "")
		)
		(fill
			(thermal_gap 0.5)
			(thermal_bridge_width 0.5)
			(island_removal_mode 0)
		)
		(polygon
			(pts
				(arc
					(start 199.4535 -212.88248)
					(mid 199.44978 -212.89146)
					(end 199.4408 -212.89518)
				)
				(arc
					(start 197.9676 -212.89518)
					(mid 197.95862 -212.89146)
					(end 197.9549 -212.88248)
				)
				(arc
					(start 197.9549 -212.387942)
					(mid 197.95862 -212.378962)
					(end 197.9676 -212.375242)
				)
				(arc
					(start 199.4408 -212.375242)
					(mid 199.44978 -212.378962)
					(end 199.4535 -212.387942)
				)
			)
		)
	)
	(zone
		(layer "In1.Cu")
		(hatch none 0.5)
		(connect_pads
			(clearance 0)
		)
		(min_thickness 0.25)
		(keepout
			(tracks not_allowed)
			(vias allowed)
			(pads allowed)
			(copperpour not_allowed)
			(footprints allowed)
		)
		(placement
			(enabled no)
			(sheetname "")
		)
		(fill
			(thermal_gap 0.5)
			(thermal_bridge_width 0.5)
			(island_removal_mode 0)
		)
		(polygon
			(pts
				(arc
					(start 281.385264 -277.4823)
					(mid 281.381544 -277.49128)
					(end 281.372564 -277.495)
				)
				(arc
					(start 279.899364 -277.495)
					(mid 279.890384 -277.49128)
					(end 279.886664 -277.4823)
				)
				(arc
					(start 279.886664 -276.987762)
					(mid 279.890384 -276.978782)
					(end 279.899364 -276.975062)
				)
				(arc
					(start 281.372564 -276.975062)
					(mid 281.381544 -276.978782)
					(end 281.385264 -276.987762)
				)
			)
		)
	)
	(zone
		(layer "In1.Cu")
		(hatch none 0.5)
		(connect_pads
			(clearance 0)
		)
		(min_thickness 0.25)
		(keepout
			(tracks not_allowed)
			(vias allowed)
			(pads allowed)
			(copperpour not_allowed)
			(footprints allowed)
		)
		(placement
			(enabled no)
			(sheetname "")
		)
		(fill
			(thermal_gap 0.5)
			(thermal_bridge_width 0.5)
			(island_removal_mode 0)
		)
		(polygon
			(pts
				(arc
					(start 60.177426 -285.132526)
					(mid 60.173706 -285.141506)
					(end 60.164726 -285.145226)
				)
				(arc
					(start 58.691526 -285.145226)
					(mid 58.682546 -285.141506)
					(end 58.678826 -285.132526)
				)
				(arc
					(start 58.678826 -284.637988)
					(mid 58.682546 -284.629008)
					(end 58.691526 -284.625288)
				)
				(arc
					(start 60.164726 -284.625288)
					(mid 60.173706 -284.629008)
					(end 60.177426 -284.637988)
				)
			)
		)
	)
	(zone
		(layer "In1.Cu")
		(hatch none 0.5)
		(connect_pads
			(clearance 0)
		)
		(min_thickness 0.25)
		(keepout
			(tracks not_allowed)
			(vias allowed)
			(pads allowed)
			(copperpour not_allowed)
			(footprints allowed)
		)
		(placement
			(enabled no)
			(sheetname "")
		)
		(fill
			(thermal_gap 0.5)
			(thermal_bridge_width 0.5)
			(island_removal_mode 0)
		)
		(polygon
			(pts
				(arc
					(start 184.365392 -314.032392)
					(mid 184.361672 -314.041372)
					(end 184.352692 -314.045092)
				)
				(arc
					(start 182.879492 -314.045092)
					(mid 182.870512 -314.041372)
					(end 182.866792 -314.032392)
				)
				(arc
					(start 182.866792 -313.537854)
					(mid 182.870512 -313.528874)
					(end 182.879492 -313.525154)
				)
				(arc
					(start 184.352692 -313.525154)
					(mid 184.361672 -313.528874)
					(end 184.365392 -313.537854)
				)
			)
		)
	)
	(zone
		(layer "In1.Cu")
		(hatch none 0.5)
		(connect_pads
			(clearance 0)
		)
		(min_thickness 0.25)
		(keepout
			(tracks not_allowed)
			(vias allowed)
			(pads allowed)
			(copperpour not_allowed)
			(footprints allowed)
		)
		(placement
			(enabled no)
			(sheetname "")
		)
		(fill
			(thermal_gap 0.5)
			(thermal_bridge_width 0.5)
			(island_removal_mode 0)
		)
		(polygon
			(pts
				(arc
					(start 447.393568 -261.332218)
					(mid 447.389848 -261.341198)
					(end 447.380868 -261.344918)
				)
				(arc
					(start 445.907668 -261.344918)
					(mid 445.898688 -261.341198)
					(end 445.894968 -261.332218)
				)
				(arc
					(start 445.894968 -260.83768)
					(mid 445.898688 -260.8287)
					(end 445.907668 -260.82498)
				)
				(arc
					(start 447.380868 -260.82498)
					(mid 447.389848 -260.8287)
					(end 447.393568 -260.83768)
				)
			)
		)
	)
	(zone
		(layer "In1.Cu")
		(hatch none 0.5)
		(connect_pads
			(clearance 0)
		)
		(min_thickness 0.25)
		(keepout
			(tracks not_allowed)
			(vias allowed)
			(pads allowed)
			(copperpour not_allowed)
			(footprints allowed)
		)
		(placement
			(enabled no)
			(sheetname "")
		)
		(fill
			(thermal_gap 0.5)
			(thermal_bridge_width 0.5)
			(island_removal_mode 0)
		)
		(polygon
			(pts
				(arc
					(start 288.929318 -202.682094)
					(mid 288.925598 -202.691074)
					(end 288.916618 -202.694794)
				)
				(arc
					(start 287.443418 -202.694794)
					(mid 287.434438 -202.691074)
					(end 287.430718 -202.682094)
				)
				(arc
					(start 287.430718 -202.187556)
					(mid 287.434438 -202.178576)
					(end 287.443418 -202.174856)
				)
				(arc
					(start 288.916618 -202.174856)
					(mid 288.925598 -202.178576)
					(end 288.929318 -202.187556)
				)
			)
		)
	)
	(zone
		(layer "In1.Cu")
		(hatch none 0.5)
		(connect_pads
			(clearance 0)
		)
		(min_thickness 0.25)
		(keepout
			(tracks not_allowed)
			(vias allowed)
			(pads allowed)
			(copperpour not_allowed)
			(footprints allowed)
		)
		(placement
			(enabled no)
			(sheetname "")
		)
		(fill
			(thermal_gap 0.5)
			(thermal_bridge_width 0.5)
			(island_removal_mode 0)
		)
		(polygon
			(pts
				(arc
					(start 147.19808 -390.761474)
					(mid 146.89328 -390.761474)
					(end 147.19808 -390.761474)
				)
			)
		)
	)
	(zone
		(layer "In1.Cu")
		(hatch none 0.5)
		(connect_pads
			(clearance 0)
		)
		(min_thickness 0.25)
		(keepout
			(tracks not_allowed)
			(vias allowed)
			(pads allowed)
			(copperpour not_allowed)
			(footprints allowed)
		)
		(placement
			(enabled no)
			(sheetname "")
		)
		(fill
			(thermal_gap 0.5)
			(thermal_bridge_width 0.5)
			(island_removal_mode 0)
		)
		(polygon
			(pts
				(arc
					(start 30.001464 -197.582536)
					(mid 29.997744 -197.591516)
					(end 29.988764 -197.595236)
				)
				(arc
					(start 28.515564 -197.595236)
					(mid 28.506584 -197.591516)
					(end 28.502864 -197.582536)
				)
				(arc
					(start 28.502864 -197.087998)
					(mid 28.506584 -197.079018)
					(end 28.515564 -197.075298)
				)
				(arc
					(start 29.988764 -197.075298)
					(mid 29.997744 -197.079018)
					(end 30.001464 -197.087998)
				)
			)
		)
	)
	(zone
		(layer "In1.Cu")
		(hatch none 0.5)
		(connect_pads
			(clearance 0)
		)
		(min_thickness 0.25)
		(keepout
			(tracks not_allowed)
			(vias allowed)
			(pads allowed)
			(copperpour not_allowed)
			(footprints allowed)
		)
		(placement
			(enabled no)
			(sheetname "")
		)
		(fill
			(thermal_gap 0.5)
			(thermal_bridge_width 0.5)
			(island_removal_mode 0)
		)
		(polygon
			(pts
				(arc
					(start 450.8373 -212.032088)
					(mid 450.83358 -212.041068)
					(end 450.8246 -212.044788)
				)
				(arc
					(start 449.3514 -212.044788)
					(mid 449.34242 -212.041068)
					(end 449.3387 -212.032088)
				)
				(arc
					(start 449.3387 -211.53755)
					(mid 449.34242 -211.52857)
					(end 449.3514 -211.52485)
				)
				(arc
					(start 450.8246 -211.52485)
					(mid 450.83358 -211.52857)
					(end 450.8373 -211.53755)
				)
			)
		)
	)
	(zone
		(layer "In1.Cu")
		(hatch none 0.5)
		(connect_pads
			(clearance 0)
		)
		(min_thickness 0.25)
		(keepout
			(tracks not_allowed)
			(vias allowed)
			(pads allowed)
			(copperpour not_allowed)
			(footprints allowed)
		)
		(placement
			(enabled no)
			(sheetname "")
		)
		(fill
			(thermal_gap 0.5)
			(thermal_bridge_width 0.5)
			(island_removal_mode 0)
		)
		(polygon
			(pts
				(arc
					(start 420.661338 -240.082324)
					(mid 420.657618 -240.091304)
					(end 420.648638 -240.095024)
				)
				(arc
					(start 419.175438 -240.095024)
					(mid 419.166458 -240.091304)
					(end 419.162738 -240.082324)
				)
				(arc
					(start 419.162738 -239.587786)
					(mid 419.166458 -239.578806)
					(end 419.175438 -239.575086)
				)
				(arc
					(start 420.648638 -239.575086)
					(mid 420.657618 -239.578806)
					(end 420.661338 -239.587786)
				)
			)
		)
	)
	(zone
		(layer "In1.Cu")
		(hatch none 0.5)
		(connect_pads
			(clearance 0)
		)
		(min_thickness 0.25)
		(keepout
			(tracks not_allowed)
			(vias allowed)
			(pads allowed)
			(copperpour not_allowed)
			(footprints allowed)
		)
		(placement
			(enabled no)
			(sheetname "")
		)
		(fill
			(thermal_gap 0.5)
			(thermal_bridge_width 0.5)
			(island_removal_mode 0)
		)
		(polygon
			(pts
				(arc
					(start 154.398218 -390.761474)
					(mid 154.093418 -390.761474)
					(end 154.398218 -390.761474)
				)
			)
		)
	)
	(zone
		(layer "In1.Cu")
		(hatch none 0.5)
		(connect_pads
			(clearance 0)
		)
		(min_thickness 0.25)
		(keepout
			(tracks not_allowed)
			(vias allowed)
			(pads allowed)
			(copperpour not_allowed)
			(footprints allowed)
		)
		(placement
			(enabled no)
			(sheetname "")
		)
		(fill
			(thermal_gap 0.5)
			(thermal_bridge_width 0.5)
			(island_removal_mode 0)
		)
		(polygon
			(pts
				(arc
					(start 187.809378 -282.582366)
					(mid 187.805658 -282.591346)
					(end 187.796678 -282.595066)
				)
				(arc
					(start 186.323478 -282.595066)
					(mid 186.314498 -282.591346)
					(end 186.310778 -282.582366)
				)
				(arc
					(start 186.310778 -282.087828)
					(mid 186.314498 -282.078848)
					(end 186.323478 -282.075128)
				)
				(arc
					(start 187.796678 -282.075128)
					(mid 187.805658 -282.078848)
					(end 187.809378 -282.087828)
				)
			)
		)
	)
	(zone
		(layer "In1.Cu")
		(hatch none 0.5)
		(connect_pads
			(clearance 0)
		)
		(min_thickness 0.25)
		(keepout
			(tracks not_allowed)
			(vias allowed)
			(pads allowed)
			(copperpour not_allowed)
			(footprints allowed)
		)
		(placement
			(enabled no)
			(sheetname "")
		)
		(fill
			(thermal_gap 0.5)
			(thermal_bridge_width 0.5)
			(island_removal_mode 0)
		)
		(polygon
			(pts
				(arc
					(start 180.265324 -211.182458)
					(mid 180.261604 -211.191438)
					(end 180.252624 -211.195158)
				)
				(arc
					(start 178.779424 -211.195158)
					(mid 178.770444 -211.191438)
					(end 178.766724 -211.182458)
				)
				(arc
					(start 178.766724 -210.68792)
					(mid 178.770444 -210.67894)
					(end 178.779424 -210.67522)
				)
				(arc
					(start 180.252624 -210.67522)
					(mid 180.261604 -210.67894)
					(end 180.265324 -210.68792)
				)
			)
		)
	)
	(zone
		(layer "In1.Cu")
		(hatch none 0.5)
		(connect_pads
			(clearance 0)
		)
		(min_thickness 0.25)
		(keepout
			(tracks not_allowed)
			(vias allowed)
			(pads allowed)
			(copperpour not_allowed)
			(footprints allowed)
		)
		(placement
			(enabled no)
			(sheetname "")
		)
		(fill
			(thermal_gap 0.5)
			(thermal_bridge_width 0.5)
			(island_removal_mode 0)
		)
		(polygon
			(pts
				(arc
					(start 132.961126 -386.003292)
					(mid 132.580126 -386.003292)
					(end 132.961126 -386.003292)
				)
			)
		)
	)
	(zone
		(layer "In1.Cu")
		(hatch none 0.5)
		(connect_pads
			(clearance 0)
		)
		(min_thickness 0.25)
		(keepout
			(tracks not_allowed)
			(vias allowed)
			(pads allowed)
			(copperpour not_allowed)
			(footprints allowed)
		)
		(placement
			(enabled no)
			(sheetname "")
		)
		(fill
			(thermal_gap 0.5)
			(thermal_bridge_width 0.5)
			(island_removal_mode 0)
		)
		(polygon
			(pts
				(arc
					(start 212.820504 0.553974)
					(mid 212.842822 0.607856)
					(end 212.896704 0.630174)
				)
				(arc
					(start 213.508844 0.630174)
					(mid 213.562726 0.607856)
					(end 213.585044 0.553974)
				)
				(arc
					(start 213.585044 -0.543306)
					(mid 213.562726 -0.597188)
					(end 213.508844 -0.619506)
				)
				(arc
					(start 212.896704 -0.619506)
					(mid 212.842822 -0.597188)
					(end 212.820504 -0.543306)
				)
			)
		)
	)
	(zone
		(layer "In1.Cu")
		(hatch none 0.5)
		(connect_pads
			(clearance 0)
		)
		(min_thickness 0.25)
		(keepout
			(tracks not_allowed)
			(vias allowed)
			(pads allowed)
			(copperpour not_allowed)
			(footprints allowed)
		)
		(placement
			(enabled no)
			(sheetname "")
		)
		(fill
			(thermal_gap 0.5)
			(thermal_bridge_width 0.5)
			(island_removal_mode 0)
		)
		(polygon
			(pts
				(arc
					(start 420.28872 -394.385292)
					(mid 419.90772 -394.385292)
					(end 420.28872 -394.385292)
				)
			)
		)
	)
	(zone
		(layer "In1.Cu")
		(hatch none 0.5)
		(connect_pads
			(clearance 0)
		)
		(min_thickness 0.25)
		(keepout
			(tracks not_allowed)
			(vias allowed)
			(pads allowed)
			(copperpour not_allowed)
			(footprints allowed)
		)
		(placement
			(enabled no)
			(sheetname "")
		)
		(fill
			(thermal_gap 0.5)
			(thermal_bridge_width 0.5)
			(island_removal_mode 0)
		)
		(polygon
			(pts
				(arc
					(start 342.388698 -394.385292)
					(mid 342.007698 -394.385292)
					(end 342.388698 -394.385292)
				)
			)
		)
	)
	(zone
		(layer "In1.Cu")
		(hatch none 0.5)
		(connect_pads
			(clearance 0)
		)
		(min_thickness 0.25)
		(keepout
			(tracks not_allowed)
			(vias allowed)
			(pads allowed)
			(copperpour not_allowed)
			(footprints allowed)
		)
		(placement
			(enabled no)
			(sheetname "")
		)
		(fill
			(thermal_gap 0.5)
			(thermal_bridge_width 0.5)
			(island_removal_mode 0)
		)
		(polygon
			(pts
				(arc
					(start 320.3702 -399.143474)
					(mid 320.0654 -399.143474)
					(end 320.3702 -399.143474)
				)
			)
		)
	)
	(zone
		(layer "In1.Cu")
		(hatch none 0.5)
		(connect_pads
			(clearance 0)
		)
		(min_thickness 0.25)
		(keepout
			(tracks not_allowed)
			(vias allowed)
			(pads allowed)
			(copperpour not_allowed)
			(footprints allowed)
		)
		(placement
			(enabled no)
			(sheetname "")
		)
		(fill
			(thermal_gap 0.5)
			(thermal_bridge_width 0.5)
			(island_removal_mode 0)
		)
		(polygon
			(pts
				(arc
					(start 25.901396 -246.882412)
					(mid 25.897676 -246.891392)
					(end 25.888696 -246.895112)
				)
				(arc
					(start 24.415496 -246.895112)
					(mid 24.406516 -246.891392)
					(end 24.402796 -246.882412)
				)
				(arc
					(start 24.402796 -246.387874)
					(mid 24.406516 -246.378894)
					(end 24.415496 -246.375174)
				)
				(arc
					(start 25.888696 -246.375174)
					(mid 25.897676 -246.378894)
					(end 25.901396 -246.387874)
				)
			)
		)
	)
	(zone
		(layer "In1.Cu")
		(hatch none 0.5)
		(connect_pads
			(clearance 0)
		)
		(min_thickness 0.25)
		(keepout
			(tracks not_allowed)
			(vias allowed)
			(pads allowed)
			(copperpour not_allowed)
			(footprints allowed)
		)
		(placement
			(enabled no)
			(sheetname "")
		)
		(fill
			(thermal_gap 0.5)
			(thermal_bridge_width 0.5)
			(island_removal_mode 0)
		)
		(polygon
			(pts
				(arc
					(start 80.098138 -383.92227)
					(mid 79.793338 -383.92227)
					(end 80.098138 -383.92227)
				)
			)
		)
	)
	(zone
		(layer "In1.Cu")
		(hatch none 0.5)
		(connect_pads
			(clearance 0)
		)
		(min_thickness 0.25)
		(keepout
			(tracks not_allowed)
			(vias allowed)
			(pads allowed)
			(copperpour not_allowed)
			(footprints allowed)
		)
		(placement
			(enabled no)
			(sheetname "")
		)
		(fill
			(thermal_gap 0.5)
			(thermal_bridge_width 0.5)
			(island_removal_mode 0)
		)
		(polygon
			(pts
				(arc
					(start 293.029386 -295.33215)
					(mid 293.025666 -295.34113)
					(end 293.016686 -295.34485)
				)
				(arc
					(start 291.543486 -295.34485)
					(mid 291.534506 -295.34113)
					(end 291.530786 -295.33215)
				)
				(arc
					(start 291.530786 -294.837612)
					(mid 291.534506 -294.828632)
					(end 291.543486 -294.824912)
				)
				(arc
					(start 293.016686 -294.824912)
					(mid 293.025666 -294.828632)
					(end 293.029386 -294.837612)
				)
			)
		)
	)
	(zone
		(layer "In1.Cu")
		(hatch none 0.5)
		(connect_pads
			(clearance 0)
		)
		(min_thickness 0.25)
		(keepout
			(tracks not_allowed)
			(vias allowed)
			(pads allowed)
			(copperpour not_allowed)
			(footprints allowed)
		)
		(placement
			(enabled no)
			(sheetname "")
		)
		(fill
			(thermal_gap 0.5)
			(thermal_bridge_width 0.5)
			(island_removal_mode 0)
		)
		(polygon
			(pts
				(arc
					(start 22.45741 -242.632484)
					(mid 22.45369 -242.641464)
					(end 22.44471 -242.645184)
				)
				(arc
					(start 20.97151 -242.645184)
					(mid 20.96253 -242.641464)
					(end 20.95881 -242.632484)
				)
				(arc
					(start 20.95881 -242.137946)
					(mid 20.96253 -242.128966)
					(end 20.97151 -242.125246)
				)
				(arc
					(start 22.44471 -242.125246)
					(mid 22.45369 -242.128966)
					(end 22.45741 -242.137946)
				)
			)
		)
	)
	(zone
		(layer "In1.Cu")
		(hatch none 0.5)
		(connect_pads
			(clearance 0)
		)
		(min_thickness 0.25)
		(keepout
			(tracks not_allowed)
			(vias allowed)
			(pads allowed)
			(copperpour not_allowed)
			(footprints allowed)
		)
		(placement
			(enabled no)
			(sheetname "")
		)
		(fill
			(thermal_gap 0.5)
			(thermal_bridge_width 0.5)
			(island_removal_mode 0)
		)
		(polygon
			(pts
				(arc
					(start 18.357342 -268.982444)
					(mid 18.353622 -268.991424)
					(end 18.344642 -268.995144)
				)
				(arc
					(start 16.871442 -268.995144)
					(mid 16.862462 -268.991424)
					(end 16.858742 -268.982444)
				)
				(arc
					(start 16.858742 -268.487906)
					(mid 16.862462 -268.478926)
					(end 16.871442 -268.475206)
				)
				(arc
					(start 18.344642 -268.475206)
					(mid 18.353622 -268.478926)
					(end 18.357342 -268.487906)
				)
			)
		)
	)
	(zone
		(layer "In1.Cu")
		(hatch none 0.5)
		(connect_pads
			(clearance 0)
		)
		(min_thickness 0.25)
		(keepout
			(tracks not_allowed)
			(vias allowed)
			(pads allowed)
			(copperpour not_allowed)
			(footprints allowed)
		)
		(placement
			(enabled no)
			(sheetname "")
		)
		(fill
			(thermal_gap 0.5)
			(thermal_bridge_width 0.5)
			(island_removal_mode 0)
		)
		(polygon
			(pts
				(arc
					(start 33.445196 -293.632382)
					(mid 33.441476 -293.641362)
					(end 33.432496 -293.645082)
				)
				(arc
					(start 31.959296 -293.645082)
					(mid 31.950316 -293.641362)
					(end 31.946596 -293.632382)
				)
				(arc
					(start 31.946596 -293.137844)
					(mid 31.950316 -293.128864)
					(end 31.959296 -293.125144)
				)
				(arc
					(start 33.432496 -293.125144)
					(mid 33.441476 -293.128864)
					(end 33.445196 -293.137844)
				)
			)
		)
	)
	(zone
		(layer "In1.Cu")
		(hatch none 0.5)
		(connect_pads
			(clearance 0)
		)
		(min_thickness 0.25)
		(keepout
			(tracks not_allowed)
			(vias allowed)
			(pads allowed)
			(copperpour not_allowed)
			(footprints allowed)
		)
		(placement
			(enabled no)
			(sheetname "")
		)
		(fill
			(thermal_gap 0.5)
			(thermal_bridge_width 0.5)
			(island_removal_mode 0)
		)
		(polygon
			(pts
				(arc
					(start 337.18881 -397.156432)
					(mid 336.80781 -397.156432)
					(end 337.18881 -397.156432)
				)
			)
		)
	)
	(zone
		(layer "In1.Cu")
		(hatch none 0.5)
		(connect_pads
			(clearance 0)
		)
		(min_thickness 0.25)
		(keepout
			(tracks not_allowed)
			(vias allowed)
			(pads allowed)
			(copperpour not_allowed)
			(footprints allowed)
		)
		(placement
			(enabled no)
			(sheetname "")
		)
		(fill
			(thermal_gap 0.5)
			(thermal_bridge_width 0.5)
			(island_removal_mode 0)
		)
		(polygon
			(pts
				(arc
					(start 277.941532 -219.682314)
					(mid 277.937812 -219.691294)
					(end 277.928832 -219.695014)
				)
				(arc
					(start 276.455632 -219.695014)
					(mid 276.446652 -219.691294)
					(end 276.442932 -219.682314)
				)
				(arc
					(start 276.442932 -219.187776)
					(mid 276.446652 -219.178796)
					(end 276.455632 -219.175076)
				)
				(arc
					(start 277.928832 -219.175076)
					(mid 277.937812 -219.178796)
					(end 277.941532 -219.187776)
				)
			)
		)
	)
	(zone
		(layer "In1.Cu")
		(hatch none 0.5)
		(connect_pads
			(clearance 0)
		)
		(min_thickness 0.25)
		(keepout
			(tracks not_allowed)
			(vias allowed)
			(pads allowed)
			(copperpour not_allowed)
			(footprints allowed)
		)
		(placement
			(enabled no)
			(sheetname "")
		)
		(fill
			(thermal_gap 0.5)
			(thermal_bridge_width 0.5)
			(island_removal_mode 0)
		)
		(polygon
			(pts
				(arc
					(start 306.260754 -394.385292)
					(mid 305.879754 -394.385292)
					(end 306.260754 -394.385292)
				)
			)
		)
	)
	(zone
		(layer "In1.Cu")
		(hatch none 0.5)
		(connect_pads
			(clearance 0)
		)
		(min_thickness 0.25)
		(keepout
			(tracks not_allowed)
			(vias allowed)
			(pads allowed)
			(copperpour not_allowed)
			(footprints allowed)
		)
		(placement
			(enabled no)
			(sheetname "")
		)
		(fill
			(thermal_gap 0.5)
			(thermal_bridge_width 0.5)
			(island_removal_mode 0)
		)
		(polygon
			(pts
				(arc
					(start 300.57344 -303.83226)
					(mid 300.56972 -303.84124)
					(end 300.56074 -303.84496)
				)
				(arc
					(start 299.08754 -303.84496)
					(mid 299.07856 -303.84124)
					(end 299.07484 -303.83226)
				)
				(arc
					(start 299.07484 -303.337722)
					(mid 299.07856 -303.328742)
					(end 299.08754 -303.325022)
				)
				(arc
					(start 300.56074 -303.325022)
					(mid 300.56972 -303.328742)
					(end 300.57344 -303.337722)
				)
			)
		)
	)
	(zone
		(layer "In1.Cu")
		(hatch none 0.5)
		(connect_pads
			(clearance 0)
		)
		(min_thickness 0.25)
		(keepout
			(tracks not_allowed)
			(vias allowed)
			(pads allowed)
			(copperpour not_allowed)
			(footprints allowed)
		)
		(placement
			(enabled no)
			(sheetname "")
		)
		(fill
			(thermal_gap 0.5)
			(thermal_bridge_width 0.5)
			(island_removal_mode 0)
		)
		(polygon
			(pts
				(arc
					(start 270.397478 -236.68228)
					(mid 270.393758 -236.69126)
					(end 270.384778 -236.69498)
				)
				(arc
					(start 268.911578 -236.69498)
					(mid 268.902598 -236.69126)
					(end 268.898878 -236.68228)
				)
				(arc
					(start 268.898878 -236.187742)
					(mid 268.902598 -236.178762)
					(end 268.911578 -236.175042)
				)
				(arc
					(start 270.384778 -236.175042)
					(mid 270.393758 -236.178762)
					(end 270.397478 -236.187742)
				)
			)
		)
	)
	(zone
		(layer "In1.Cu")
		(hatch none 0.5)
		(connect_pads
			(clearance 0)
		)
		(min_thickness 0.25)
		(keepout
			(tracks not_allowed)
			(vias allowed)
			(pads allowed)
			(copperpour not_allowed)
			(footprints allowed)
		)
		(placement
			(enabled no)
			(sheetname "")
		)
		(fill
			(thermal_gap 0.5)
			(thermal_bridge_width 0.5)
			(island_removal_mode 0)
		)
		(polygon
			(pts
				(arc
					(start 428.205392 -228.18217)
					(mid 428.201672 -228.19115)
					(end 428.192692 -228.19487)
				)
				(arc
					(start 426.719492 -228.19487)
					(mid 426.710512 -228.19115)
					(end 426.706792 -228.18217)
				)
				(arc
					(start 426.706792 -227.687632)
					(mid 426.710512 -227.678652)
					(end 426.719492 -227.674932)
				)
				(arc
					(start 428.192692 -227.674932)
					(mid 428.201672 -227.678652)
					(end 428.205392 -227.687632)
				)
			)
		)
	)
	(zone
		(layer "In1.Cu")
		(hatch none 0.5)
		(connect_pads
			(clearance 0)
		)
		(min_thickness 0.25)
		(keepout
			(tracks not_allowed)
			(vias allowed)
			(pads allowed)
			(copperpour not_allowed)
			(footprints allowed)
		)
		(placement
			(enabled no)
			(sheetname "")
		)
		(fill
			(thermal_gap 0.5)
			(thermal_bridge_width 0.5)
			(island_removal_mode 0)
		)
		(polygon
			(pts
				(arc
					(start 311.860946 -397.156432)
					(mid 311.479946 -397.156432)
					(end 311.860946 -397.156432)
				)
			)
		)
	)
	(zone
		(layer "In1.Cu")
		(hatch none 0.5)
		(connect_pads
			(clearance 0)
		)
		(min_thickness 0.25)
		(keepout
			(tracks not_allowed)
			(vias allowed)
			(pads allowed)
			(copperpour not_allowed)
			(footprints allowed)
		)
		(placement
			(enabled no)
			(sheetname "")
		)
		(fill
			(thermal_gap 0.5)
			(thermal_bridge_width 0.5)
			(island_removal_mode 0)
		)
		(polygon
			(pts
				(arc
					(start 300.57344 -294.482266)
					(mid 300.56972 -294.491246)
					(end 300.56074 -294.494966)
				)
				(arc
					(start 299.08754 -294.494966)
					(mid 299.07856 -294.491246)
					(end 299.07484 -294.482266)
				)
				(arc
					(start 299.07484 -293.987728)
					(mid 299.07856 -293.978748)
					(end 299.08754 -293.975028)
				)
				(arc
					(start 300.56074 -293.975028)
					(mid 300.56972 -293.978748)
					(end 300.57344 -293.987728)
				)
			)
		)
	)
	(zone
		(layer "In1.Cu")
		(hatch none 0.5)
		(connect_pads
			(clearance 0)
		)
		(min_thickness 0.25)
		(keepout
			(tracks not_allowed)
			(vias allowed)
			(pads allowed)
			(copperpour not_allowed)
			(footprints allowed)
		)
		(placement
			(enabled no)
			(sheetname "")
		)
		(fill
			(thermal_gap 0.5)
			(thermal_bridge_width 0.5)
			(island_removal_mode 0)
		)
		(polygon
			(pts
				(arc
					(start 416.398202 -399.143474)
					(mid 416.093402 -399.143474)
					(end 416.398202 -399.143474)
				)
			)
		)
	)
	(zone
		(layer "In1.Cu")
		(hatch none 0.5)
		(connect_pads
			(clearance 0)
		)
		(min_thickness 0.25)
		(keepout
			(tracks not_allowed)
			(vias allowed)
			(pads allowed)
			(copperpour not_allowed)
			(footprints allowed)
		)
		(placement
			(enabled no)
			(sheetname "")
		)
		(fill
			(thermal_gap 0.5)
			(thermal_bridge_width 0.5)
			(island_removal_mode 0)
		)
		(polygon
			(pts
				(arc
					(start 22.45741 -197.582536)
					(mid 22.45369 -197.591516)
					(end 22.44471 -197.595236)
				)
				(arc
					(start 20.97151 -197.595236)
					(mid 20.96253 -197.591516)
					(end 20.95881 -197.582536)
				)
				(arc
					(start 20.95881 -197.087998)
					(mid 20.96253 -197.079018)
					(end 20.97151 -197.075298)
				)
				(arc
					(start 22.44471 -197.075298)
					(mid 22.45369 -197.079018)
					(end 22.45741 -197.087998)
				)
			)
		)
	)
	(zone
		(layer "In1.Cu")
		(hatch none 0.5)
		(connect_pads
			(clearance 0)
		)
		(min_thickness 0.25)
		(keepout
			(tracks not_allowed)
			(vias allowed)
			(pads allowed)
			(copperpour not_allowed)
			(footprints allowed)
		)
		(placement
			(enabled no)
			(sheetname "")
		)
		(fill
			(thermal_gap 0.5)
			(thermal_bridge_width 0.5)
			(island_removal_mode 0)
		)
		(polygon
			(pts
				(arc
					(start 118.270274 -383.92227)
					(mid 117.965474 -383.92227)
					(end 118.270274 -383.92227)
				)
			)
		)
	)
	(zone
		(layer "In1.Cu")
		(hatch none 0.5)
		(connect_pads
			(clearance 0)
		)
		(min_thickness 0.25)
		(keepout
			(tracks not_allowed)
			(vias allowed)
			(pads allowed)
			(copperpour not_allowed)
			(footprints allowed)
		)
		(placement
			(enabled no)
			(sheetname "")
		)
		(fill
			(thermal_gap 0.5)
			(thermal_bridge_width 0.5)
			(island_removal_mode 0)
		)
		(polygon
			(pts
				(arc
					(start 184.365392 -294.48252)
					(mid 184.361672 -294.4915)
					(end 184.352692 -294.49522)
				)
				(arc
					(start 182.879492 -294.49522)
					(mid 182.870512 -294.4915)
					(end 182.866792 -294.48252)
				)
				(arc
					(start 182.866792 -293.987982)
					(mid 182.870512 -293.979002)
					(end 182.879492 -293.975282)
				)
				(arc
					(start 184.352692 -293.975282)
					(mid 184.361672 -293.979002)
					(end 184.365392 -293.987982)
				)
			)
		)
	)
	(zone
		(layer "In1.Cu")
		(hatch none 0.5)
		(connect_pads
			(clearance 0)
		)
		(min_thickness 0.25)
		(keepout
			(tracks not_allowed)
			(vias allowed)
			(pads allowed)
			(copperpour not_allowed)
			(footprints allowed)
		)
		(placement
			(enabled no)
			(sheetname "")
		)
		(fill
			(thermal_gap 0.5)
			(thermal_bridge_width 0.5)
			(island_removal_mode 0)
		)
		(polygon
			(pts
				(arc
					(start 169.277284 -200.98258)
					(mid 169.273564 -200.99156)
					(end 169.264584 -200.99528)
				)
				(arc
					(start 167.791384 -200.99528)
					(mid 167.782404 -200.99156)
					(end 167.778684 -200.98258)
				)
				(arc
					(start 167.778684 -200.488042)
					(mid 167.782404 -200.479062)
					(end 167.791384 -200.475342)
				)
				(arc
					(start 169.264584 -200.475342)
					(mid 169.273564 -200.479062)
					(end 169.277284 -200.488042)
				)
			)
		)
	)
	(zone
		(layer "In1.Cu")
		(hatch none 0.5)
		(connect_pads
			(clearance 0)
		)
		(min_thickness 0.25)
		(keepout
			(tracks not_allowed)
			(vias allowed)
			(pads allowed)
			(copperpour not_allowed)
			(footprints allowed)
		)
		(placement
			(enabled no)
			(sheetname "")
		)
		(fill
			(thermal_gap 0.5)
			(thermal_bridge_width 0.5)
			(island_removal_mode 0)
		)
		(polygon
			(pts
				(arc
					(start 96.898206 -383.92227)
					(mid 96.593406 -383.92227)
					(end 96.898206 -383.92227)
				)
			)
		)
	)
	(zone
		(layer "In1.Cu")
		(hatch none 0.5)
		(connect_pads
			(clearance 0)
		)
		(min_thickness 0.25)
		(keepout
			(tracks not_allowed)
			(vias allowed)
			(pads allowed)
			(copperpour not_allowed)
			(footprints allowed)
		)
		(placement
			(enabled no)
			(sheetname "")
		)
		(fill
			(thermal_gap 0.5)
			(thermal_bridge_width 0.5)
			(island_removal_mode 0)
		)
		(polygon
			(pts
				(arc
					(start 45.089318 -278.332438)
					(mid 45.085598 -278.341418)
					(end 45.076618 -278.345138)
				)
				(arc
					(start 43.603418 -278.345138)
					(mid 43.594438 -278.341418)
					(end 43.590718 -278.332438)
				)
				(arc
					(start 43.590718 -277.8379)
					(mid 43.594438 -277.82892)
					(end 43.603418 -277.8252)
				)
				(arc
					(start 45.076618 -277.8252)
					(mid 45.085598 -277.82892)
					(end 45.089318 -277.8379)
				)
			)
		)
	)
	(zone
		(layer "In1.Cu")
		(hatch none 0.5)
		(connect_pads
			(clearance 0)
		)
		(min_thickness 0.25)
		(keepout
			(tracks not_allowed)
			(vias allowed)
			(pads allowed)
			(copperpour not_allowed)
			(footprints allowed)
		)
		(placement
			(enabled no)
			(sheetname "")
		)
		(fill
			(thermal_gap 0.5)
			(thermal_bridge_width 0.5)
			(island_removal_mode 0)
		)
		(polygon
			(pts
				(arc
					(start 435.749446 -312.332116)
					(mid 435.745726 -312.341096)
					(end 435.736746 -312.344816)
				)
				(arc
					(start 434.263546 -312.344816)
					(mid 434.254566 -312.341096)
					(end 434.250846 -312.332116)
				)
				(arc
					(start 434.250846 -311.837578)
					(mid 434.254566 -311.828598)
					(end 434.263546 -311.824878)
				)
				(arc
					(start 435.736746 -311.824878)
					(mid 435.745726 -311.828598)
					(end 435.749446 -311.837578)
				)
			)
		)
	)
	(zone
		(layer "In1.Cu")
		(hatch none 0.5)
		(connect_pads
			(clearance 0)
		)
		(min_thickness 0.25)
		(keepout
			(tracks not_allowed)
			(vias allowed)
			(pads allowed)
			(copperpour not_allowed)
			(footprints allowed)
		)
		(placement
			(enabled no)
			(sheetname "")
		)
		(fill
			(thermal_gap 0.5)
			(thermal_bridge_width 0.5)
			(island_removal_mode 0)
		)
		(polygon
			(pts
				(arc
					(start 296.473372 -290.232338)
					(mid 296.469652 -290.241318)
					(end 296.460672 -290.245038)
				)
				(arc
					(start 294.987472 -290.245038)
					(mid 294.978492 -290.241318)
					(end 294.974772 -290.232338)
				)
				(arc
					(start 294.974772 -289.7378)
					(mid 294.978492 -289.72882)
					(end 294.987472 -289.7251)
				)
				(arc
					(start 296.460672 -289.7251)
					(mid 296.469652 -289.72882)
					(end 296.473372 -289.7378)
				)
			)
		)
	)
	(zone
		(layer "In1.Cu")
		(hatch none 0.5)
		(connect_pads
			(clearance 0)
		)
		(min_thickness 0.25)
		(keepout
			(tracks not_allowed)
			(vias allowed)
			(pads allowed)
			(copperpour not_allowed)
			(footprints allowed)
		)
		(placement
			(enabled no)
			(sheetname "")
		)
		(fill
			(thermal_gap 0.5)
			(thermal_bridge_width 0.5)
			(island_removal_mode 0)
		)
		(polygon
			(pts
				(arc
					(start 162.797998 -383.92227)
					(mid 162.493198 -383.92227)
					(end 162.797998 -383.92227)
				)
			)
		)
	)
	(zone
		(layer "In1.Cu")
		(hatch none 0.5)
		(connect_pads
			(clearance 0)
		)
		(min_thickness 0.25)
		(keepout
			(tracks not_allowed)
			(vias allowed)
			(pads allowed)
			(copperpour not_allowed)
			(footprints allowed)
		)
		(placement
			(enabled no)
			(sheetname "")
		)
		(fill
			(thermal_gap 0.5)
			(thermal_bridge_width 0.5)
			(island_removal_mode 0)
		)
		(polygon
			(pts
				(arc
					(start 265.87831 -205.834996)
					(mid 265.21791 -205.834996)
					(end 265.87831 -205.834996)
				)
			)
		)
	)
	(zone
		(layer "In1.Cu")
		(hatch none 0.5)
		(connect_pads
			(clearance 0)
		)
		(min_thickness 0.25)
		(keepout
			(tracks not_allowed)
			(vias allowed)
			(pads allowed)
			(copperpour not_allowed)
			(footprints allowed)
		)
		(placement
			(enabled no)
			(sheetname "")
		)
		(fill
			(thermal_gap 0.5)
			(thermal_bridge_width 0.5)
			(island_removal_mode 0)
		)
		(polygon
			(pts
				(arc
					(start 385.690872 -399.701258)
					(mid 385.817872 -399.828258)
					(end 385.944872 -399.701258)
				)
				(arc
					(start 385.944872 -399.625058)
					(mid 385.817872 -399.498058)
					(end 385.690872 -399.625058)
				)
			)
		)
	)
	(zone
		(layer "In1.Cu")
		(hatch none 0.5)
		(connect_pads
			(clearance 0)
		)
		(min_thickness 0.25)
		(keepout
			(tracks not_allowed)
			(vias allowed)
			(pads allowed)
			(copperpour not_allowed)
			(footprints allowed)
		)
		(placement
			(enabled no)
			(sheetname "")
		)
		(fill
			(thermal_gap 0.5)
			(thermal_bridge_width 0.5)
			(island_removal_mode 0)
		)
		(polygon
			(pts
				(arc
					(start 349.918528 -399.701258)
					(mid 350.045528 -399.828258)
					(end 350.172528 -399.701258)
				)
				(arc
					(start 350.172528 -399.625058)
					(mid 350.045528 -399.498058)
					(end 349.918528 -399.625058)
				)
			)
		)
	)
	(zone
		(layer "In1.Cu")
		(hatch none 0.5)
		(connect_pads
			(clearance 0)
		)
		(min_thickness 0.25)
		(keepout
			(tracks not_allowed)
			(vias allowed)
			(pads allowed)
			(copperpour not_allowed)
			(footprints allowed)
		)
		(placement
			(enabled no)
			(sheetname "")
		)
		(fill
			(thermal_gap 0.5)
			(thermal_bridge_width 0.5)
			(island_removal_mode 0)
		)
		(polygon
			(pts
				(arc
					(start 417.217352 -214.582248)
					(mid 417.213632 -214.591228)
					(end 417.204652 -214.594948)
				)
				(arc
					(start 415.731452 -214.594948)
					(mid 415.722472 -214.591228)
					(end 415.718752 -214.582248)
				)
				(arc
					(start 415.718752 -214.08771)
					(mid 415.722472 -214.07873)
					(end 415.731452 -214.07501)
				)
				(arc
					(start 417.204652 -214.07501)
					(mid 417.213632 -214.07873)
					(end 417.217352 -214.08771)
				)
			)
		)
	)
	(zone
		(layer "In1.Cu")
		(hatch none 0.5)
		(connect_pads
			(clearance 0)
		)
		(min_thickness 0.25)
		(keepout
			(tracks not_allowed)
			(vias allowed)
			(pads allowed)
			(copperpour not_allowed)
			(footprints allowed)
		)
		(placement
			(enabled no)
			(sheetname "")
		)
		(fill
			(thermal_gap 0.5)
			(thermal_bridge_width 0.5)
			(island_removal_mode 0)
		)
		(polygon
			(pts
				(arc
					(start 296.473372 -224.782126)
					(mid 296.469652 -224.791106)
					(end 296.460672 -224.794826)
				)
				(arc
					(start 294.987472 -224.794826)
					(mid 294.978492 -224.791106)
					(end 294.974772 -224.782126)
				)
				(arc
					(start 294.974772 -224.287588)
					(mid 294.978492 -224.278608)
					(end 294.987472 -224.274888)
				)
				(arc
					(start 296.460672 -224.274888)
					(mid 296.469652 -224.278608)
					(end 296.473372 -224.287588)
				)
			)
		)
	)
	(zone
		(layer "In1.Cu")
		(hatch none 0.5)
		(connect_pads
			(clearance 0)
		)
		(min_thickness 0.25)
		(keepout
			(tracks not_allowed)
			(vias allowed)
			(pads allowed)
			(copperpour not_allowed)
			(footprints allowed)
		)
		(placement
			(enabled no)
			(sheetname "")
		)
		(fill
			(thermal_gap 0.5)
			(thermal_bridge_width 0.5)
			(island_removal_mode 0)
		)
		(polygon
			(pts
				(arc
					(start 350.621092 -294.031162)
					(mid 350.316292 -294.335962)
					(end 350.621092 -294.640762)
				)
				(arc
					(start 351.561146 -294.640762)
					(mid 351.865946 -294.335962)
					(end 351.561146 -294.031162)
				)
			)
		)
	)
	(zone
		(layer "In1.Cu")
		(hatch none 0.5)
		(connect_pads
			(clearance 0)
		)
		(min_thickness 0.25)
		(keepout
			(tracks not_allowed)
			(vias allowed)
			(pads allowed)
			(copperpour not_allowed)
			(footprints allowed)
		)
		(placement
			(enabled no)
			(sheetname "")
		)
		(fill
			(thermal_gap 0.5)
			(thermal_bridge_width 0.5)
			(island_removal_mode 0)
		)
		(polygon
			(pts
				(arc
					(start 270.397478 -229.882192)
					(mid 270.393758 -229.891172)
					(end 270.384778 -229.894892)
				)
				(arc
					(start 268.911578 -229.894892)
					(mid 268.902598 -229.891172)
					(end 268.898878 -229.882192)
				)
				(arc
					(start 268.898878 -229.387654)
					(mid 268.902598 -229.378674)
					(end 268.911578 -229.374954)
				)
				(arc
					(start 270.384778 -229.374954)
					(mid 270.393758 -229.378674)
					(end 270.397478 -229.387654)
				)
			)
		)
	)
	(zone
		(layer "In1.Cu")
		(hatch none 0.5)
		(connect_pads
			(clearance 0)
		)
		(min_thickness 0.25)
		(keepout
			(tracks not_allowed)
			(vias allowed)
			(pads allowed)
			(copperpour not_allowed)
			(footprints allowed)
		)
		(placement
			(enabled no)
			(sheetname "")
		)
		(fill
			(thermal_gap 0.5)
			(thermal_bridge_width 0.5)
			(island_removal_mode 0)
		)
		(polygon
			(pts
				(arc
					(start 424.761406 -254.53213)
					(mid 424.757686 -254.54111)
					(end 424.748706 -254.54483)
				)
				(arc
					(start 423.275506 -254.54483)
					(mid 423.266526 -254.54111)
					(end 423.262806 -254.53213)
				)
				(arc
					(start 423.262806 -254.037592)
					(mid 423.266526 -254.028612)
					(end 423.275506 -254.024892)
				)
				(arc
					(start 424.748706 -254.024892)
					(mid 424.757686 -254.028612)
					(end 424.761406 -254.037592)
				)
			)
		)
	)
	(zone
		(layer "In1.Cu")
		(hatch none 0.5)
		(connect_pads
			(clearance 0)
		)
		(min_thickness 0.25)
		(keepout
			(tracks not_allowed)
			(vias allowed)
			(pads allowed)
			(copperpour not_allowed)
			(footprints allowed)
		)
		(placement
			(enabled no)
			(sheetname "")
		)
		(fill
			(thermal_gap 0.5)
			(thermal_bridge_width 0.5)
			(island_removal_mode 0)
		)
		(polygon
			(pts
				(arc
					(start 285.485332 -309.78221)
					(mid 285.481612 -309.79119)
					(end 285.472632 -309.79491)
				)
				(arc
					(start 283.999432 -309.79491)
					(mid 283.990452 -309.79119)
					(end 283.986732 -309.78221)
				)
				(arc
					(start 283.986732 -309.287672)
					(mid 283.990452 -309.278692)
					(end 283.999432 -309.274972)
				)
				(arc
					(start 285.472632 -309.274972)
					(mid 285.481612 -309.278692)
					(end 285.485332 -309.287672)
				)
			)
		)
	)
	(zone
		(layer "In1.Cu")
		(hatch none 0.5)
		(connect_pads
			(clearance 0)
		)
		(min_thickness 0.25)
		(keepout
			(tracks not_allowed)
			(vias allowed)
			(pads allowed)
			(copperpour not_allowed)
			(footprints allowed)
		)
		(placement
			(enabled no)
			(sheetname "")
		)
		(fill
			(thermal_gap 0.5)
			(thermal_bridge_width 0.5)
			(island_removal_mode 0)
		)
		(polygon
			(pts
				(arc
					(start 129.36093 -389.467344)
					(mid 128.97993 -389.467344)
					(end 129.36093 -389.467344)
				)
			)
		)
	)
	(zone
		(layer "In1.Cu")
		(hatch none 0.5)
		(connect_pads
			(clearance 0)
		)
		(min_thickness 0.25)
		(keepout
			(tracks not_allowed)
			(vias allowed)
			(pads allowed)
			(copperpour not_allowed)
			(footprints allowed)
		)
		(placement
			(enabled no)
			(sheetname "")
		)
		(fill
			(thermal_gap 0.5)
			(thermal_bridge_width 0.5)
			(island_removal_mode 0)
		)
		(polygon
			(pts
				(arc
					(start 184.365392 -225.632518)
					(mid 184.361672 -225.641498)
					(end 184.352692 -225.645218)
				)
				(arc
					(start 182.879492 -225.645218)
					(mid 182.870512 -225.641498)
					(end 182.866792 -225.632518)
				)
				(arc
					(start 182.866792 -225.13798)
					(mid 182.870512 -225.129)
					(end 182.879492 -225.12528)
				)
				(arc
					(start 184.352692 -225.12528)
					(mid 184.361672 -225.129)
					(end 184.365392 -225.13798)
				)
			)
		)
	)
	(zone
		(layer "In1.Cu")
		(hatch none 0.5)
		(connect_pads
			(clearance 0)
		)
		(min_thickness 0.25)
		(keepout
			(tracks not_allowed)
			(vias allowed)
			(pads allowed)
			(copperpour not_allowed)
			(footprints allowed)
		)
		(placement
			(enabled no)
			(sheetname "")
		)
		(fill
			(thermal_gap 0.5)
			(thermal_bridge_width 0.5)
			(island_removal_mode 0)
		)
		(polygon
			(pts
				(arc
					(start 431.061622 -11.91768)
					(mid 431.039304 -11.971562)
					(end 430.985422 -11.99388)
				)
				(arc
					(start 429.948848 -11.99388)
					(mid 429.894966 -11.971562)
					(end 429.872648 -11.91768)
				)
				(arc
					(start 429.872648 -10.51814)
					(mid 429.894966 -10.464258)
					(end 429.948848 -10.44194)
				)
				(arc
					(start 430.985422 -10.44194)
					(mid 431.039304 -10.464258)
					(end 431.061622 -10.51814)
				)
			)
		)
	)
	(zone
		(layer "In1.Cu")
		(hatch none 0.5)
		(connect_pads
			(clearance 0)
		)
		(min_thickness 0.25)
		(keepout
			(tracks not_allowed)
			(vias allowed)
			(pads allowed)
			(copperpour not_allowed)
			(footprints allowed)
		)
		(placement
			(enabled no)
			(sheetname "")
		)
		(fill
			(thermal_gap 0.5)
			(thermal_bridge_width 0.5)
			(island_removal_mode 0)
		)
		(polygon
			(pts
				(arc
					(start 33.445196 -267.282422)
					(mid 33.441476 -267.291402)
					(end 33.432496 -267.295122)
				)
				(arc
					(start 31.959296 -267.295122)
					(mid 31.950316 -267.291402)
					(end 31.946596 -267.282422)
				)
				(arc
					(start 31.946596 -266.787884)
					(mid 31.950316 -266.778904)
					(end 31.959296 -266.775184)
				)
				(arc
					(start 33.432496 -266.775184)
					(mid 33.441476 -266.778904)
					(end 33.445196 -266.787884)
				)
			)
		)
	)
	(zone
		(layer "In1.Cu")
		(hatch none 0.5)
		(connect_pads
			(clearance 0)
		)
		(min_thickness 0.25)
		(keepout
			(tracks not_allowed)
			(vias allowed)
			(pads allowed)
			(copperpour not_allowed)
			(footprints allowed)
		)
		(placement
			(enabled no)
			(sheetname "")
		)
		(fill
			(thermal_gap 0.5)
			(thermal_bridge_width 0.5)
			(island_removal_mode 0)
		)
		(polygon
			(pts
				(arc
					(start 353.441 -294.031162)
					(mid 353.1362 -294.335962)
					(end 353.441 -294.640762)
				)
				(arc
					(start 354.381054 -294.640762)
					(mid 354.685854 -294.335962)
					(end 354.381054 -294.031162)
				)
			)
		)
	)
	(zone
		(layer "In1.Cu")
		(hatch none 0.5)
		(connect_pads
			(clearance 0)
		)
		(min_thickness 0.25)
		(keepout
			(tracks not_allowed)
			(vias allowed)
			(pads allowed)
			(copperpour not_allowed)
			(footprints allowed)
		)
		(placement
			(enabled no)
			(sheetname "")
		)
		(fill
			(thermal_gap 0.5)
			(thermal_bridge_width 0.5)
			(island_removal_mode 0)
		)
		(polygon
			(pts
				(arc
					(start 270.397478 -217.982292)
					(mid 270.393758 -217.991272)
					(end 270.384778 -217.994992)
				)
				(arc
					(start 268.911578 -217.994992)
					(mid 268.902598 -217.991272)
					(end 268.898878 -217.982292)
				)
				(arc
					(start 268.898878 -217.487754)
					(mid 268.902598 -217.478774)
					(end 268.911578 -217.475054)
				)
				(arc
					(start 270.384778 -217.475054)
					(mid 270.393758 -217.478774)
					(end 270.397478 -217.487754)
				)
			)
		)
	)
	(zone
		(layer "In1.Cu")
		(hatch none 0.5)
		(connect_pads
			(clearance 0)
		)
		(min_thickness 0.25)
		(keepout
			(tracks not_allowed)
			(vias allowed)
			(pads allowed)
			(copperpour not_allowed)
			(footprints allowed)
		)
		(placement
			(enabled no)
			(sheetname "")
		)
		(fill
			(thermal_gap 0.5)
			(thermal_bridge_width 0.5)
			(island_removal_mode 0)
		)
		(polygon
			(pts
				(arc
					(start 169.277284 -242.632484)
					(mid 169.273564 -242.641464)
					(end 169.264584 -242.645184)
				)
				(arc
					(start 167.791384 -242.645184)
					(mid 167.782404 -242.641464)
					(end 167.778684 -242.632484)
				)
				(arc
					(start 167.778684 -242.137946)
					(mid 167.782404 -242.128966)
					(end 167.791384 -242.125246)
				)
				(arc
					(start 169.264584 -242.125246)
					(mid 169.273564 -242.128966)
					(end 169.277284 -242.137946)
				)
			)
		)
	)
	(zone
		(layer "In1.Cu")
		(hatch none 0.5)
		(connect_pads
			(clearance 0)
		)
		(min_thickness 0.25)
		(keepout
			(tracks not_allowed)
			(vias allowed)
			(pads allowed)
			(copperpour not_allowed)
			(footprints allowed)
		)
		(placement
			(enabled no)
			(sheetname "")
		)
		(fill
			(thermal_gap 0.5)
			(thermal_bridge_width 0.5)
			(island_removal_mode 0)
		)
		(polygon
			(pts
				(arc
					(start 341.518494 -399.701258)
					(mid 341.645494 -399.828258)
					(end 341.772494 -399.701258)
				)
				(arc
					(start 341.772494 -399.625058)
					(mid 341.645494 -399.498058)
					(end 341.518494 -399.625058)
				)
			)
		)
	)
	(zone
		(layer "In1.Cu")
		(hatch none 0.5)
		(connect_pads
			(clearance 0)
		)
		(min_thickness 0.25)
		(keepout
			(tracks not_allowed)
			(vias allowed)
			(pads allowed)
			(copperpour not_allowed)
			(footprints allowed)
		)
		(placement
			(enabled no)
			(sheetname "")
		)
		(fill
			(thermal_gap 0.5)
			(thermal_bridge_width 0.5)
			(island_removal_mode 0)
		)
		(polygon
			(pts
				(arc
					(start 184.365392 -300.43247)
					(mid 184.361672 -300.44145)
					(end 184.352692 -300.44517)
				)
				(arc
					(start 182.879492 -300.44517)
					(mid 182.870512 -300.44145)
					(end 182.866792 -300.43247)
				)
				(arc
					(start 182.866792 -299.937932)
					(mid 182.870512 -299.928952)
					(end 182.879492 -299.925232)
				)
				(arc
					(start 184.352692 -299.925232)
					(mid 184.361672 -299.928952)
					(end 184.365392 -299.937932)
				)
			)
		)
	)
	(zone
		(layer "In1.Cu")
		(hatch none 0.5)
		(connect_pads
			(clearance 0)
		)
		(min_thickness 0.25)
		(keepout
			(tracks not_allowed)
			(vias allowed)
			(pads allowed)
			(copperpour not_allowed)
			(footprints allowed)
		)
		(placement
			(enabled no)
			(sheetname "")
		)
		(fill
			(thermal_gap 0.5)
			(thermal_bridge_width 0.5)
			(island_removal_mode 0)
		)
		(polygon
			(pts
				(arc
					(start 60.191142 -383.440686)
					(mid 60.318142 -383.567686)
					(end 60.445142 -383.440686)
				)
				(arc
					(start 60.445142 -383.364486)
					(mid 60.318142 -383.237486)
					(end 60.191142 -383.364486)
				)
			)
		)
	)
	(zone
		(layer "In1.Cu")
		(hatch none 0.5)
		(connect_pads
			(clearance 0)
		)
		(min_thickness 0.25)
		(keepout
			(tracks not_allowed)
			(vias allowed)
			(pads allowed)
			(copperpour not_allowed)
			(footprints allowed)
		)
		(placement
			(enabled no)
			(sheetname "")
		)
		(fill
			(thermal_gap 0.5)
			(thermal_bridge_width 0.5)
			(island_removal_mode 0)
		)
		(polygon
			(pts
				(arc
					(start 191.909446 -210.332574)
					(mid 191.905726 -210.341554)
					(end 191.896746 -210.345274)
				)
				(arc
					(start 190.423546 -210.345274)
					(mid 190.414566 -210.341554)
					(end 190.410846 -210.332574)
				)
				(arc
					(start 190.410846 -209.838036)
					(mid 190.414566 -209.829056)
					(end 190.423546 -209.825336)
				)
				(arc
					(start 191.896746 -209.825336)
					(mid 191.905726 -209.829056)
					(end 191.909446 -209.838036)
				)
			)
		)
	)
	(zone
		(layer "In1.Cu")
		(hatch none 0.5)
		(connect_pads
			(clearance 0)
		)
		(min_thickness 0.25)
		(keepout
			(tracks not_allowed)
			(vias allowed)
			(pads allowed)
			(copperpour not_allowed)
			(footprints allowed)
		)
		(placement
			(enabled no)
			(sheetname "")
		)
		(fill
			(thermal_gap 0.5)
			(thermal_bridge_width 0.5)
			(island_removal_mode 0)
		)
		(polygon
			(pts
				(arc
					(start 296.473372 -295.33215)
					(mid 296.469652 -295.34113)
					(end 296.460672 -295.34485)
				)
				(arc
					(start 294.987472 -295.34485)
					(mid 294.978492 -295.34113)
					(end 294.974772 -295.33215)
				)
				(arc
					(start 294.974772 -294.837612)
					(mid 294.978492 -294.828632)
					(end 294.987472 -294.824912)
				)
				(arc
					(start 296.460672 -294.824912)
					(mid 296.469652 -294.828632)
					(end 296.473372 -294.837612)
				)
			)
		)
	)
	(zone
		(layer "In1.Cu")
		(hatch none 0.5)
		(connect_pads
			(clearance 0)
		)
		(min_thickness 0.25)
		(keepout
			(tracks not_allowed)
			(vias allowed)
			(pads allowed)
			(copperpour not_allowed)
			(footprints allowed)
		)
		(placement
			(enabled no)
			(sheetname "")
		)
		(fill
			(thermal_gap 0.5)
			(thermal_bridge_width 0.5)
			(island_removal_mode 0)
		)
		(polygon
			(pts
				(arc
					(start 52.633372 -268.13256)
					(mid 52.629652 -268.14154)
					(end 52.620672 -268.14526)
				)
				(arc
					(start 51.147472 -268.14526)
					(mid 51.138492 -268.14154)
					(end 51.134772 -268.13256)
				)
				(arc
					(start 51.134772 -267.638022)
					(mid 51.138492 -267.629042)
					(end 51.147472 -267.625322)
				)
				(arc
					(start 52.620672 -267.625322)
					(mid 52.629652 -267.629042)
					(end 52.633372 -267.638022)
				)
			)
		)
	)
	(zone
		(layer "In1.Cu")
		(hatch none 0.5)
		(connect_pads
			(clearance 0)
		)
		(min_thickness 0.25)
		(keepout
			(tracks not_allowed)
			(vias allowed)
			(pads allowed)
			(copperpour not_allowed)
			(footprints allowed)
		)
		(placement
			(enabled no)
			(sheetname "")
		)
		(fill
			(thermal_gap 0.5)
			(thermal_bridge_width 0.5)
			(island_removal_mode 0)
		)
		(polygon
			(pts
				(arc
					(start 25.901396 -302.982376)
					(mid 25.897676 -302.991356)
					(end 25.888696 -302.995076)
				)
				(arc
					(start 24.415496 -302.995076)
					(mid 24.406516 -302.991356)
					(end 24.402796 -302.982376)
				)
				(arc
					(start 24.402796 -302.487838)
					(mid 24.406516 -302.478858)
					(end 24.415496 -302.475138)
				)
				(arc
					(start 25.888696 -302.475138)
					(mid 25.897676 -302.478858)
					(end 25.901396 -302.487838)
				)
			)
		)
	)
	(zone
		(layer "In1.Cu")
		(hatch none 0.5)
		(connect_pads
			(clearance 0)
		)
		(min_thickness 0.25)
		(keepout
			(tracks not_allowed)
			(vias allowed)
			(pads allowed)
			(copperpour not_allowed)
			(footprints allowed)
		)
		(placement
			(enabled no)
			(sheetname "")
		)
		(fill
			(thermal_gap 0.5)
			(thermal_bridge_width 0.5)
			(island_removal_mode 0)
		)
		(polygon
			(pts
				(arc
					(start 187.809378 -318.282574)
					(mid 187.805658 -318.291554)
					(end 187.796678 -318.295274)
				)
				(arc
					(start 186.323478 -318.295274)
					(mid 186.314498 -318.291554)
					(end 186.310778 -318.282574)
				)
				(arc
					(start 186.310778 -317.788036)
					(mid 186.314498 -317.779056)
					(end 186.323478 -317.775336)
				)
				(arc
					(start 187.796678 -317.775336)
					(mid 187.805658 -317.779056)
					(end 187.809378 -317.788036)
				)
			)
		)
	)
	(zone
		(layer "In1.Cu")
		(hatch none 0.5)
		(connect_pads
			(clearance 0)
		)
		(min_thickness 0.25)
		(keepout
			(tracks not_allowed)
			(vias allowed)
			(pads allowed)
			(copperpour not_allowed)
			(footprints allowed)
		)
		(placement
			(enabled no)
			(sheetname "")
		)
		(fill
			(thermal_gap 0.5)
			(thermal_bridge_width 0.5)
			(island_removal_mode 0)
		)
		(polygon
			(pts
				(arc
					(start 195.353432 -200.132442)
					(mid 195.349712 -200.141422)
					(end 195.340732 -200.145142)
				)
				(arc
					(start 193.867532 -200.145142)
					(mid 193.858552 -200.141422)
					(end 193.854832 -200.132442)
				)
				(arc
					(start 193.854832 -199.637904)
					(mid 193.858552 -199.628924)
					(end 193.867532 -199.625204)
				)
				(arc
					(start 195.340732 -199.625204)
					(mid 195.349712 -199.628924)
					(end 195.353432 -199.637904)
				)
			)
		)
	)
	(zone
		(layer "In1.Cu")
		(hatch none 0.5)
		(connect_pads
			(clearance 0)
		)
		(min_thickness 0.25)
		(keepout
			(tracks not_allowed)
			(vias allowed)
			(pads allowed)
			(copperpour not_allowed)
			(footprints allowed)
		)
		(placement
			(enabled no)
			(sheetname "")
		)
		(fill
			(thermal_gap 0.5)
			(thermal_bridge_width 0.5)
			(island_removal_mode 0)
		)
		(polygon
			(pts
				(arc
					(start 300.189392 4.531614)
					(mid 300.167074 4.477732)
					(end 300.113192 4.455414)
				)
				(arc
					(start 299.501052 4.455414)
					(mid 299.44717 4.477732)
					(end 299.424852 4.531614)
				)
				(arc
					(start 299.424852 5.628894)
					(mid 299.44717 5.682776)
					(end 299.501052 5.705094)
				)
				(arc
					(start 300.113192 5.705094)
					(mid 300.167074 5.682776)
					(end 300.189392 5.628894)
				)
			)
		)
	)
	(zone
		(layer "In1.Cu")
		(hatch none 0.5)
		(connect_pads
			(clearance 0)
		)
		(min_thickness 0.25)
		(keepout
			(tracks not_allowed)
			(vias allowed)
			(pads allowed)
			(copperpour not_allowed)
			(footprints allowed)
		)
		(placement
			(enabled no)
			(sheetname "")
		)
		(fill
			(thermal_gap 0.5)
			(thermal_bridge_width 0.5)
			(island_removal_mode 0)
		)
		(polygon
			(pts
				(arc
					(start 379.070362 -392.30427)
					(mid 378.765562 -392.30427)
					(end 379.070362 -392.30427)
				)
			)
		)
	)
	(zone
		(layer "In1.Cu")
		(hatch none 0.5)
		(connect_pads
			(clearance 0)
		)
		(min_thickness 0.25)
		(keepout
			(tracks not_allowed)
			(vias allowed)
			(pads allowed)
			(copperpour not_allowed)
			(footprints allowed)
		)
		(placement
			(enabled no)
			(sheetname "")
		)
		(fill
			(thermal_gap 0.5)
			(thermal_bridge_width 0.5)
			(island_removal_mode 0)
		)
		(polygon
			(pts
				(arc
					(start 55.39105 -383.440686)
					(mid 55.51805 -383.567686)
					(end 55.64505 -383.440686)
				)
				(arc
					(start 55.64505 -383.364486)
					(mid 55.51805 -383.237486)
					(end 55.39105 -383.364486)
				)
			)
		)
	)
	(zone
		(layer "In1.Cu")
		(hatch none 0.5)
		(connect_pads
			(clearance 0)
		)
		(min_thickness 0.25)
		(keepout
			(tracks not_allowed)
			(vias allowed)
			(pads allowed)
			(copperpour not_allowed)
			(footprints allowed)
		)
		(placement
			(enabled no)
			(sheetname "")
		)
		(fill
			(thermal_gap 0.5)
			(thermal_bridge_width 0.5)
			(island_removal_mode 0)
		)
		(polygon
			(pts
				(arc
					(start 432.30546 -268.132306)
					(mid 432.30174 -268.141286)
					(end 432.29276 -268.145006)
				)
				(arc
					(start 430.81956 -268.145006)
					(mid 430.81058 -268.141286)
					(end 430.80686 -268.132306)
				)
				(arc
					(start 430.80686 -267.637768)
					(mid 430.81058 -267.628788)
					(end 430.81956 -267.625068)
				)
				(arc
					(start 432.29276 -267.625068)
					(mid 432.30174 -267.628788)
					(end 432.30546 -267.637768)
				)
			)
		)
	)
	(zone
		(layer "In1.Cu")
		(hatch none 0.5)
		(connect_pads
			(clearance 0)
		)
		(min_thickness 0.25)
		(keepout
			(tracks not_allowed)
			(vias allowed)
			(pads allowed)
			(copperpour not_allowed)
			(footprints allowed)
		)
		(placement
			(enabled no)
			(sheetname "")
		)
		(fill
			(thermal_gap 0.5)
			(thermal_bridge_width 0.5)
			(island_removal_mode 0)
		)
		(polygon
			(pts
				(arc
					(start 300.57344 -242.63223)
					(mid 300.56972 -242.64121)
					(end 300.56074 -242.64493)
				)
				(arc
					(start 299.08754 -242.64493)
					(mid 299.07856 -242.64121)
					(end 299.07484 -242.63223)
				)
				(arc
					(start 299.07484 -242.137692)
					(mid 299.07856 -242.128712)
					(end 299.08754 -242.124992)
				)
				(arc
					(start 300.56074 -242.124992)
					(mid 300.56972 -242.128712)
					(end 300.57344 -242.137692)
				)
			)
		)
	)
	(zone
		(layer "In1.Cu")
		(hatch none 0.5)
		(connect_pads
			(clearance 0)
		)
		(min_thickness 0.25)
		(keepout
			(tracks not_allowed)
			(vias allowed)
			(pads allowed)
			(copperpour not_allowed)
			(footprints allowed)
		)
		(placement
			(enabled no)
			(sheetname "")
		)
		(fill
			(thermal_gap 0.5)
			(thermal_bridge_width 0.5)
			(island_removal_mode 0)
		)
		(polygon
			(pts
				(arc
					(start 33.445196 -262.182356)
					(mid 33.441476 -262.191336)
					(end 33.432496 -262.195056)
				)
				(arc
					(start 31.959296 -262.195056)
					(mid 31.950316 -262.191336)
					(end 31.946596 -262.182356)
				)
				(arc
					(start 31.946596 -261.687818)
					(mid 31.950316 -261.678838)
					(end 31.959296 -261.675118)
				)
				(arc
					(start 33.432496 -261.675118)
					(mid 33.441476 -261.678838)
					(end 33.445196 -261.687818)
				)
			)
		)
	)
	(zone
		(layer "In1.Cu")
		(hatch none 0.5)
		(connect_pads
			(clearance 0)
		)
		(min_thickness 0.25)
		(keepout
			(tracks not_allowed)
			(vias allowed)
			(pads allowed)
			(copperpour not_allowed)
			(footprints allowed)
		)
		(placement
			(enabled no)
			(sheetname "")
		)
		(fill
			(thermal_gap 0.5)
			(thermal_bridge_width 0.5)
			(island_removal_mode 0)
		)
		(polygon
			(pts
				(arc
					(start 60.661296 -388.774432)
					(mid 60.280296 -388.774432)
					(end 60.661296 -388.774432)
				)
			)
		)
	)
	(zone
		(layer "In1.Cu")
		(hatch none 0.5)
		(connect_pads
			(clearance 0)
		)
		(min_thickness 0.25)
		(keepout
			(tracks not_allowed)
			(vias allowed)
			(pads allowed)
			(copperpour not_allowed)
			(footprints allowed)
		)
		(placement
			(enabled no)
			(sheetname "")
		)
		(fill
			(thermal_gap 0.5)
			(thermal_bridge_width 0.5)
			(island_removal_mode 0)
		)
		(polygon
			(pts
				(arc
					(start 447.393568 -268.132306)
					(mid 447.389848 -268.141286)
					(end 447.380868 -268.145006)
				)
				(arc
					(start 445.907668 -268.145006)
					(mid 445.898688 -268.141286)
					(end 445.894968 -268.132306)
				)
				(arc
					(start 445.894968 -267.637768)
					(mid 445.898688 -267.628788)
					(end 445.907668 -267.625068)
				)
				(arc
					(start 447.380868 -267.625068)
					(mid 447.389848 -267.628788)
					(end 447.393568 -267.637768)
				)
			)
		)
	)
	(zone
		(layer "In1.Cu")
		(hatch none 0.5)
		(connect_pads
			(clearance 0)
		)
		(min_thickness 0.25)
		(keepout
			(tracks not_allowed)
			(vias allowed)
			(pads allowed)
			(copperpour not_allowed)
			(footprints allowed)
		)
		(placement
			(enabled no)
			(sheetname "")
		)
		(fill
			(thermal_gap 0.5)
			(thermal_bridge_width 0.5)
			(island_removal_mode 0)
		)
		(polygon
			(pts
				(arc
					(start 266.29741 -305.532282)
					(mid 266.29369 -305.541262)
					(end 266.28471 -305.544982)
				)
				(arc
					(start 264.81151 -305.544982)
					(mid 264.80253 -305.541262)
					(end 264.79881 -305.532282)
				)
				(arc
					(start 264.79881 -305.037744)
					(mid 264.80253 -305.028764)
					(end 264.81151 -305.025044)
				)
				(arc
					(start 266.28471 -305.025044)
					(mid 266.29369 -305.028764)
					(end 266.29741 -305.037744)
				)
			)
		)
	)
	(zone
		(layer "In1.Cu")
		(hatch none 0.5)
		(connect_pads
			(clearance 0)
		)
		(min_thickness 0.25)
		(keepout
			(tracks not_allowed)
			(vias allowed)
			(pads allowed)
			(copperpour not_allowed)
			(footprints allowed)
		)
		(placement
			(enabled no)
			(sheetname "")
		)
		(fill
			(thermal_gap 0.5)
			(thermal_bridge_width 0.5)
			(island_removal_mode 0)
		)
		(polygon
			(pts
				(arc
					(start 380.891034 -391.822686)
					(mid 381.018034 -391.949686)
					(end 381.145034 -391.822686)
				)
				(arc
					(start 381.145034 -391.746486)
					(mid 381.018034 -391.619486)
					(end 380.891034 -391.746486)
				)
			)
		)
	)
	(zone
		(layer "In1.Cu")
		(hatch none 0.5)
		(connect_pads
			(clearance 0)
		)
		(min_thickness 0.25)
		(keepout
			(tracks not_allowed)
			(vias allowed)
			(pads allowed)
			(copperpour not_allowed)
			(footprints allowed)
		)
		(placement
			(enabled no)
			(sheetname "")
		)
		(fill
			(thermal_gap 0.5)
			(thermal_bridge_width 0.5)
			(island_removal_mode 0)
		)
		(polygon
			(pts
				(arc
					(start 273.841464 -221.382082)
					(mid 273.837744 -221.391062)
					(end 273.828764 -221.394782)
				)
				(arc
					(start 272.355564 -221.394782)
					(mid 272.346584 -221.391062)
					(end 272.342864 -221.382082)
				)
				(arc
					(start 272.342864 -220.887544)
					(mid 272.346584 -220.878564)
					(end 272.355564 -220.874844)
				)
				(arc
					(start 273.828764 -220.874844)
					(mid 273.837744 -220.878564)
					(end 273.841464 -220.887544)
				)
			)
		)
	)
	(zone
		(layer "In1.Cu")
		(hatch none 0.5)
		(connect_pads
			(clearance 0)
		)
		(min_thickness 0.25)
		(keepout
			(tracks not_allowed)
			(vias allowed)
			(pads allowed)
			(copperpour not_allowed)
			(footprints allowed)
		)
		(placement
			(enabled no)
			(sheetname "")
		)
		(fill
			(thermal_gap 0.5)
			(thermal_bridge_width 0.5)
			(island_removal_mode 0)
		)
		(polygon
			(pts
				(arc
					(start 161.598102 -390.761474)
					(mid 161.293302 -390.761474)
					(end 161.598102 -390.761474)
				)
			)
		)
	)
	(zone
		(layer "In1.Cu")
		(hatch none 0.5)
		(connect_pads
			(clearance 0)
		)
		(min_thickness 0.25)
		(keepout
			(tracks not_allowed)
			(vias allowed)
			(pads allowed)
			(copperpour not_allowed)
			(footprints allowed)
		)
		(placement
			(enabled no)
			(sheetname "")
		)
		(fill
			(thermal_gap 0.5)
			(thermal_bridge_width 0.5)
			(island_removal_mode 0)
		)
		(polygon
			(pts
				(arc
					(start 270.397478 -278.332184)
					(mid 270.393758 -278.341164)
					(end 270.384778 -278.344884)
				)
				(arc
					(start 268.911578 -278.344884)
					(mid 268.902598 -278.341164)
					(end 268.898878 -278.332184)
				)
				(arc
					(start 268.898878 -277.837646)
					(mid 268.902598 -277.828666)
					(end 268.911578 -277.824946)
				)
				(arc
					(start 270.384778 -277.824946)
					(mid 270.393758 -277.828666)
					(end 270.397478 -277.837646)
				)
			)
		)
	)
	(zone
		(layer "In1.Cu")
		(hatch none 0.5)
		(connect_pads
			(clearance 0)
		)
		(min_thickness 0.25)
		(keepout
			(tracks not_allowed)
			(vias allowed)
			(pads allowed)
			(copperpour not_allowed)
			(footprints allowed)
		)
		(placement
			(enabled no)
			(sheetname "")
		)
		(fill
			(thermal_gap 0.5)
			(thermal_bridge_width 0.5)
			(island_removal_mode 0)
		)
		(polygon
			(pts
				(arc
					(start 420.661338 -279.182322)
					(mid 420.657618 -279.191302)
					(end 420.648638 -279.195022)
				)
				(arc
					(start 419.175438 -279.195022)
					(mid 419.166458 -279.191302)
					(end 419.162738 -279.182322)
				)
				(arc
					(start 419.162738 -278.687784)
					(mid 419.166458 -278.678804)
					(end 419.175438 -278.675084)
				)
				(arc
					(start 420.648638 -278.675084)
					(mid 420.657618 -278.678804)
					(end 420.661338 -278.687784)
				)
			)
		)
	)
	(zone
		(layer "In1.Cu")
		(hatch none 0.5)
		(connect_pads
			(clearance 0)
		)
		(min_thickness 0.25)
		(keepout
			(tracks not_allowed)
			(vias allowed)
			(pads allowed)
			(copperpour not_allowed)
			(footprints allowed)
		)
		(placement
			(enabled no)
			(sheetname "")
		)
		(fill
			(thermal_gap 0.5)
			(thermal_bridge_width 0.5)
			(island_removal_mode 0)
		)
		(polygon
			(pts
				(arc
					(start 45.089318 -205.232508)
					(mid 45.085598 -205.241488)
					(end 45.076618 -205.245208)
				)
				(arc
					(start 43.603418 -205.245208)
					(mid 43.594438 -205.241488)
					(end 43.590718 -205.232508)
				)
				(arc
					(start 43.590718 -204.73797)
					(mid 43.594438 -204.72899)
					(end 43.603418 -204.72527)
				)
				(arc
					(start 45.076618 -204.72527)
					(mid 45.085598 -204.72899)
					(end 45.089318 -204.73797)
				)
			)
		)
	)
	(zone
		(layer "In1.Cu")
		(hatch none 0.5)
		(connect_pads
			(clearance 0)
		)
		(min_thickness 0.25)
		(keepout
			(tracks not_allowed)
			(vias allowed)
			(pads allowed)
			(copperpour not_allowed)
			(footprints allowed)
		)
		(placement
			(enabled no)
			(sheetname "")
		)
		(fill
			(thermal_gap 0.5)
			(thermal_bridge_width 0.5)
			(island_removal_mode 0)
		)
		(polygon
			(pts
				(arc
					(start 420.661338 -268.98219)
					(mid 420.657618 -268.99117)
					(end 420.648638 -268.99489)
				)
				(arc
					(start 419.175438 -268.99489)
					(mid 419.166458 -268.99117)
					(end 419.162738 -268.98219)
				)
				(arc
					(start 419.162738 -268.487652)
					(mid 419.166458 -268.478672)
					(end 419.175438 -268.474952)
				)
				(arc
					(start 420.648638 -268.474952)
					(mid 420.657618 -268.478672)
					(end 420.661338 -268.487652)
				)
			)
		)
	)
	(zone
		(layer "In1.Cu")
		(hatch none 0.5)
		(connect_pads
			(clearance 0)
		)
		(min_thickness 0.25)
		(keepout
			(tracks not_allowed)
			(vias allowed)
			(pads allowed)
			(copperpour not_allowed)
			(footprints allowed)
		)
		(placement
			(enabled no)
			(sheetname "")
		)
		(fill
			(thermal_gap 0.5)
			(thermal_bridge_width 0.5)
			(island_removal_mode 0)
		)
		(polygon
			(pts
				(arc
					(start 417.217352 -283.43225)
					(mid 417.213632 -283.44123)
					(end 417.204652 -283.44495)
				)
				(arc
					(start 415.731452 -283.44495)
					(mid 415.722472 -283.44123)
					(end 415.718752 -283.43225)
				)
				(arc
					(start 415.718752 -282.937712)
					(mid 415.722472 -282.928732)
					(end 415.731452 -282.925012)
				)
				(arc
					(start 417.204652 -282.925012)
					(mid 417.213632 -282.928732)
					(end 417.217352 -282.937712)
				)
			)
		)
	)
	(zone
		(layer "In1.Cu")
		(hatch none 0.5)
		(connect_pads
			(clearance 0)
		)
		(min_thickness 0.25)
		(keepout
			(tracks not_allowed)
			(vias allowed)
			(pads allowed)
			(copperpour not_allowed)
			(footprints allowed)
		)
		(placement
			(enabled no)
			(sheetname "")
		)
		(fill
			(thermal_gap 0.5)
			(thermal_bridge_width 0.5)
			(island_removal_mode 0)
		)
		(polygon
			(pts
				(arc
					(start 308.117494 -222.23222)
					(mid 308.113774 -222.2412)
					(end 308.104794 -222.24492)
				)
				(arc
					(start 306.631594 -222.24492)
					(mid 306.622614 -222.2412)
					(end 306.618894 -222.23222)
				)
				(arc
					(start 306.618894 -221.737682)
					(mid 306.622614 -221.728702)
					(end 306.631594 -221.724982)
				)
				(arc
					(start 308.104794 -221.724982)
					(mid 308.113774 -221.728702)
					(end 308.117494 -221.737682)
				)
			)
		)
	)
	(zone
		(layer "In1.Cu")
		(hatch none 0.5)
		(connect_pads
			(clearance 0)
		)
		(min_thickness 0.25)
		(keepout
			(tracks not_allowed)
			(vias allowed)
			(pads allowed)
			(copperpour not_allowed)
			(footprints allowed)
		)
		(placement
			(enabled no)
			(sheetname "")
		)
		(fill
			(thermal_gap 0.5)
			(thermal_bridge_width 0.5)
			(island_removal_mode 0)
		)
		(polygon
			(pts
				(arc
					(start 184.365392 -291.082476)
					(mid 184.361672 -291.091456)
					(end 184.352692 -291.095176)
				)
				(arc
					(start 182.879492 -291.095176)
					(mid 182.870512 -291.091456)
					(end 182.866792 -291.082476)
				)
				(arc
					(start 182.866792 -290.587938)
					(mid 182.870512 -290.578958)
					(end 182.879492 -290.575238)
				)
				(arc
					(start 184.352692 -290.575238)
					(mid 184.361672 -290.578958)
					(end 184.365392 -290.587938)
				)
			)
		)
	)
	(zone
		(layer "In1.Cu")
		(hatch none 0.5)
		(connect_pads
			(clearance 0)
		)
		(min_thickness 0.25)
		(keepout
			(tracks not_allowed)
			(vias allowed)
			(pads allowed)
			(copperpour not_allowed)
			(footprints allowed)
		)
		(placement
			(enabled no)
			(sheetname "")
		)
		(fill
			(thermal_gap 0.5)
			(thermal_bridge_width 0.5)
			(island_removal_mode 0)
		)
		(polygon
			(pts
				(arc
					(start 119.761 -386.003292)
					(mid 119.38 -386.003292)
					(end 119.761 -386.003292)
				)
			)
		)
	)
	(zone
		(layer "In1.Cu")
		(hatch none 0.5)
		(connect_pads
			(clearance 0)
		)
		(min_thickness 0.25)
		(keepout
			(tracks not_allowed)
			(vias allowed)
			(pads allowed)
			(copperpour not_allowed)
			(footprints allowed)
		)
		(placement
			(enabled no)
			(sheetname "")
		)
		(fill
			(thermal_gap 0.5)
			(thermal_bridge_width 0.5)
			(island_removal_mode 0)
		)
		(polygon
			(pts
				(arc
					(start 79.518764 -383.440686)
					(mid 79.645764 -383.567686)
					(end 79.772764 -383.440686)
				)
				(arc
					(start 79.772764 -383.364486)
					(mid 79.645764 -383.237486)
					(end 79.518764 -383.364486)
				)
			)
		)
	)
	(zone
		(layer "In1.Cu")
		(hatch none 0.5)
		(connect_pads
			(clearance 0)
		)
		(min_thickness 0.25)
		(keepout
			(tracks not_allowed)
			(vias allowed)
			(pads allowed)
			(copperpour not_allowed)
			(footprints allowed)
		)
		(placement
			(enabled no)
			(sheetname "")
		)
		(fill
			(thermal_gap 0.5)
			(thermal_bridge_width 0.5)
			(island_removal_mode 0)
		)
		(polygon
			(pts
				(arc
					(start 206.5782 -279.785318)
					(mid 205.9178 -279.785318)
					(end 206.5782 -279.785318)
				)
			)
		)
	)
	(zone
		(layer "In1.Cu")
		(hatch none 0.5)
		(connect_pads
			(clearance 0)
		)
		(min_thickness 0.25)
		(keepout
			(tracks not_allowed)
			(vias allowed)
			(pads allowed)
			(copperpour not_allowed)
			(footprints allowed)
		)
		(placement
			(enabled no)
			(sheetname "")
		)
		(fill
			(thermal_gap 0.5)
			(thermal_bridge_width 0.5)
			(island_removal_mode 0)
		)
		(polygon
			(pts
				(arc
					(start 180.265324 -297.882564)
					(mid 180.261604 -297.891544)
					(end 180.252624 -297.895264)
				)
				(arc
					(start 178.779424 -297.895264)
					(mid 178.770444 -297.891544)
					(end 178.766724 -297.882564)
				)
				(arc
					(start 178.766724 -297.388026)
					(mid 178.770444 -297.379046)
					(end 178.779424 -297.375326)
				)
				(arc
					(start 180.252624 -297.375326)
					(mid 180.261604 -297.379046)
					(end 180.265324 -297.388026)
				)
			)
		)
	)
	(zone
		(layer "In1.Cu")
		(hatch none 0.5)
		(connect_pads
			(clearance 0)
		)
		(min_thickness 0.25)
		(keepout
			(tracks not_allowed)
			(vias allowed)
			(pads allowed)
			(copperpour not_allowed)
			(footprints allowed)
		)
		(placement
			(enabled no)
			(sheetname "")
		)
		(fill
			(thermal_gap 0.5)
			(thermal_bridge_width 0.5)
			(island_removal_mode 0)
		)
		(polygon
			(pts
				(arc
					(start 338.388706 -393.69238)
					(mid 338.007706 -393.69238)
					(end 338.388706 -393.69238)
				)
			)
		)
	)
	(zone
		(layer "In1.Cu")
		(hatch none 0.5)
		(connect_pads
			(clearance 0)
		)
		(min_thickness 0.25)
		(keepout
			(tracks not_allowed)
			(vias allowed)
			(pads allowed)
			(copperpour not_allowed)
			(footprints allowed)
		)
		(placement
			(enabled no)
			(sheetname "")
		)
		(fill
			(thermal_gap 0.5)
			(thermal_bridge_width 0.5)
			(island_removal_mode 0)
		)
		(polygon
			(pts
				(arc
					(start 184.365392 -246.032528)
					(mid 184.361672 -246.041508)
					(end 184.352692 -246.045228)
				)
				(arc
					(start 182.879492 -246.045228)
					(mid 182.870512 -246.041508)
					(end 182.866792 -246.032528)
				)
				(arc
					(start 182.866792 -245.53799)
					(mid 182.870512 -245.52901)
					(end 182.879492 -245.52529)
				)
				(arc
					(start 184.352692 -245.52529)
					(mid 184.361672 -245.52901)
					(end 184.365392 -245.53799)
				)
			)
		)
	)
	(zone
		(layer "In1.Cu")
		(hatch none 0.5)
		(connect_pads
			(clearance 0)
		)
		(min_thickness 0.25)
		(keepout
			(tracks not_allowed)
			(vias allowed)
			(pads allowed)
			(copperpour not_allowed)
			(footprints allowed)
		)
		(placement
			(enabled no)
			(sheetname "")
		)
		(fill
			(thermal_gap 0.5)
			(thermal_bridge_width 0.5)
			(island_removal_mode 0)
		)
		(polygon
			(pts
				(arc
					(start 308.117494 -246.032274)
					(mid 308.113774 -246.041254)
					(end 308.104794 -246.044974)
				)
				(arc
					(start 306.631594 -246.044974)
					(mid 306.622614 -246.041254)
					(end 306.618894 -246.032274)
				)
				(arc
					(start 306.618894 -245.537736)
					(mid 306.622614 -245.528756)
					(end 306.631594 -245.525036)
				)
				(arc
					(start 308.104794 -245.525036)
					(mid 308.113774 -245.528756)
					(end 308.117494 -245.537736)
				)
			)
		)
	)
	(zone
		(layer "In1.Cu")
		(hatch none 0.5)
		(connect_pads
			(clearance 0)
		)
		(min_thickness 0.25)
		(keepout
			(tracks not_allowed)
			(vias allowed)
			(pads allowed)
			(copperpour not_allowed)
			(footprints allowed)
		)
		(placement
			(enabled no)
			(sheetname "")
		)
		(fill
			(thermal_gap 0.5)
			(thermal_bridge_width 0.5)
			(island_removal_mode 0)
		)
		(polygon
			(pts
				(arc
					(start 288.929318 -241.782092)
					(mid 288.925598 -241.791072)
					(end 288.916618 -241.794792)
				)
				(arc
					(start 287.443418 -241.794792)
					(mid 287.434438 -241.791072)
					(end 287.430718 -241.782092)
				)
				(arc
					(start 287.430718 -241.287554)
					(mid 287.434438 -241.278574)
					(end 287.443418 -241.274854)
				)
				(arc
					(start 288.916618 -241.274854)
					(mid 288.925598 -241.278574)
					(end 288.929318 -241.287554)
				)
			)
		)
	)
	(zone
		(layer "In1.Cu")
		(hatch none 0.5)
		(connect_pads
			(clearance 0)
		)
		(min_thickness 0.25)
		(keepout
			(tracks not_allowed)
			(vias allowed)
			(pads allowed)
			(copperpour not_allowed)
			(footprints allowed)
		)
		(placement
			(enabled no)
			(sheetname "")
		)
		(fill
			(thermal_gap 0.5)
			(thermal_bridge_width 0.5)
			(island_removal_mode 0)
		)
		(polygon
			(pts
				(arc
					(start 33.445196 -221.382336)
					(mid 33.441476 -221.391316)
					(end 33.432496 -221.395036)
				)
				(arc
					(start 31.959296 -221.395036)
					(mid 31.950316 -221.391316)
					(end 31.946596 -221.382336)
				)
				(arc
					(start 31.946596 -220.887798)
					(mid 31.950316 -220.878818)
					(end 31.959296 -220.875098)
				)
				(arc
					(start 33.432496 -220.875098)
					(mid 33.441476 -220.878818)
					(end 33.445196 -220.887798)
				)
			)
		)
	)
	(zone
		(layer "In1.Cu")
		(hatch none 0.5)
		(connect_pads
			(clearance 0)
		)
		(min_thickness 0.25)
		(keepout
			(tracks not_allowed)
			(vias allowed)
			(pads allowed)
			(copperpour not_allowed)
			(footprints allowed)
		)
		(placement
			(enabled no)
			(sheetname "")
		)
		(fill
			(thermal_gap 0.5)
			(thermal_bridge_width 0.5)
			(island_removal_mode 0)
		)
		(polygon
			(pts
				(arc
					(start 119.361204 -388.774432)
					(mid 118.980204 -388.774432)
					(end 119.361204 -388.774432)
				)
			)
		)
	)
	(zone
		(layer "In1.Cu")
		(hatch none 0.5)
		(connect_pads
			(clearance 0)
		)
		(min_thickness 0.25)
		(keepout
			(tracks not_allowed)
			(vias allowed)
			(pads allowed)
			(copperpour not_allowed)
			(footprints allowed)
		)
		(placement
			(enabled no)
			(sheetname "")
		)
		(fill
			(thermal_gap 0.5)
			(thermal_bridge_width 0.5)
			(island_removal_mode 0)
		)
		(polygon
			(pts
				(arc
					(start 413.117284 -245.182136)
					(mid 413.113564 -245.191116)
					(end 413.104584 -245.194836)
				)
				(arc
					(start 411.631384 -245.194836)
					(mid 411.622404 -245.191116)
					(end 411.618684 -245.182136)
				)
				(arc
					(start 411.618684 -244.687598)
					(mid 411.622404 -244.678618)
					(end 411.631384 -244.674898)
				)
				(arc
					(start 413.104584 -244.674898)
					(mid 413.113564 -244.678618)
					(end 413.117284 -244.687598)
				)
			)
		)
	)
	(zone
		(layer "In1.Cu")
		(hatch none 0.5)
		(connect_pads
			(clearance 0)
		)
		(min_thickness 0.25)
		(keepout
			(tracks not_allowed)
			(vias allowed)
			(pads allowed)
			(copperpour not_allowed)
			(footprints allowed)
		)
		(placement
			(enabled no)
			(sheetname "")
		)
		(fill
			(thermal_gap 0.5)
			(thermal_bridge_width 0.5)
			(island_removal_mode 0)
		)
		(polygon
			(pts
				(arc
					(start 273.841464 -286.832294)
					(mid 273.837744 -286.841274)
					(end 273.828764 -286.844994)
				)
				(arc
					(start 272.355564 -286.844994)
					(mid 272.346584 -286.841274)
					(end 272.342864 -286.832294)
				)
				(arc
					(start 272.342864 -286.337756)
					(mid 272.346584 -286.328776)
					(end 272.355564 -286.325056)
				)
				(arc
					(start 273.828764 -286.325056)
					(mid 273.837744 -286.328776)
					(end 273.841464 -286.337756)
				)
			)
		)
	)
	(zone
		(layer "In1.Cu")
		(hatch none 0.5)
		(connect_pads
			(clearance 0)
		)
		(min_thickness 0.25)
		(keepout
			(tracks not_allowed)
			(vias allowed)
			(pads allowed)
			(copperpour not_allowed)
			(footprints allowed)
		)
		(placement
			(enabled no)
			(sheetname "")
		)
		(fill
			(thermal_gap 0.5)
			(thermal_bridge_width 0.5)
			(island_removal_mode 0)
		)
		(polygon
			(pts
				(arc
					(start 165.177216 -253.6825)
					(mid 165.173496 -253.69148)
					(end 165.164516 -253.6952)
				)
				(arc
					(start 163.691316 -253.6952)
					(mid 163.682336 -253.69148)
					(end 163.678616 -253.6825)
				)
				(arc
					(start 163.678616 -253.187962)
					(mid 163.682336 -253.178982)
					(end 163.691316 -253.175262)
				)
				(arc
					(start 165.164516 -253.175262)
					(mid 165.173496 -253.178982)
					(end 165.177216 -253.187962)
				)
			)
		)
	)
	(zone
		(layer "In1.Cu")
		(hatch none 0.5)
		(connect_pads
			(clearance 0)
		)
		(min_thickness 0.25)
		(keepout
			(tracks not_allowed)
			(vias allowed)
			(pads allowed)
			(copperpour not_allowed)
			(footprints allowed)
		)
		(placement
			(enabled no)
			(sheetname "")
		)
		(fill
			(thermal_gap 0.5)
			(thermal_bridge_width 0.5)
			(island_removal_mode 0)
		)
		(polygon
			(pts
				(arc
					(start 165.177216 -304.682398)
					(mid 165.173496 -304.691378)
					(end 165.164516 -304.695098)
				)
				(arc
					(start 163.691316 -304.695098)
					(mid 163.682336 -304.691378)
					(end 163.678616 -304.682398)
				)
				(arc
					(start 163.678616 -304.18786)
					(mid 163.682336 -304.17888)
					(end 163.691316 -304.17516)
				)
				(arc
					(start 165.164516 -304.17516)
					(mid 165.173496 -304.17888)
					(end 165.177216 -304.18786)
				)
			)
		)
	)
	(zone
		(layer "In1.Cu")
		(hatch none 0.5)
		(connect_pads
			(clearance 0)
		)
		(min_thickness 0.25)
		(keepout
			(tracks not_allowed)
			(vias allowed)
			(pads allowed)
			(copperpour not_allowed)
			(footprints allowed)
		)
		(placement
			(enabled no)
			(sheetname "")
		)
		(fill
			(thermal_gap 0.5)
			(thermal_bridge_width 0.5)
			(island_removal_mode 0)
		)
		(polygon
			(pts
				(arc
					(start 311.390792 -399.701258)
					(mid 311.517792 -399.828258)
					(end 311.644792 -399.701258)
				)
				(arc
					(start 311.644792 -399.625058)
					(mid 311.517792 -399.498058)
					(end 311.390792 -399.625058)
				)
			)
		)
	)
	(zone
		(layer "In1.Cu")
		(hatch none 0.5)
		(connect_pads
			(clearance 0)
		)
		(min_thickness 0.25)
		(keepout
			(tracks not_allowed)
			(vias allowed)
			(pads allowed)
			(copperpour not_allowed)
			(footprints allowed)
		)
		(placement
			(enabled no)
			(sheetname "")
		)
		(fill
			(thermal_gap 0.5)
			(thermal_bridge_width 0.5)
			(island_removal_mode 0)
		)
		(polygon
			(pts
				(arc
					(start 165.177216 -211.182458)
					(mid 165.173496 -211.191438)
					(end 165.164516 -211.195158)
				)
				(arc
					(start 163.691316 -211.195158)
					(mid 163.682336 -211.191438)
					(end 163.678616 -211.182458)
				)
				(arc
					(start 163.678616 -210.68792)
					(mid 163.682336 -210.67894)
					(end 163.691316 -210.67522)
				)
				(arc
					(start 165.164516 -210.67522)
					(mid 165.173496 -210.67894)
					(end 165.177216 -210.68792)
				)
			)
		)
	)
	(zone
		(layer "In1.Cu")
		(hatch none 0.5)
		(connect_pads
			(clearance 0)
		)
		(min_thickness 0.25)
		(keepout
			(tracks not_allowed)
			(vias allowed)
			(pads allowed)
			(copperpour not_allowed)
			(footprints allowed)
		)
		(placement
			(enabled no)
			(sheetname "")
		)
		(fill
			(thermal_gap 0.5)
			(thermal_bridge_width 0.5)
			(island_removal_mode 0)
		)
		(polygon
			(pts
				(arc
					(start 344.78849 -397.849344)
					(mid 344.40749 -397.849344)
					(end 344.78849 -397.849344)
				)
			)
		)
	)
	(zone
		(layer "In1.Cu")
		(hatch none 0.5)
		(connect_pads
			(clearance 0)
		)
		(min_thickness 0.25)
		(keepout
			(tracks not_allowed)
			(vias allowed)
			(pads allowed)
			(copperpour not_allowed)
			(footprints allowed)
		)
		(placement
			(enabled no)
			(sheetname "")
		)
		(fill
			(thermal_gap 0.5)
			(thermal_bridge_width 0.5)
			(island_removal_mode 0)
		)
		(polygon
			(pts
				(arc
					(start 454.937368 -311.482232)
					(mid 454.933648 -311.491212)
					(end 454.924668 -311.494932)
				)
				(arc
					(start 453.451468 -311.494932)
					(mid 453.442488 -311.491212)
					(end 453.438768 -311.482232)
				)
				(arc
					(start 453.438768 -310.987694)
					(mid 453.442488 -310.978714)
					(end 453.451468 -310.974994)
				)
				(arc
					(start 454.924668 -310.974994)
					(mid 454.933648 -310.978714)
					(end 454.937368 -310.987694)
				)
			)
		)
	)
	(zone
		(layer "In1.Cu")
		(hatch none 0.5)
		(connect_pads
			(clearance 0)
		)
		(min_thickness 0.25)
		(keepout
			(tracks not_allowed)
			(vias allowed)
			(pads allowed)
			(copperpour not_allowed)
			(footprints allowed)
		)
		(placement
			(enabled no)
			(sheetname "")
		)
		(fill
			(thermal_gap 0.5)
			(thermal_bridge_width 0.5)
			(island_removal_mode 0)
		)
		(polygon
			(pts
				(arc
					(start 288.929318 -217.132154)
					(mid 288.925598 -217.141134)
					(end 288.916618 -217.144854)
				)
				(arc
					(start 287.443418 -217.144854)
					(mid 287.434438 -217.141134)
					(end 287.430718 -217.132154)
				)
				(arc
					(start 287.430718 -216.637616)
					(mid 287.434438 -216.628636)
					(end 287.443418 -216.624916)
				)
				(arc
					(start 288.916618 -216.624916)
					(mid 288.925598 -216.628636)
					(end 288.929318 -216.637616)
				)
			)
		)
	)
	(zone
		(layer "In1.Cu")
		(hatch none 0.5)
		(connect_pads
			(clearance 0)
		)
		(min_thickness 0.25)
		(keepout
			(tracks not_allowed)
			(vias allowed)
			(pads allowed)
			(copperpour not_allowed)
			(footprints allowed)
		)
		(placement
			(enabled no)
			(sheetname "")
		)
		(fill
			(thermal_gap 0.5)
			(thermal_bridge_width 0.5)
			(island_removal_mode 0)
		)
		(polygon
			(pts
				(arc
					(start 285.485332 -281.732228)
					(mid 285.481612 -281.741208)
					(end 285.472632 -281.744928)
				)
				(arc
					(start 283.999432 -281.744928)
					(mid 283.990452 -281.741208)
					(end 283.986732 -281.732228)
				)
				(arc
					(start 283.986732 -281.23769)
					(mid 283.990452 -281.22871)
					(end 283.999432 -281.22499)
				)
				(arc
					(start 285.472632 -281.22499)
					(mid 285.481612 -281.22871)
					(end 285.485332 -281.23769)
				)
			)
		)
	)
	(zone
		(layer "In1.Cu")
		(hatch none 0.5)
		(connect_pads
			(clearance 0)
		)
		(min_thickness 0.25)
		(keepout
			(tracks not_allowed)
			(vias allowed)
			(pads allowed)
			(copperpour not_allowed)
			(footprints allowed)
		)
		(placement
			(enabled no)
			(sheetname "")
		)
		(fill
			(thermal_gap 0.5)
			(thermal_bridge_width 0.5)
			(island_removal_mode 0)
		)
		(polygon
			(pts
				(arc
					(start 187.809378 -293.632382)
					(mid 187.805658 -293.641362)
					(end 187.796678 -293.645082)
				)
				(arc
					(start 186.323478 -293.645082)
					(mid 186.314498 -293.641362)
					(end 186.310778 -293.632382)
				)
				(arc
					(start 186.310778 -293.137844)
					(mid 186.314498 -293.128864)
					(end 186.323478 -293.125144)
				)
				(arc
					(start 187.796678 -293.125144)
					(mid 187.805658 -293.128864)
					(end 187.809378 -293.137844)
				)
			)
		)
	)
	(zone
		(layer "In1.Cu")
		(hatch none 0.5)
		(connect_pads
			(clearance 0)
		)
		(min_thickness 0.25)
		(keepout
			(tracks not_allowed)
			(vias allowed)
			(pads allowed)
			(copperpour not_allowed)
			(footprints allowed)
		)
		(placement
			(enabled no)
			(sheetname "")
		)
		(fill
			(thermal_gap 0.5)
			(thermal_bridge_width 0.5)
			(island_removal_mode 0)
		)
		(polygon
			(pts
				(arc
					(start 60.177426 -304.682398)
					(mid 60.173706 -304.691378)
					(end 60.164726 -304.695098)
				)
				(arc
					(start 58.691526 -304.695098)
					(mid 58.682546 -304.691378)
					(end 58.678826 -304.682398)
				)
				(arc
					(start 58.678826 -304.18786)
					(mid 58.682546 -304.17888)
					(end 58.691526 -304.17516)
				)
				(arc
					(start 60.164726 -304.17516)
					(mid 60.173706 -304.17888)
					(end 60.177426 -304.18786)
				)
			)
		)
	)
	(zone
		(layer "In1.Cu")
		(hatch none 0.5)
		(connect_pads
			(clearance 0)
		)
		(min_thickness 0.25)
		(keepout
			(tracks not_allowed)
			(vias allowed)
			(pads allowed)
			(copperpour not_allowed)
			(footprints allowed)
		)
		(placement
			(enabled no)
			(sheetname "")
		)
		(fill
			(thermal_gap 0.5)
			(thermal_bridge_width 0.5)
			(island_removal_mode 0)
		)
		(polygon
			(pts
				(arc
					(start 331.088492 -385.11861)
					(mid 331.079256 -385.138534)
					(end 331.076046 -385.160266)
				)
				(arc
					(start 331.076046 -385.35483)
					(mid 331.098364 -385.408712)
					(end 331.152246 -385.43103)
				)
				(arc
					(start 331.838046 -385.43103)
					(mid 331.891928 -385.408712)
					(end 331.914246 -385.35483)
				)
				(arc
					(start 331.914246 -385.160266)
					(mid 331.911078 -385.138522)
					(end 331.9018 -385.11861)
				)
				(arc
					(start 331.709014 -384.822446)
					(mid 331.696792 -384.780762)
					(end 331.709268 -384.739134)
				)
				(arc
					(start 331.9018 -384.44551)
					(mid 331.911036 -384.425586)
					(end 331.914246 -384.403854)
				)
				(arc
					(start 331.914246 -384.20929)
					(mid 331.891928 -384.155408)
					(end 331.838046 -384.13309)
				)
				(arc
					(start 331.152246 -384.13309)
					(mid 331.098364 -384.155408)
					(end 331.076046 -384.20929)
				)
				(arc
					(start 331.076046 -384.405124)
					(mid 331.079214 -384.426868)
					(end 331.088492 -384.44678)
				)
				(arc
					(start 331.281024 -384.740404)
					(mid 331.293426 -384.78206)
					(end 331.281024 -384.823716)
				)
			)
		)
	)
	(zone
		(layer "In1.Cu")
		(hatch none 0.5)
		(connect_pads
			(clearance 0)
		)
		(min_thickness 0.25)
		(keepout
			(tracks not_allowed)
			(vias allowed)
			(pads allowed)
			(copperpour not_allowed)
			(footprints allowed)
		)
		(placement
			(enabled no)
			(sheetname "")
		)
		(fill
			(thermal_gap 0.5)
			(thermal_bridge_width 0.5)
			(island_removal_mode 0)
		)
		(polygon
			(pts
				(arc
					(start 443.2935 -243.482114)
					(mid 443.28978 -243.491094)
					(end 443.2808 -243.494814)
				)
				(arc
					(start 441.8076 -243.494814)
					(mid 441.79862 -243.491094)
					(end 441.7949 -243.482114)
				)
				(arc
					(start 441.7949 -242.987576)
					(mid 441.79862 -242.978596)
					(end 441.8076 -242.974876)
				)
				(arc
					(start 443.2808 -242.974876)
					(mid 443.28978 -242.978596)
					(end 443.2935 -242.987576)
				)
			)
		)
	)
	(zone
		(layer "In1.Cu")
		(hatch none 0.5)
		(connect_pads
			(clearance 0)
		)
		(min_thickness 0.25)
		(keepout
			(tracks not_allowed)
			(vias allowed)
			(pads allowed)
			(copperpour not_allowed)
			(footprints allowed)
		)
		(placement
			(enabled no)
			(sheetname "")
		)
		(fill
			(thermal_gap 0.5)
			(thermal_bridge_width 0.5)
			(island_removal_mode 0)
		)
		(polygon
			(pts
				(arc
					(start 55.372508 -7.672324)
					(mid 55.394826 -7.618442)
					(end 55.448708 -7.596124)
				)
				(arc
					(start 56.485282 -7.596124)
					(mid 56.539164 -7.618442)
					(end 56.561482 -7.672324)
				)
				(arc
					(start 56.561482 -9.071864)
					(mid 56.539164 -9.125746)
					(end 56.485282 -9.148064)
				)
				(arc
					(start 55.448708 -9.148064)
					(mid 55.394826 -9.125746)
					(end 55.372508 -9.071864)
				)
			)
		)
	)
	(zone
		(layer "In1.Cu")
		(hatch none 0.5)
		(connect_pads
			(clearance 0)
		)
		(min_thickness 0.25)
		(keepout
			(tracks not_allowed)
			(vias allowed)
			(pads allowed)
			(copperpour not_allowed)
			(footprints allowed)
		)
		(placement
			(enabled no)
			(sheetname "")
		)
		(fill
			(thermal_gap 0.5)
			(thermal_bridge_width 0.5)
			(island_removal_mode 0)
		)
		(polygon
			(pts
				(arc
					(start 432.30546 -308.082188)
					(mid 432.30174 -308.091168)
					(end 432.29276 -308.094888)
				)
				(arc
					(start 430.81956 -308.094888)
					(mid 430.81058 -308.091168)
					(end 430.80686 -308.082188)
				)
				(arc
					(start 430.80686 -307.58765)
					(mid 430.81058 -307.57867)
					(end 430.81956 -307.57495)
				)
				(arc
					(start 432.29276 -307.57495)
					(mid 432.30174 -307.57867)
					(end 432.30546 -307.58765)
				)
			)
		)
	)
	(zone
		(layer "In1.Cu")
		(hatch none 0.5)
		(connect_pads
			(clearance 0)
		)
		(min_thickness 0.25)
		(keepout
			(tracks not_allowed)
			(vias allowed)
			(pads allowed)
			(copperpour not_allowed)
			(footprints allowed)
		)
		(placement
			(enabled no)
			(sheetname "")
		)
		(fill
			(thermal_gap 0.5)
			(thermal_bridge_width 0.5)
			(island_removal_mode 0)
		)
		(polygon
			(pts
				(arc
					(start 308.117494 -205.232254)
					(mid 308.113774 -205.241234)
					(end 308.104794 -205.244954)
				)
				(arc
					(start 306.631594 -205.244954)
					(mid 306.622614 -205.241234)
					(end 306.618894 -205.232254)
				)
				(arc
					(start 306.618894 -204.737716)
					(mid 306.622614 -204.728736)
					(end 306.631594 -204.725016)
				)
				(arc
					(start 308.104794 -204.725016)
					(mid 308.113774 -204.728736)
					(end 308.117494 -204.737716)
				)
			)
		)
	)
	(zone
		(layer "In1.Cu")
		(hatch none 0.5)
		(connect_pads
			(clearance 0)
		)
		(min_thickness 0.25)
		(keepout
			(tracks not_allowed)
			(vias allowed)
			(pads allowed)
			(copperpour not_allowed)
			(footprints allowed)
		)
		(placement
			(enabled no)
			(sheetname "")
		)
		(fill
			(thermal_gap 0.5)
			(thermal_bridge_width 0.5)
			(island_removal_mode 0)
		)
		(polygon
			(pts
				(arc
					(start 277.941532 -269.832328)
					(mid 277.937812 -269.841308)
					(end 277.928832 -269.845028)
				)
				(arc
					(start 276.455632 -269.845028)
					(mid 276.446652 -269.841308)
					(end 276.442932 -269.832328)
				)
				(arc
					(start 276.442932 -269.33779)
					(mid 276.446652 -269.32881)
					(end 276.455632 -269.32509)
				)
				(arc
					(start 277.928832 -269.32509)
					(mid 277.937812 -269.32881)
					(end 277.941532 -269.33779)
				)
			)
		)
	)
	(zone
		(layer "In1.Cu")
		(hatch none 0.5)
		(connect_pads
			(clearance 0)
		)
		(min_thickness 0.25)
		(keepout
			(tracks not_allowed)
			(vias allowed)
			(pads allowed)
			(copperpour not_allowed)
			(footprints allowed)
		)
		(placement
			(enabled no)
			(sheetname "")
		)
		(fill
			(thermal_gap 0.5)
			(thermal_bridge_width 0.5)
			(island_removal_mode 0)
		)
		(polygon
			(pts
				(arc
					(start 40.50284 -425.510706)
					(mid 40.556722 -425.488388)
					(end 40.57904 -425.434506)
				)
				(arc
					(start 40.57904 -425.078906)
					(mid 40.556722 -425.025024)
					(end 40.50284 -425.002706)
				)
				(arc
					(start 38.59784 -425.002706)
					(mid 38.543958 -425.025024)
					(end 38.52164 -425.078906)
				)
				(arc
					(start 38.52164 -425.434506)
					(mid 38.543958 -425.488388)
					(end 38.59784 -425.510706)
				)
			)
		)
	)
	(zone
		(layer "In1.Cu")
		(hatch none 0.5)
		(connect_pads
			(clearance 0)
		)
		(min_thickness 0.25)
		(keepout
			(tracks not_allowed)
			(vias allowed)
			(pads allowed)
			(copperpour not_allowed)
			(footprints allowed)
		)
		(placement
			(enabled no)
			(sheetname "")
		)
		(fill
			(thermal_gap 0.5)
			(thermal_bridge_width 0.5)
			(island_removal_mode 0)
		)
		(polygon
			(pts
				(arc
					(start 146.618706 -383.440686)
					(mid 146.745706 -383.567686)
					(end 146.872706 -383.440686)
				)
				(arc
					(start 146.872706 -383.364486)
					(mid 146.745706 -383.237486)
					(end 146.618706 -383.364486)
				)
			)
		)
	)
	(zone
		(layer "In1.Cu")
		(hatch none 0.5)
		(connect_pads
			(clearance 0)
		)
		(min_thickness 0.25)
		(keepout
			(tracks not_allowed)
			(vias allowed)
			(pads allowed)
			(copperpour not_allowed)
			(footprints allowed)
		)
		(placement
			(enabled no)
			(sheetname "")
		)
		(fill
			(thermal_gap 0.5)
			(thermal_bridge_width 0.5)
			(island_removal_mode 0)
		)
		(polygon
			(pts
				(arc
					(start 48.190912 -391.319258)
					(mid 48.317912 -391.446258)
					(end 48.444912 -391.319258)
				)
				(arc
					(start 48.444912 -391.243058)
					(mid 48.317912 -391.116058)
					(end 48.190912 -391.243058)
				)
			)
		)
	)
	(zone
		(layer "In1.Cu")
		(hatch none 0.5)
		(connect_pads
			(clearance 0)
		)
		(min_thickness 0.25)
		(keepout
			(tracks not_allowed)
			(vias allowed)
			(pads allowed)
			(copperpour not_allowed)
			(footprints allowed)
		)
		(placement
			(enabled no)
			(sheetname "")
		)
		(fill
			(thermal_gap 0.5)
			(thermal_bridge_width 0.5)
			(island_removal_mode 0)
		)
		(polygon
			(pts
				(arc
					(start 413.117284 -304.682144)
					(mid 413.113564 -304.691124)
					(end 413.104584 -304.694844)
				)
				(arc
					(start 411.631384 -304.694844)
					(mid 411.622404 -304.691124)
					(end 411.618684 -304.682144)
				)
				(arc
					(start 411.618684 -304.187606)
					(mid 411.622404 -304.178626)
					(end 411.631384 -304.174906)
				)
				(arc
					(start 413.104584 -304.174906)
					(mid 413.113564 -304.178626)
					(end 413.117284 -304.187606)
				)
			)
		)
	)
	(zone
		(layer "In1.Cu")
		(hatch none 0.5)
		(connect_pads
			(clearance 0)
		)
		(min_thickness 0.25)
		(keepout
			(tracks not_allowed)
			(vias allowed)
			(pads allowed)
			(copperpour not_allowed)
			(footprints allowed)
		)
		(placement
			(enabled no)
			(sheetname "")
		)
		(fill
			(thermal_gap 0.5)
			(thermal_bridge_width 0.5)
			(island_removal_mode 0)
		)
		(polygon
			(pts
				(arc
					(start 35.807396 -426.148246)
					(mid 35.792517 -426.184167)
					(end 35.756596 -426.199046)
				)
				(arc
					(start 35.248596 -426.199046)
					(mid 35.212675 -426.184167)
					(end 35.197796 -426.148246)
				)
				(arc
					(start 35.197796 -425.671996)
					(mid 35.212675 -425.636075)
					(end 35.248596 -425.621196)
				)
				(arc
					(start 35.756596 -425.621196)
					(mid 35.792517 -425.636075)
					(end 35.807396 -425.671996)
				)
			)
		)
	)
	(zone
		(layer "In1.Cu")
		(hatch none 0.5)
		(connect_pads
			(clearance 0)
		)
		(min_thickness 0.25)
		(keepout
			(tracks not_allowed)
			(vias allowed)
			(pads allowed)
			(copperpour not_allowed)
			(footprints allowed)
		)
		(placement
			(enabled no)
			(sheetname "")
		)
		(fill
			(thermal_gap 0.5)
			(thermal_bridge_width 0.5)
			(island_removal_mode 0)
		)
		(polygon
			(pts
				(arc
					(start 402.618702 -391.822686)
					(mid 402.745702 -391.949686)
					(end 402.872702 -391.822686)
				)
				(arc
					(start 402.872702 -391.746486)
					(mid 402.745702 -391.619486)
					(end 402.618702 -391.746486)
				)
			)
		)
	)
	(zone
		(layer "In1.Cu")
		(hatch none 0.5)
		(connect_pads
			(clearance 0)
		)
		(min_thickness 0.25)
		(keepout
			(tracks not_allowed)
			(vias allowed)
			(pads allowed)
			(copperpour not_allowed)
			(footprints allowed)
		)
		(placement
			(enabled no)
			(sheetname "")
		)
		(fill
			(thermal_gap 0.5)
			(thermal_bridge_width 0.5)
			(island_removal_mode 0)
		)
		(polygon
			(pts
				(arc
					(start 273.841464 -276.632162)
					(mid 273.837744 -276.641142)
					(end 273.828764 -276.644862)
				)
				(arc
					(start 272.355564 -276.644862)
					(mid 272.346584 -276.641142)
					(end 272.342864 -276.632162)
				)
				(arc
					(start 272.342864 -276.137624)
					(mid 272.346584 -276.128644)
					(end 272.355564 -276.124924)
				)
				(arc
					(start 273.828764 -276.124924)
					(mid 273.837744 -276.128644)
					(end 273.841464 -276.137624)
				)
			)
		)
	)
	(zone
		(layer "In1.Cu")
		(hatch none 0.5)
		(connect_pads
			(clearance 0)
		)
		(min_thickness 0.25)
		(keepout
			(tracks not_allowed)
			(vias allowed)
			(pads allowed)
			(copperpour not_allowed)
			(footprints allowed)
		)
		(placement
			(enabled no)
			(sheetname "")
		)
		(fill
			(thermal_gap 0.5)
			(thermal_bridge_width 0.5)
			(island_removal_mode 0)
		)
		(polygon
			(pts
				(arc
					(start 277.941532 -252.832108)
					(mid 277.937812 -252.841088)
					(end 277.928832 -252.844808)
				)
				(arc
					(start 276.455632 -252.844808)
					(mid 276.446652 -252.841088)
					(end 276.442932 -252.832108)
				)
				(arc
					(start 276.442932 -252.33757)
					(mid 276.446652 -252.32859)
					(end 276.455632 -252.32487)
				)
				(arc
					(start 277.928832 -252.32487)
					(mid 277.937812 -252.32859)
					(end 277.941532 -252.33757)
				)
			)
		)
	)
	(zone
		(layer "In1.Cu")
		(hatch none 0.5)
		(connect_pads
			(clearance 0)
		)
		(min_thickness 0.25)
		(keepout
			(tracks not_allowed)
			(vias allowed)
			(pads allowed)
			(copperpour not_allowed)
			(footprints allowed)
		)
		(placement
			(enabled no)
			(sheetname "")
		)
		(fill
			(thermal_gap 0.5)
			(thermal_bridge_width 0.5)
			(island_removal_mode 0)
		)
		(polygon
			(pts
				(arc
					(start 428.205392 -207.78216)
					(mid 428.201672 -207.79114)
					(end 428.192692 -207.79486)
				)
				(arc
					(start 426.719492 -207.79486)
					(mid 426.710512 -207.79114)
					(end 426.706792 -207.78216)
				)
				(arc
					(start 426.706792 -207.287622)
					(mid 426.710512 -207.278642)
					(end 426.719492 -207.274922)
				)
				(arc
					(start 428.192692 -207.274922)
					(mid 428.201672 -207.278642)
					(end 428.205392 -207.287622)
				)
			)
		)
	)
	(zone
		(layer "In1.Cu")
		(hatch none 0.5)
		(connect_pads
			(clearance 0)
		)
		(min_thickness 0.25)
		(keepout
			(tracks not_allowed)
			(vias allowed)
			(pads allowed)
			(copperpour not_allowed)
			(footprints allowed)
		)
		(placement
			(enabled no)
			(sheetname "")
		)
		(fill
			(thermal_gap 0.5)
			(thermal_bridge_width 0.5)
			(island_removal_mode 0)
		)
		(polygon
			(pts
				(arc
					(start 265.87831 -276.38502)
					(mid 265.21791 -276.38502)
					(end 265.87831 -276.38502)
				)
			)
		)
	)
	(zone
		(layer "In1.Cu")
		(hatch none 0.5)
		(connect_pads
			(clearance 0)
		)
		(min_thickness 0.25)
		(keepout
			(tracks not_allowed)
			(vias allowed)
			(pads allowed)
			(copperpour not_allowed)
			(footprints allowed)
		)
		(placement
			(enabled no)
			(sheetname "")
		)
		(fill
			(thermal_gap 0.5)
			(thermal_bridge_width 0.5)
			(island_removal_mode 0)
		)
		(polygon
			(pts
				(arc
					(start 415.089086 -393.69238)
					(mid 414.708086 -393.69238)
					(end 415.089086 -393.69238)
				)
			)
		)
	)
	(zone
		(layer "In1.Cu")
		(hatch none 0.5)
		(connect_pads
			(clearance 0)
		)
		(min_thickness 0.25)
		(keepout
			(tracks not_allowed)
			(vias allowed)
			(pads allowed)
			(copperpour not_allowed)
			(footprints allowed)
		)
		(placement
			(enabled no)
			(sheetname "")
		)
		(fill
			(thermal_gap 0.5)
			(thermal_bridge_width 0.5)
			(island_removal_mode 0)
		)
		(polygon
			(pts
				(arc
					(start 439.849514 -242.63223)
					(mid 439.845794 -242.64121)
					(end 439.836814 -242.64493)
				)
				(arc
					(start 438.363614 -242.64493)
					(mid 438.354634 -242.64121)
					(end 438.350914 -242.63223)
				)
				(arc
					(start 438.350914 -242.137692)
					(mid 438.354634 -242.128712)
					(end 438.363614 -242.124992)
				)
				(arc
					(start 439.836814 -242.124992)
					(mid 439.845794 -242.128712)
					(end 439.849514 -242.137692)
				)
			)
		)
	)
	(zone
		(layer "In1.Cu")
		(hatch none 0.5)
		(connect_pads
			(clearance 0)
		)
		(min_thickness 0.25)
		(keepout
			(tracks not_allowed)
			(vias allowed)
			(pads allowed)
			(copperpour not_allowed)
			(footprints allowed)
		)
		(placement
			(enabled no)
			(sheetname "")
		)
		(fill
			(thermal_gap 0.5)
			(thermal_bridge_width 0.5)
			(island_removal_mode 0)
		)
		(polygon
			(pts
				(arc
					(start 293.029386 -291.082222)
					(mid 293.025666 -291.091202)
					(end 293.016686 -291.094922)
				)
				(arc
					(start 291.543486 -291.094922)
					(mid 291.534506 -291.091202)
					(end 291.530786 -291.082222)
				)
				(arc
					(start 291.530786 -290.587684)
					(mid 291.534506 -290.578704)
					(end 291.543486 -290.574984)
				)
				(arc
					(start 293.016686 -290.574984)
					(mid 293.025666 -290.578704)
					(end 293.029386 -290.587684)
				)
			)
		)
	)
	(zone
		(layer "In1.Cu")
		(hatch none 0.5)
		(connect_pads
			(clearance 0)
		)
		(min_thickness 0.25)
		(keepout
			(tracks not_allowed)
			(vias allowed)
			(pads allowed)
			(copperpour not_allowed)
			(footprints allowed)
		)
		(placement
			(enabled no)
			(sheetname "")
		)
		(fill
			(thermal_gap 0.5)
			(thermal_bridge_width 0.5)
			(island_removal_mode 0)
		)
		(polygon
			(pts
				(arc
					(start 45.089318 -217.982546)
					(mid 45.085598 -217.991526)
					(end 45.076618 -217.995246)
				)
				(arc
					(start 43.603418 -217.995246)
					(mid 43.594438 -217.991526)
					(end 43.590718 -217.982546)
				)
				(arc
					(start 43.590718 -217.488008)
					(mid 43.594438 -217.479028)
					(end 43.603418 -217.475308)
				)
				(arc
					(start 45.076618 -217.475308)
					(mid 45.085598 -217.479028)
					(end 45.089318 -217.488008)
				)
			)
		)
	)
	(zone
		(layer "In1.Cu")
		(hatch none 0.5)
		(connect_pads
			(clearance 0)
		)
		(min_thickness 0.25)
		(keepout
			(tracks not_allowed)
			(vias allowed)
			(pads allowed)
			(copperpour not_allowed)
			(footprints allowed)
		)
		(placement
			(enabled no)
			(sheetname "")
		)
		(fill
			(thermal_gap 0.5)
			(thermal_bridge_width 0.5)
			(island_removal_mode 0)
		)
		(polygon
			(pts
				(arc
					(start 195.353432 -285.98241)
					(mid 195.349712 -285.99139)
					(end 195.340732 -285.99511)
				)
				(arc
					(start 193.867532 -285.99511)
					(mid 193.858552 -285.99139)
					(end 193.854832 -285.98241)
				)
				(arc
					(start 193.854832 -285.487872)
					(mid 193.858552 -285.478892)
					(end 193.867532 -285.475172)
				)
				(arc
					(start 195.340732 -285.475172)
					(mid 195.349712 -285.478892)
					(end 195.353432 -285.487872)
				)
			)
		)
	)
	(zone
		(layer "In1.Cu")
		(hatch none 0.5)
		(connect_pads
			(clearance 0)
		)
		(min_thickness 0.25)
		(keepout
			(tracks not_allowed)
			(vias allowed)
			(pads allowed)
			(copperpour not_allowed)
			(footprints allowed)
		)
		(placement
			(enabled no)
			(sheetname "")
		)
		(fill
			(thermal_gap 0.5)
			(thermal_bridge_width 0.5)
			(island_removal_mode 0)
		)
		(polygon
			(pts
				(arc
					(start 187.809378 -200.132442)
					(mid 187.805658 -200.141422)
					(end 187.796678 -200.145142)
				)
				(arc
					(start 186.323478 -200.145142)
					(mid 186.314498 -200.141422)
					(end 186.310778 -200.132442)
				)
				(arc
					(start 186.310778 -199.637904)
					(mid 186.314498 -199.628924)
					(end 186.323478 -199.625204)
				)
				(arc
					(start 187.796678 -199.625204)
					(mid 187.805658 -199.628924)
					(end 187.809378 -199.637904)
				)
			)
		)
	)
	(zone
		(layer "In1.Cu")
		(hatch none 0.5)
		(connect_pads
			(clearance 0)
		)
		(min_thickness 0.25)
		(keepout
			(tracks not_allowed)
			(vias allowed)
			(pads allowed)
			(copperpour not_allowed)
			(footprints allowed)
		)
		(placement
			(enabled no)
			(sheetname "")
		)
		(fill
			(thermal_gap 0.5)
			(thermal_bridge_width 0.5)
			(island_removal_mode 0)
		)
		(polygon
			(pts
				(arc
					(start 296.473372 -280.88209)
					(mid 296.469652 -280.89107)
					(end 296.460672 -280.89479)
				)
				(arc
					(start 294.987472 -280.89479)
					(mid 294.978492 -280.89107)
					(end 294.974772 -280.88209)
				)
				(arc
					(start 294.974772 -280.387552)
					(mid 294.978492 -280.378572)
					(end 294.987472 -280.374852)
				)
				(arc
					(start 296.460672 -280.374852)
					(mid 296.469652 -280.378572)
					(end 296.473372 -280.387552)
				)
			)
		)
	)
	(zone
		(layer "In1.Cu")
		(hatch none 0.5)
		(connect_pads
			(clearance 0)
		)
		(min_thickness 0.25)
		(keepout
			(tracks not_allowed)
			(vias allowed)
			(pads allowed)
			(copperpour not_allowed)
			(footprints allowed)
		)
		(placement
			(enabled no)
			(sheetname "")
		)
		(fill
			(thermal_gap 0.5)
			(thermal_bridge_width 0.5)
			(island_removal_mode 0)
		)
		(polygon
			(pts
				(arc
					(start 316.661038 -397.156432)
					(mid 316.280038 -397.156432)
					(end 316.661038 -397.156432)
				)
			)
		)
	)
	(zone
		(layer "In1.Cu")
		(hatch none 0.5)
		(connect_pads
			(clearance 0)
		)
		(min_thickness 0.25)
		(keepout
			(tracks not_allowed)
			(vias allowed)
			(pads allowed)
			(copperpour not_allowed)
			(footprints allowed)
		)
		(placement
			(enabled no)
			(sheetname "")
		)
		(fill
			(thermal_gap 0.5)
			(thermal_bridge_width 0.5)
			(island_removal_mode 0)
		)
		(polygon
			(pts
				(arc
					(start 285.485332 -229.882192)
					(mid 285.481612 -229.891172)
					(end 285.472632 -229.894892)
				)
				(arc
					(start 283.999432 -229.894892)
					(mid 283.990452 -229.891172)
					(end 283.986732 -229.882192)
				)
				(arc
					(start 283.986732 -229.387654)
					(mid 283.990452 -229.378674)
					(end 283.999432 -229.374954)
				)
				(arc
					(start 285.472632 -229.374954)
					(mid 285.481612 -229.378674)
					(end 285.485332 -229.387654)
				)
			)
		)
	)
	(zone
		(layer "In1.Cu")
		(hatch none 0.5)
		(connect_pads
			(clearance 0)
		)
		(min_thickness 0.25)
		(keepout
			(tracks not_allowed)
			(vias allowed)
			(pads allowed)
			(copperpour not_allowed)
			(footprints allowed)
		)
		(placement
			(enabled no)
			(sheetname "")
		)
		(fill
			(thermal_gap 0.5)
			(thermal_bridge_width 0.5)
			(island_removal_mode 0)
		)
		(polygon
			(pts
				(arc
					(start 384.490976 -391.822686)
					(mid 384.617976 -391.949686)
					(end 384.744976 -391.822686)
				)
				(arc
					(start 384.744976 -391.746486)
					(mid 384.617976 -391.619486)
					(end 384.490976 -391.746486)
				)
			)
		)
	)
	(zone
		(layer "In1.Cu")
		(hatch none 0.5)
		(connect_pads
			(clearance 0)
		)
		(min_thickness 0.25)
		(keepout
			(tracks not_allowed)
			(vias allowed)
			(pads allowed)
			(copperpour not_allowed)
			(footprints allowed)
		)
		(placement
			(enabled no)
			(sheetname "")
		)
		(fill
			(thermal_gap 0.5)
			(thermal_bridge_width 0.5)
			(island_removal_mode 0)
		)
		(polygon
			(pts
				(arc
					(start 288.929318 -312.332116)
					(mid 288.925598 -312.341096)
					(end 288.916618 -312.344816)
				)
				(arc
					(start 287.443418 -312.344816)
					(mid 287.434438 -312.341096)
					(end 287.430718 -312.332116)
				)
				(arc
					(start 287.430718 -311.837578)
					(mid 287.434438 -311.828598)
					(end 287.443418 -311.824878)
				)
				(arc
					(start 288.916618 -311.824878)
					(mid 288.925598 -311.828598)
					(end 288.929318 -311.837578)
				)
			)
		)
	)
	(zone
		(layer "In1.Cu")
		(hatch none 0.5)
		(connect_pads
			(clearance 0)
		)
		(min_thickness 0.25)
		(keepout
			(tracks not_allowed)
			(vias allowed)
			(pads allowed)
			(copperpour not_allowed)
			(footprints allowed)
		)
		(placement
			(enabled no)
			(sheetname "")
		)
		(fill
			(thermal_gap 0.5)
			(thermal_bridge_width 0.5)
			(island_removal_mode 0)
		)
		(polygon
			(pts
				(arc
					(start 420.661338 -273.232118)
					(mid 420.657618 -273.241098)
					(end 420.648638 -273.244818)
				)
				(arc
					(start 419.175438 -273.244818)
					(mid 419.166458 -273.241098)
					(end 419.162738 -273.232118)
				)
				(arc
					(start 419.162738 -272.73758)
					(mid 419.166458 -272.7286)
					(end 419.175438 -272.72488)
				)
				(arc
					(start 420.648638 -272.72488)
					(mid 420.657618 -272.7286)
					(end 420.661338 -272.73758)
				)
			)
		)
	)
	(zone
		(layer "In1.Cu")
		(hatch none 0.5)
		(connect_pads
			(clearance 0)
		)
		(min_thickness 0.25)
		(keepout
			(tracks not_allowed)
			(vias allowed)
			(pads allowed)
			(copperpour not_allowed)
			(footprints allowed)
		)
		(placement
			(enabled no)
			(sheetname "")
		)
		(fill
			(thermal_gap 0.5)
			(thermal_bridge_width 0.5)
			(island_removal_mode 0)
		)
		(polygon
			(pts
				(arc
					(start 343.91854 -399.701258)
					(mid 344.04554 -399.828258)
					(end 344.17254 -399.701258)
				)
				(arc
					(start 344.17254 -399.625058)
					(mid 344.04554 -399.498058)
					(end 343.91854 -399.625058)
				)
			)
		)
	)
	(zone
		(layer "In1.Cu")
		(hatch none 0.5)
		(connect_pads
			(clearance 0)
		)
		(min_thickness 0.25)
		(keepout
			(tracks not_allowed)
			(vias allowed)
			(pads allowed)
			(copperpour not_allowed)
			(footprints allowed)
		)
		(placement
			(enabled no)
			(sheetname "")
		)
		(fill
			(thermal_gap 0.5)
			(thermal_bridge_width 0.5)
			(island_removal_mode 0)
		)
		(polygon
			(pts
				(arc
					(start 270.397478 -281.732228)
					(mid 270.393758 -281.741208)
					(end 270.384778 -281.744928)
				)
				(arc
					(start 268.911578 -281.744928)
					(mid 268.902598 -281.741208)
					(end 268.898878 -281.732228)
				)
				(arc
					(start 268.898878 -281.23769)
					(mid 268.902598 -281.22871)
					(end 268.911578 -281.22499)
				)
				(arc
					(start 270.384778 -281.22499)
					(mid 270.393758 -281.22871)
					(end 270.397478 -281.23769)
				)
			)
		)
	)
	(zone
		(layer "In1.Cu")
		(hatch none 0.5)
		(connect_pads
			(clearance 0)
		)
		(min_thickness 0.25)
		(keepout
			(tracks not_allowed)
			(vias allowed)
			(pads allowed)
			(copperpour not_allowed)
			(footprints allowed)
		)
		(placement
			(enabled no)
			(sheetname "")
		)
		(fill
			(thermal_gap 0.5)
			(thermal_bridge_width 0.5)
			(island_removal_mode 0)
		)
		(polygon
			(pts
				(arc
					(start 308.117494 -311.482232)
					(mid 308.113774 -311.491212)
					(end 308.104794 -311.494932)
				)
				(arc
					(start 306.631594 -311.494932)
					(mid 306.622614 -311.491212)
					(end 306.618894 -311.482232)
				)
				(arc
					(start 306.618894 -310.987694)
					(mid 306.622614 -310.978714)
					(end 306.631594 -310.974994)
				)
				(arc
					(start 308.104794 -310.974994)
					(mid 308.113774 -310.978714)
					(end 308.117494 -310.987694)
				)
			)
		)
	)
	(zone
		(layer "In1.Cu")
		(hatch none 0.5)
		(connect_pads
			(clearance 0)
		)
		(min_thickness 0.25)
		(keepout
			(tracks not_allowed)
			(vias allowed)
			(pads allowed)
			(copperpour not_allowed)
			(footprints allowed)
		)
		(placement
			(enabled no)
			(sheetname "")
		)
		(fill
			(thermal_gap 0.5)
			(thermal_bridge_width 0.5)
			(island_removal_mode 0)
		)
		(polygon
			(pts
				(arc
					(start 420.661338 -239.232186)
					(mid 420.657618 -239.241166)
					(end 420.648638 -239.244886)
				)
				(arc
					(start 419.175438 -239.244886)
					(mid 419.166458 -239.241166)
					(end 419.162738 -239.232186)
				)
				(arc
					(start 419.162738 -238.737648)
					(mid 419.166458 -238.728668)
					(end 419.175438 -238.724948)
				)
				(arc
					(start 420.648638 -238.724948)
					(mid 420.657618 -238.728668)
					(end 420.661338 -238.737648)
				)
			)
		)
	)
	(zone
		(layer "In1.Cu")
		(hatch none 0.5)
		(connect_pads
			(clearance 0)
		)
		(min_thickness 0.25)
		(keepout
			(tracks not_allowed)
			(vias allowed)
			(pads allowed)
			(copperpour not_allowed)
			(footprints allowed)
		)
		(placement
			(enabled no)
			(sheetname "")
		)
		(fill
			(thermal_gap 0.5)
			(thermal_bridge_width 0.5)
			(island_removal_mode 0)
		)
		(polygon
			(pts
				(arc
					(start 300.57344 -302.132238)
					(mid 300.56972 -302.141218)
					(end 300.56074 -302.144938)
				)
				(arc
					(start 299.08754 -302.144938)
					(mid 299.07856 -302.141218)
					(end 299.07484 -302.132238)
				)
				(arc
					(start 299.07484 -301.6377)
					(mid 299.07856 -301.62872)
					(end 299.08754 -301.625)
				)
				(arc
					(start 300.56074 -301.625)
					(mid 300.56972 -301.62872)
					(end 300.57344 -301.6377)
				)
			)
		)
	)
	(zone
		(layer "In1.Cu")
		(hatch none 0.5)
		(connect_pads
			(clearance 0)
		)
		(min_thickness 0.25)
		(keepout
			(tracks not_allowed)
			(vias allowed)
			(pads allowed)
			(copperpour not_allowed)
			(footprints allowed)
		)
		(placement
			(enabled no)
			(sheetname "")
		)
		(fill
			(thermal_gap 0.5)
			(thermal_bridge_width 0.5)
			(island_removal_mode 0)
		)
		(polygon
			(pts
				(arc
					(start 206.9973 -200.98258)
					(mid 206.99358 -200.99156)
					(end 206.9846 -200.99528)
				)
				(arc
					(start 205.5114 -200.99528)
					(mid 205.50242 -200.99156)
					(end 205.4987 -200.98258)
				)
				(arc
					(start 205.4987 -200.488042)
					(mid 205.50242 -200.479062)
					(end 205.5114 -200.475342)
				)
				(arc
					(start 206.9846 -200.475342)
					(mid 206.99358 -200.479062)
					(end 206.9973 -200.488042)
				)
			)
		)
	)
	(zone
		(layer "In1.Cu")
		(hatch none 0.5)
		(connect_pads
			(clearance 0)
		)
		(min_thickness 0.25)
		(keepout
			(tracks not_allowed)
			(vias allowed)
			(pads allowed)
			(copperpour not_allowed)
			(footprints allowed)
		)
		(placement
			(enabled no)
			(sheetname "")
		)
		(fill
			(thermal_gap 0.5)
			(thermal_bridge_width 0.5)
			(island_removal_mode 0)
		)
		(polygon
			(pts
				(arc
					(start 34.873692 -17.967198)
					(mid 34.89601 -18.02108)
					(end 34.949892 -18.043398)
				)
				(arc
					(start 35.145472 -18.043398)
					(mid 35.167348 -18.040266)
					(end 35.187382 -18.030952)
				)
				(arc
					(start 35.481006 -17.83842)
					(mid 35.522662 -17.826018)
					(end 35.564318 -17.83842)
				)
				(arc
					(start 35.859212 -18.030952)
					(mid 35.879136 -18.040188)
					(end 35.900868 -18.043398)
				)
				(arc
					(start 36.095432 -18.043398)
					(mid 36.149314 -18.02108)
					(end 36.171632 -17.967198)
				)
				(arc
					(start 36.171632 -17.281398)
					(mid 36.149314 -17.227516)
					(end 36.095432 -17.205198)
				)
				(arc
					(start 35.900868 -17.205198)
					(mid 35.879124 -17.208366)
					(end 35.859212 -17.217644)
				)
				(arc
					(start 35.563048 -17.41043)
					(mid 35.521364 -17.422652)
					(end 35.479736 -17.410176)
				)
				(arc
					(start 35.186112 -17.217644)
					(mid 35.166188 -17.208408)
					(end 35.144456 -17.205198)
				)
				(arc
					(start 34.949892 -17.205198)
					(mid 34.89601 -17.227516)
					(end 34.873692 -17.281398)
				)
			)
		)
	)
	(zone
		(layer "In1.Cu")
		(hatch none 0.5)
		(connect_pads
			(clearance 0)
		)
		(min_thickness 0.25)
		(keepout
			(tracks not_allowed)
			(vias allowed)
			(pads allowed)
			(copperpour not_allowed)
			(footprints allowed)
		)
		(placement
			(enabled no)
			(sheetname "")
		)
		(fill
			(thermal_gap 0.5)
			(thermal_bridge_width 0.5)
			(island_removal_mode 0)
		)
		(polygon
			(pts
				(arc
					(start 310.77027 -392.30427)
					(mid 310.46547 -392.30427)
					(end 310.77027 -392.30427)
				)
			)
		)
	)
	(zone
		(layer "In1.Cu")
		(hatch none 0.5)
		(connect_pads
			(clearance 0)
		)
		(min_thickness 0.25)
		(keepout
			(tracks not_allowed)
			(vias allowed)
			(pads allowed)
			(copperpour not_allowed)
			(footprints allowed)
		)
		(placement
			(enabled no)
			(sheetname "")
		)
		(fill
			(thermal_gap 0.5)
			(thermal_bridge_width 0.5)
			(island_removal_mode 0)
		)
		(polygon
			(pts
				(arc
					(start 37.545264 -217.982546)
					(mid 37.541544 -217.991526)
					(end 37.532564 -217.995246)
				)
				(arc
					(start 36.059364 -217.995246)
					(mid 36.050384 -217.991526)
					(end 36.046664 -217.982546)
				)
				(arc
					(start 36.046664 -217.488008)
					(mid 36.050384 -217.479028)
					(end 36.059364 -217.475308)
				)
				(arc
					(start 37.532564 -217.475308)
					(mid 37.541544 -217.479028)
					(end 37.545264 -217.488008)
				)
			)
		)
	)
	(zone
		(layer "In1.Cu")
		(hatch none 0.5)
		(connect_pads
			(clearance 0)
		)
		(min_thickness 0.25)
		(keepout
			(tracks not_allowed)
			(vias allowed)
			(pads allowed)
			(copperpour not_allowed)
			(footprints allowed)
		)
		(placement
			(enabled no)
			(sheetname "")
		)
		(fill
			(thermal_gap 0.5)
			(thermal_bridge_width 0.5)
			(island_removal_mode 0)
		)
		(polygon
			(pts
				(arc
					(start 454.937368 -314.032138)
					(mid 454.933648 -314.041118)
					(end 454.924668 -314.044838)
				)
				(arc
					(start 453.451468 -314.044838)
					(mid 453.442488 -314.041118)
					(end 453.438768 -314.032138)
				)
				(arc
					(start 453.438768 -313.5376)
					(mid 453.442488 -313.52862)
					(end 453.451468 -313.5249)
				)
				(arc
					(start 454.924668 -313.5249)
					(mid 454.933648 -313.52862)
					(end 454.937368 -313.5376)
				)
			)
		)
	)
	(zone
		(layer "In1.Cu")
		(hatch none 0.5)
		(connect_pads
			(clearance 0)
		)
		(min_thickness 0.25)
		(keepout
			(tracks not_allowed)
			(vias allowed)
			(pads allowed)
			(copperpour not_allowed)
			(footprints allowed)
		)
		(placement
			(enabled no)
			(sheetname "")
		)
		(fill
			(thermal_gap 0.5)
			(thermal_bridge_width 0.5)
			(island_removal_mode 0)
		)
		(polygon
			(pts
				(arc
					(start 450.8373 -286.832294)
					(mid 450.83358 -286.841274)
					(end 450.8246 -286.844994)
				)
				(arc
					(start 449.3514 -286.844994)
					(mid 449.34242 -286.841274)
					(end 449.3387 -286.832294)
				)
				(arc
					(start 449.3387 -286.337756)
					(mid 449.34242 -286.328776)
					(end 449.3514 -286.325056)
				)
				(arc
					(start 450.8246 -286.325056)
					(mid 450.83358 -286.328776)
					(end 450.8373 -286.337756)
				)
			)
		)
	)
	(zone
		(layer "In1.Cu")
		(hatch none 0.5)
		(connect_pads
			(clearance 0)
		)
		(min_thickness 0.25)
		(keepout
			(tracks not_allowed)
			(vias allowed)
			(pads allowed)
			(copperpour not_allowed)
			(footprints allowed)
		)
		(placement
			(enabled no)
			(sheetname "")
		)
		(fill
			(thermal_gap 0.5)
			(thermal_bridge_width 0.5)
			(island_removal_mode 0)
		)
		(polygon
			(pts
				(arc
					(start 285.485332 -203.532232)
					(mid 285.481612 -203.541212)
					(end 285.472632 -203.544932)
				)
				(arc
					(start 283.999432 -203.544932)
					(mid 283.990452 -203.541212)
					(end 283.986732 -203.532232)
				)
				(arc
					(start 283.986732 -203.037694)
					(mid 283.990452 -203.028714)
					(end 283.999432 -203.024994)
				)
				(arc
					(start 285.472632 -203.024994)
					(mid 285.481612 -203.028714)
					(end 285.485332 -203.037694)
				)
			)
		)
	)
	(zone
		(layer "In1.Cu")
		(hatch none 0.5)
		(connect_pads
			(clearance 0)
		)
		(min_thickness 0.25)
		(keepout
			(tracks not_allowed)
			(vias allowed)
			(pads allowed)
			(copperpour not_allowed)
			(footprints allowed)
		)
		(placement
			(enabled no)
			(sheetname "")
		)
		(fill
			(thermal_gap 0.5)
			(thermal_bridge_width 0.5)
			(island_removal_mode 0)
		)
		(polygon
			(pts
				(arc
					(start 409.488894 -394.385292)
					(mid 409.107894 -394.385292)
					(end 409.488894 -394.385292)
				)
			)
		)
	)
	(zone
		(layer "In1.Cu")
		(hatch none 0.5)
		(connect_pads
			(clearance 0)
		)
		(min_thickness 0.25)
		(keepout
			(tracks not_allowed)
			(vias allowed)
			(pads allowed)
			(copperpour not_allowed)
			(footprints allowed)
		)
		(placement
			(enabled no)
			(sheetname "")
		)
		(fill
			(thermal_gap 0.5)
			(thermal_bridge_width 0.5)
			(island_removal_mode 0)
		)
		(polygon
			(pts
				(arc
					(start 88.498172 -383.92227)
					(mid 88.193372 -383.92227)
					(end 88.498172 -383.92227)
				)
			)
		)
	)
	(zone
		(layer "In1.Cu")
		(hatch none 0.5)
		(connect_pads
			(clearance 0)
		)
		(min_thickness 0.25)
		(keepout
			(tracks not_allowed)
			(vias allowed)
			(pads allowed)
			(copperpour not_allowed)
			(footprints allowed)
		)
		(placement
			(enabled no)
			(sheetname "")
		)
		(fill
			(thermal_gap 0.5)
			(thermal_bridge_width 0.5)
			(island_removal_mode 0)
		)
		(polygon
			(pts
				(arc
					(start 159.818832 -383.440686)
					(mid 159.945832 -383.567686)
					(end 160.072832 -383.440686)
				)
				(arc
					(start 160.072832 -383.364486)
					(mid 159.945832 -383.237486)
					(end 159.818832 -383.364486)
				)
			)
		)
	)
	(zone
		(layer "In1.Cu")
		(hatch none 0.5)
		(connect_pads
			(clearance 0)
		)
		(min_thickness 0.25)
		(keepout
			(tracks not_allowed)
			(vias allowed)
			(pads allowed)
			(copperpour not_allowed)
			(footprints allowed)
		)
		(placement
			(enabled no)
			(sheetname "")
		)
		(fill
			(thermal_gap 0.5)
			(thermal_bridge_width 0.5)
			(island_removal_mode 0)
		)
		(polygon
			(pts
				(arc
					(start 56.077358 -250.282456)
					(mid 56.073638 -250.291436)
					(end 56.064658 -250.295156)
				)
				(arc
					(start 54.591458 -250.295156)
					(mid 54.582478 -250.291436)
					(end 54.578758 -250.282456)
				)
				(arc
					(start 54.578758 -249.787918)
					(mid 54.582478 -249.778938)
					(end 54.591458 -249.775218)
				)
				(arc
					(start 56.064658 -249.775218)
					(mid 56.073638 -249.778938)
					(end 56.077358 -249.787918)
				)
			)
		)
	)
	(zone
		(layer "In1.Cu")
		(hatch none 0.5)
		(connect_pads
			(clearance 0)
		)
		(min_thickness 0.25)
		(keepout
			(tracks not_allowed)
			(vias allowed)
			(pads allowed)
			(copperpour not_allowed)
			(footprints allowed)
		)
		(placement
			(enabled no)
			(sheetname "")
		)
		(fill
			(thermal_gap 0.5)
			(thermal_bridge_width 0.5)
			(island_removal_mode 0)
		)
		(polygon
			(pts
				(arc
					(start 176.821338 -229.032562)
					(mid 176.817618 -229.041542)
					(end 176.808638 -229.045262)
				)
				(arc
					(start 175.335438 -229.045262)
					(mid 175.326458 -229.041542)
					(end 175.322738 -229.032562)
				)
				(arc
					(start 175.322738 -228.538024)
					(mid 175.326458 -228.529044)
					(end 175.335438 -228.525324)
				)
				(arc
					(start 176.808638 -228.525324)
					(mid 176.817618 -228.529044)
					(end 176.821338 -228.538024)
				)
			)
		)
	)
	(zone
		(layer "In1.Cu")
		(hatch none 0.5)
		(connect_pads
			(clearance 0)
		)
		(min_thickness 0.25)
		(keepout
			(tracks not_allowed)
			(vias allowed)
			(pads allowed)
			(copperpour not_allowed)
			(footprints allowed)
		)
		(placement
			(enabled no)
			(sheetname "")
		)
		(fill
			(thermal_gap 0.5)
			(thermal_bridge_width 0.5)
			(island_removal_mode 0)
		)
		(polygon
			(pts
				(arc
					(start 308.117494 -303.83226)
					(mid 308.113774 -303.84124)
					(end 308.104794 -303.84496)
				)
				(arc
					(start 306.631594 -303.84496)
					(mid 306.622614 -303.84124)
					(end 306.618894 -303.83226)
				)
				(arc
					(start 306.618894 -303.337722)
					(mid 306.622614 -303.328742)
					(end 306.631594 -303.325022)
				)
				(arc
					(start 308.104794 -303.325022)
					(mid 308.113774 -303.328742)
					(end 308.117494 -303.337722)
				)
			)
		)
	)
	(zone
		(layer "In1.Cu")
		(hatch none 0.5)
		(connect_pads
			(clearance 0)
		)
		(min_thickness 0.25)
		(keepout
			(tracks not_allowed)
			(vias allowed)
			(pads allowed)
			(copperpour not_allowed)
			(footprints allowed)
		)
		(placement
			(enabled no)
			(sheetname "")
		)
		(fill
			(thermal_gap 0.5)
			(thermal_bridge_width 0.5)
			(island_removal_mode 0)
		)
		(polygon
			(pts
				(arc
					(start 206.9973 -283.432504)
					(mid 206.99358 -283.441484)
					(end 206.9846 -283.445204)
				)
				(arc
					(start 205.5114 -283.445204)
					(mid 205.50242 -283.441484)
					(end 205.4987 -283.432504)
				)
				(arc
					(start 205.4987 -282.937966)
					(mid 205.50242 -282.928986)
					(end 205.5114 -282.925266)
				)
				(arc
					(start 206.9846 -282.925266)
					(mid 206.99358 -282.928986)
					(end 206.9973 -282.937966)
				)
			)
		)
	)
	(zone
		(layer "In1.Cu")
		(hatch none 0.5)
		(connect_pads
			(clearance 0)
		)
		(min_thickness 0.25)
		(keepout
			(tracks not_allowed)
			(vias allowed)
			(pads allowed)
			(copperpour not_allowed)
			(footprints allowed)
		)
		(placement
			(enabled no)
			(sheetname "")
		)
		(fill
			(thermal_gap 0.5)
			(thermal_bridge_width 0.5)
			(island_removal_mode 0)
		)
		(polygon
			(pts
				(arc
					(start 206.9973 -244.332506)
					(mid 206.99358 -244.341486)
					(end 206.9846 -244.345206)
				)
				(arc
					(start 205.5114 -244.345206)
					(mid 205.50242 -244.341486)
					(end 205.4987 -244.332506)
				)
				(arc
					(start 205.4987 -243.837968)
					(mid 205.50242 -243.828988)
					(end 205.5114 -243.825268)
				)
				(arc
					(start 206.9846 -243.825268)
					(mid 206.99358 -243.828988)
					(end 206.9973 -243.837968)
				)
			)
		)
	)
	(zone
		(layer "In1.Cu")
		(hatch none 0.5)
		(connect_pads
			(clearance 0)
		)
		(min_thickness 0.25)
		(keepout
			(tracks not_allowed)
			(vias allowed)
			(pads allowed)
			(copperpour not_allowed)
			(footprints allowed)
		)
		(placement
			(enabled no)
			(sheetname "")
		)
		(fill
			(thermal_gap 0.5)
			(thermal_bridge_width 0.5)
			(island_removal_mode 0)
		)
		(polygon
			(pts
				(arc
					(start 439.849514 -294.482266)
					(mid 439.845794 -294.491246)
					(end 439.836814 -294.494966)
				)
				(arc
					(start 438.363614 -294.494966)
					(mid 438.354634 -294.491246)
					(end 438.350914 -294.482266)
				)
				(arc
					(start 438.350914 -293.987728)
					(mid 438.354634 -293.978748)
					(end 438.363614 -293.975028)
				)
				(arc
					(start 439.836814 -293.975028)
					(mid 439.845794 -293.978748)
					(end 439.849514 -293.987728)
				)
			)
		)
	)
	(zone
		(layer "In1.Cu")
		(hatch none 0.5)
		(connect_pads
			(clearance 0)
		)
		(min_thickness 0.25)
		(keepout
			(tracks not_allowed)
			(vias allowed)
			(pads allowed)
			(copperpour not_allowed)
			(footprints allowed)
		)
		(placement
			(enabled no)
			(sheetname "")
		)
		(fill
			(thermal_gap 0.5)
			(thermal_bridge_width 0.5)
			(island_removal_mode 0)
		)
		(polygon
			(pts
				(arc
					(start 447.393568 -249.432318)
					(mid 447.389848 -249.441298)
					(end 447.380868 -249.445018)
				)
				(arc
					(start 445.907668 -249.445018)
					(mid 445.898688 -249.441298)
					(end 445.894968 -249.432318)
				)
				(arc
					(start 445.894968 -248.93778)
					(mid 445.898688 -248.9288)
					(end 445.907668 -248.92508)
				)
				(arc
					(start 447.380868 -248.92508)
					(mid 447.389848 -248.9288)
					(end 447.393568 -248.93778)
				)
			)
		)
	)
	(zone
		(layer "In1.Cu")
		(hatch none 0.5)
		(connect_pads
			(clearance 0)
		)
		(min_thickness 0.25)
		(keepout
			(tracks not_allowed)
			(vias allowed)
			(pads allowed)
			(copperpour not_allowed)
			(footprints allowed)
		)
		(placement
			(enabled no)
			(sheetname "")
		)
		(fill
			(thermal_gap 0.5)
			(thermal_bridge_width 0.5)
			(island_removal_mode 0)
		)
		(polygon
			(pts
				(arc
					(start 424.761406 -244.332252)
					(mid 424.757686 -244.341232)
					(end 424.748706 -244.344952)
				)
				(arc
					(start 423.275506 -244.344952)
					(mid 423.266526 -244.341232)
					(end 423.262806 -244.332252)
				)
				(arc
					(start 423.262806 -243.837714)
					(mid 423.266526 -243.828734)
					(end 423.275506 -243.825014)
				)
				(arc
					(start 424.748706 -243.825014)
					(mid 424.757686 -243.828734)
					(end 424.761406 -243.837714)
				)
			)
		)
	)
	(zone
		(layer "In1.Cu")
		(hatch none 0.5)
		(connect_pads
			(clearance 0)
		)
		(min_thickness 0.25)
		(keepout
			(tracks not_allowed)
			(vias allowed)
			(pads allowed)
			(copperpour not_allowed)
			(footprints allowed)
		)
		(placement
			(enabled no)
			(sheetname "")
		)
		(fill
			(thermal_gap 0.5)
			(thermal_bridge_width 0.5)
			(island_removal_mode 0)
		)
		(polygon
			(pts
				(arc
					(start 48.533304 -274.932394)
					(mid 48.529584 -274.941374)
					(end 48.520604 -274.945094)
				)
				(arc
					(start 47.047404 -274.945094)
					(mid 47.038424 -274.941374)
					(end 47.034704 -274.932394)
				)
				(arc
					(start 47.034704 -274.437856)
					(mid 47.038424 -274.428876)
					(end 47.047404 -274.425156)
				)
				(arc
					(start 48.520604 -274.425156)
					(mid 48.529584 -274.428876)
					(end 48.533304 -274.437856)
				)
			)
		)
	)
	(zone
		(layer "In1.Cu")
		(hatch none 0.5)
		(connect_pads
			(clearance 0)
		)
		(min_thickness 0.25)
		(keepout
			(tracks not_allowed)
			(vias allowed)
			(pads allowed)
			(copperpour not_allowed)
			(footprints allowed)
		)
		(placement
			(enabled no)
			(sheetname "")
		)
		(fill
			(thermal_gap 0.5)
			(thermal_bridge_width 0.5)
			(island_removal_mode 0)
		)
		(polygon
			(pts
				(arc
					(start 65.670684 -389.276844)
					(mid 65.670684 -389.657844)
					(end 65.670684 -389.276844)
				)
			)
		)
	)
	(zone
		(layer "In1.Cu")
		(hatch none 0.5)
		(connect_pads
			(clearance 0)
		)
		(min_thickness 0.25)
		(keepout
			(tracks not_allowed)
			(vias allowed)
			(pads allowed)
			(copperpour not_allowed)
			(footprints allowed)
		)
		(placement
			(enabled no)
			(sheetname "")
		)
		(fill
			(thermal_gap 0.5)
			(thermal_bridge_width 0.5)
			(island_removal_mode 0)
		)
		(polygon
			(pts
				(arc
					(start 443.2935 -318.28232)
					(mid 443.28978 -318.2913)
					(end 443.2808 -318.29502)
				)
				(arc
					(start 441.8076 -318.29502)
					(mid 441.79862 -318.2913)
					(end 441.7949 -318.28232)
				)
				(arc
					(start 441.7949 -317.787782)
					(mid 441.79862 -317.778802)
					(end 441.8076 -317.775082)
				)
				(arc
					(start 443.2808 -317.775082)
					(mid 443.28978 -317.778802)
					(end 443.2935 -317.787782)
				)
			)
		)
	)
	(zone
		(layer "In1.Cu")
		(hatch none 0.5)
		(connect_pads
			(clearance 0)
		)
		(min_thickness 0.25)
		(keepout
			(tracks not_allowed)
			(vias allowed)
			(pads allowed)
			(copperpour not_allowed)
			(footprints allowed)
		)
		(placement
			(enabled no)
			(sheetname "")
		)
		(fill
			(thermal_gap 0.5)
			(thermal_bridge_width 0.5)
			(island_removal_mode 0)
		)
		(polygon
			(pts
				(arc
					(start 40.98925 -248.582434)
					(mid 40.98553 -248.591414)
					(end 40.97655 -248.595134)
				)
				(arc
					(start 39.50335 -248.595134)
					(mid 39.49437 -248.591414)
					(end 39.49065 -248.582434)
				)
				(arc
					(start 39.49065 -248.087896)
					(mid 39.49437 -248.078916)
					(end 39.50335 -248.075196)
				)
				(arc
					(start 40.97655 -248.075196)
					(mid 40.98553 -248.078916)
					(end 40.98925 -248.087896)
				)
			)
		)
	)
	(zone
		(layer "In1.Cu")
		(hatch none 0.5)
		(connect_pads
			(clearance 0)
		)
		(min_thickness 0.25)
		(keepout
			(tracks not_allowed)
			(vias allowed)
			(pads allowed)
			(copperpour not_allowed)
			(footprints allowed)
		)
		(placement
			(enabled no)
			(sheetname "")
		)
		(fill
			(thermal_gap 0.5)
			(thermal_bridge_width 0.5)
			(island_removal_mode 0)
		)
		(polygon
			(pts
				(arc
					(start 184.365392 -240.932462)
					(mid 184.361672 -240.941442)
					(end 184.352692 -240.945162)
				)
				(arc
					(start 182.879492 -240.945162)
					(mid 182.870512 -240.941442)
					(end 182.866792 -240.932462)
				)
				(arc
					(start 182.866792 -240.437924)
					(mid 182.870512 -240.428944)
					(end 182.879492 -240.425224)
				)
				(arc
					(start 184.352692 -240.425224)
					(mid 184.361672 -240.428944)
					(end 184.365392 -240.437924)
				)
			)
		)
	)
	(zone
		(layer "In1.Cu")
		(hatch none 0.5)
		(connect_pads
			(clearance 0)
		)
		(min_thickness 0.25)
		(keepout
			(tracks not_allowed)
			(vias allowed)
			(pads allowed)
			(copperpour not_allowed)
			(footprints allowed)
		)
		(placement
			(enabled no)
			(sheetname "")
		)
		(fill
			(thermal_gap 0.5)
			(thermal_bridge_width 0.5)
			(island_removal_mode 0)
		)
		(polygon
			(pts
				(arc
					(start 56.077358 -302.982376)
					(mid 56.073638 -302.991356)
					(end 56.064658 -302.995076)
				)
				(arc
					(start 54.591458 -302.995076)
					(mid 54.582478 -302.991356)
					(end 54.578758 -302.982376)
				)
				(arc
					(start 54.578758 -302.487838)
					(mid 54.582478 -302.478858)
					(end 54.591458 -302.475138)
				)
				(arc
					(start 56.064658 -302.475138)
					(mid 56.073638 -302.478858)
					(end 56.077358 -302.487838)
				)
			)
		)
	)
	(zone
		(layer "In1.Cu")
		(hatch none 0.5)
		(connect_pads
			(clearance 0)
		)
		(min_thickness 0.25)
		(keepout
			(tracks not_allowed)
			(vias allowed)
			(pads allowed)
			(copperpour not_allowed)
			(footprints allowed)
		)
		(placement
			(enabled no)
			(sheetname "")
		)
		(fill
			(thermal_gap 0.5)
			(thermal_bridge_width 0.5)
			(island_removal_mode 0)
		)
		(polygon
			(pts
				(arc
					(start 187.809378 -221.382336)
					(mid 187.805658 -221.391316)
					(end 187.796678 -221.395036)
				)
				(arc
					(start 186.323478 -221.395036)
					(mid 186.314498 -221.391316)
					(end 186.310778 -221.382336)
				)
				(arc
					(start 186.310778 -220.887798)
					(mid 186.314498 -220.878818)
					(end 186.323478 -220.875098)
				)
				(arc
					(start 187.796678 -220.875098)
					(mid 187.805658 -220.878818)
					(end 187.809378 -220.887798)
				)
			)
		)
	)
	(zone
		(layer "In1.Cu")
		(hatch none 0.5)
		(connect_pads
			(clearance 0)
		)
		(min_thickness 0.25)
		(keepout
			(tracks not_allowed)
			(vias allowed)
			(pads allowed)
			(copperpour not_allowed)
			(footprints allowed)
		)
		(placement
			(enabled no)
			(sheetname "")
		)
		(fill
			(thermal_gap 0.5)
			(thermal_bridge_width 0.5)
			(island_removal_mode 0)
		)
		(polygon
			(pts
				(arc
					(start 308.117494 -219.682314)
					(mid 308.113774 -219.691294)
					(end 308.104794 -219.695014)
				)
				(arc
					(start 306.631594 -219.695014)
					(mid 306.622614 -219.691294)
					(end 306.618894 -219.682314)
				)
				(arc
					(start 306.618894 -219.187776)
					(mid 306.622614 -219.178796)
					(end 306.631594 -219.175076)
				)
				(arc
					(start 308.104794 -219.175076)
					(mid 308.113774 -219.178796)
					(end 308.117494 -219.187776)
				)
			)
		)
	)
	(zone
		(layer "In1.Cu")
		(hatch none 0.5)
		(connect_pads
			(clearance 0)
		)
		(min_thickness 0.25)
		(keepout
			(tracks not_allowed)
			(vias allowed)
			(pads allowed)
			(copperpour not_allowed)
			(footprints allowed)
		)
		(placement
			(enabled no)
			(sheetname "")
		)
		(fill
			(thermal_gap 0.5)
			(thermal_bridge_width 0.5)
			(island_removal_mode 0)
		)
		(polygon
			(pts
				(arc
					(start 424.761406 -289.3822)
					(mid 424.757686 -289.39118)
					(end 424.748706 -289.3949)
				)
				(arc
					(start 423.275506 -289.3949)
					(mid 423.266526 -289.39118)
					(end 423.262806 -289.3822)
				)
				(arc
					(start 423.262806 -288.887662)
					(mid 423.266526 -288.878682)
					(end 423.275506 -288.874962)
				)
				(arc
					(start 424.748706 -288.874962)
					(mid 424.757686 -288.878682)
					(end 424.761406 -288.887662)
				)
			)
		)
	)
	(zone
		(layer "In1.Cu")
		(hatch none 0.5)
		(connect_pads
			(clearance 0)
		)
		(min_thickness 0.25)
		(keepout
			(tracks not_allowed)
			(vias allowed)
			(pads allowed)
			(copperpour not_allowed)
			(footprints allowed)
		)
		(placement
			(enabled no)
			(sheetname "")
		)
		(fill
			(thermal_gap 0.5)
			(thermal_bridge_width 0.5)
			(island_removal_mode 0)
		)
		(polygon
			(pts
				(arc
					(start 447.393568 -211.182204)
					(mid 447.389848 -211.191184)
					(end 447.380868 -211.194904)
				)
				(arc
					(start 445.907668 -211.194904)
					(mid 445.898688 -211.191184)
					(end 445.894968 -211.182204)
				)
				(arc
					(start 445.894968 -210.687666)
					(mid 445.898688 -210.678686)
					(end 445.907668 -210.674966)
				)
				(arc
					(start 447.380868 -210.674966)
					(mid 447.389848 -210.678686)
					(end 447.393568 -210.687666)
				)
			)
		)
	)
	(zone
		(layer "In1.Cu")
		(hatch none 0.5)
		(connect_pads
			(clearance 0)
		)
		(min_thickness 0.25)
		(keepout
			(tracks not_allowed)
			(vias allowed)
			(pads allowed)
			(copperpour not_allowed)
			(footprints allowed)
		)
		(placement
			(enabled no)
			(sheetname "")
		)
		(fill
			(thermal_gap 0.5)
			(thermal_bridge_width 0.5)
			(island_removal_mode 0)
		)
		(polygon
			(pts
				(arc
					(start 450.8373 -248.58218)
					(mid 450.83358 -248.59116)
					(end 450.8246 -248.59488)
				)
				(arc
					(start 449.3514 -248.59488)
					(mid 449.34242 -248.59116)
					(end 449.3387 -248.58218)
				)
				(arc
					(start 449.3387 -248.087642)
					(mid 449.34242 -248.078662)
					(end 449.3514 -248.074942)
				)
				(arc
					(start 450.8246 -248.074942)
					(mid 450.83358 -248.078662)
					(end 450.8373 -248.087642)
				)
			)
		)
	)
	(zone
		(layer "In1.Cu")
		(hatch none 0.5)
		(connect_pads
			(clearance 0)
		)
		(min_thickness 0.25)
		(keepout
			(tracks not_allowed)
			(vias allowed)
			(pads allowed)
			(copperpour not_allowed)
			(footprints allowed)
		)
		(placement
			(enabled no)
			(sheetname "")
		)
		(fill
			(thermal_gap 0.5)
			(thermal_bridge_width 0.5)
			(island_removal_mode 0)
		)
		(polygon
			(pts
				(arc
					(start 296.473372 -202.682094)
					(mid 296.469652 -202.691074)
					(end 296.460672 -202.694794)
				)
				(arc
					(start 294.987472 -202.694794)
					(mid 294.978492 -202.691074)
					(end 294.974772 -202.682094)
				)
				(arc
					(start 294.974772 -202.187556)
					(mid 294.978492 -202.178576)
					(end 294.987472 -202.174856)
				)
				(arc
					(start 296.460672 -202.174856)
					(mid 296.469652 -202.178576)
					(end 296.473372 -202.187556)
				)
			)
		)
	)
	(zone
		(layer "In1.Cu")
		(hatch none 0.5)
		(connect_pads
			(clearance 0)
		)
		(min_thickness 0.25)
		(keepout
			(tracks not_allowed)
			(vias allowed)
			(pads allowed)
			(copperpour not_allowed)
			(footprints allowed)
		)
		(placement
			(enabled no)
			(sheetname "")
		)
		(fill
			(thermal_gap 0.5)
			(thermal_bridge_width 0.5)
			(island_removal_mode 0)
		)
		(polygon
			(pts
				(arc
					(start 52.633372 -252.832362)
					(mid 52.629652 -252.841342)
					(end 52.620672 -252.845062)
				)
				(arc
					(start 51.147472 -252.845062)
					(mid 51.138492 -252.841342)
					(end 51.134772 -252.832362)
				)
				(arc
					(start 51.134772 -252.337824)
					(mid 51.138492 -252.328844)
					(end 51.147472 -252.325124)
				)
				(arc
					(start 52.620672 -252.325124)
					(mid 52.629652 -252.328844)
					(end 52.633372 -252.337824)
				)
			)
		)
	)
	(zone
		(layer "In1.Cu")
		(hatch none 0.5)
		(connect_pads
			(clearance 0)
		)
		(min_thickness 0.25)
		(keepout
			(tracks not_allowed)
			(vias allowed)
			(pads allowed)
			(copperpour not_allowed)
			(footprints allowed)
		)
		(placement
			(enabled no)
			(sheetname "")
		)
		(fill
			(thermal_gap 0.5)
			(thermal_bridge_width 0.5)
			(island_removal_mode 0)
		)
		(polygon
			(pts
				(arc
					(start 300.57344 -240.932208)
					(mid 300.56972 -240.941188)
					(end 300.56074 -240.944908)
				)
				(arc
					(start 299.08754 -240.944908)
					(mid 299.07856 -240.941188)
					(end 299.07484 -240.932208)
				)
				(arc
					(start 299.07484 -240.43767)
					(mid 299.07856 -240.42869)
					(end 299.08754 -240.42497)
				)
				(arc
					(start 300.56074 -240.42497)
					(mid 300.56972 -240.42869)
					(end 300.57344 -240.43767)
				)
			)
		)
	)
	(zone
		(layer "In1.Cu")
		(hatch none 0.5)
		(connect_pads
			(clearance 0)
		)
		(min_thickness 0.25)
		(keepout
			(tracks not_allowed)
			(vias allowed)
			(pads allowed)
			(copperpour not_allowed)
			(footprints allowed)
		)
		(placement
			(enabled no)
			(sheetname "")
		)
		(fill
			(thermal_gap 0.5)
			(thermal_bridge_width 0.5)
			(island_removal_mode 0)
		)
		(polygon
			(pts
				(arc
					(start 45.089318 -314.032392)
					(mid 45.085598 -314.041372)
					(end 45.076618 -314.045092)
				)
				(arc
					(start 43.603418 -314.045092)
					(mid 43.594438 -314.041372)
					(end 43.590718 -314.032392)
				)
				(arc
					(start 43.590718 -313.537854)
					(mid 43.594438 -313.528874)
					(end 43.603418 -313.525154)
				)
				(arc
					(start 45.076618 -313.525154)
					(mid 45.085598 -313.528874)
					(end 45.089318 -313.537854)
				)
			)
		)
	)
	(zone
		(layer "In1.Cu")
		(hatch none 0.5)
		(connect_pads
			(clearance 0)
		)
		(min_thickness 0.25)
		(keepout
			(tracks not_allowed)
			(vias allowed)
			(pads allowed)
			(copperpour not_allowed)
			(footprints allowed)
		)
		(placement
			(enabled no)
			(sheetname "")
		)
		(fill
			(thermal_gap 0.5)
			(thermal_bridge_width 0.5)
			(island_removal_mode 0)
		)
		(polygon
			(pts
				(arc
					(start 375.760996 -394.385292)
					(mid 375.379996 -394.385292)
					(end 375.760996 -394.385292)
				)
			)
		)
	)
	(zone
		(layer "In1.Cu")
		(hatch none 0.5)
		(connect_pads
			(clearance 0)
		)
		(min_thickness 0.25)
		(keepout
			(tracks not_allowed)
			(vias allowed)
			(pads allowed)
			(copperpour not_allowed)
			(footprints allowed)
		)
		(placement
			(enabled no)
			(sheetname "")
		)
		(fill
			(thermal_gap 0.5)
			(thermal_bridge_width 0.5)
			(island_removal_mode 0)
		)
		(polygon
			(pts
				(arc
					(start 421.089074 -397.156432)
					(mid 420.708074 -397.156432)
					(end 421.089074 -397.156432)
				)
			)
		)
	)
	(zone
		(layer "In1.Cu")
		(hatch none 0.5)
		(connect_pads
			(clearance 0)
		)
		(min_thickness 0.25)
		(keepout
			(tracks not_allowed)
			(vias allowed)
			(pads allowed)
			(copperpour not_allowed)
			(footprints allowed)
		)
		(placement
			(enabled no)
			(sheetname "")
		)
		(fill
			(thermal_gap 0.5)
			(thermal_bridge_width 0.5)
			(island_removal_mode 0)
		)
		(polygon
			(pts
				(arc
					(start 195.353432 -224.78238)
					(mid 195.349712 -224.79136)
					(end 195.340732 -224.79508)
				)
				(arc
					(start 193.867532 -224.79508)
					(mid 193.858552 -224.79136)
					(end 193.854832 -224.78238)
				)
				(arc
					(start 193.854832 -224.287842)
					(mid 193.858552 -224.278862)
					(end 193.867532 -224.275142)
				)
				(arc
					(start 195.340732 -224.275142)
					(mid 195.349712 -224.278862)
					(end 195.353432 -224.287842)
				)
			)
		)
	)
	(zone
		(layer "In1.Cu")
		(hatch none 0.5)
		(connect_pads
			(clearance 0)
		)
		(min_thickness 0.25)
		(keepout
			(tracks not_allowed)
			(vias allowed)
			(pads allowed)
			(copperpour not_allowed)
			(footprints allowed)
		)
		(placement
			(enabled no)
			(sheetname "")
		)
		(fill
			(thermal_gap 0.5)
			(thermal_bridge_width 0.5)
			(island_removal_mode 0)
		)
		(polygon
			(pts
				(arc
					(start 199.4535 -229.032562)
					(mid 199.44978 -229.041542)
					(end 199.4408 -229.045262)
				)
				(arc
					(start 197.9676 -229.045262)
					(mid 197.95862 -229.041542)
					(end 197.9549 -229.032562)
				)
				(arc
					(start 197.9549 -228.538024)
					(mid 197.95862 -228.529044)
					(end 197.9676 -228.525324)
				)
				(arc
					(start 199.4408 -228.525324)
					(mid 199.44978 -228.529044)
					(end 199.4535 -228.538024)
				)
			)
		)
	)
	(zone
		(layer "In1.Cu")
		(hatch none 0.5)
		(connect_pads
			(clearance 0)
		)
		(min_thickness 0.25)
		(keepout
			(tracks not_allowed)
			(vias allowed)
			(pads allowed)
			(copperpour not_allowed)
			(footprints allowed)
		)
		(placement
			(enabled no)
			(sheetname "")
		)
		(fill
			(thermal_gap 0.5)
			(thermal_bridge_width 0.5)
			(island_removal_mode 0)
		)
		(polygon
			(pts
				(arc
					(start 199.4535 -268.13256)
					(mid 199.44978 -268.14154)
					(end 199.4408 -268.14526)
				)
				(arc
					(start 197.9676 -268.14526)
					(mid 197.95862 -268.14154)
					(end 197.9549 -268.13256)
				)
				(arc
					(start 197.9549 -267.638022)
					(mid 197.95862 -267.629042)
					(end 197.9676 -267.625322)
				)
				(arc
					(start 199.4408 -267.625322)
					(mid 199.44978 -267.629042)
					(end 199.4535 -267.638022)
				)
			)
		)
	)
	(zone
		(layer "In1.Cu")
		(hatch none 0.5)
		(connect_pads
			(clearance 0)
		)
		(min_thickness 0.25)
		(keepout
			(tracks not_allowed)
			(vias allowed)
			(pads allowed)
			(copperpour not_allowed)
			(footprints allowed)
		)
		(placement
			(enabled no)
			(sheetname "")
		)
		(fill
			(thermal_gap 0.5)
			(thermal_bridge_width 0.5)
			(island_removal_mode 0)
		)
		(polygon
			(pts
				(arc
					(start 52.633372 -269.832582)
					(mid 52.629652 -269.841562)
					(end 52.620672 -269.845282)
				)
				(arc
					(start 51.147472 -269.845282)
					(mid 51.138492 -269.841562)
					(end 51.134772 -269.832582)
				)
				(arc
					(start 51.134772 -269.338044)
					(mid 51.138492 -269.329064)
					(end 51.147472 -269.325344)
				)
				(arc
					(start 52.620672 -269.325344)
					(mid 52.629652 -269.329064)
					(end 52.633372 -269.338044)
				)
			)
		)
	)
	(zone
		(layer "In1.Cu")
		(hatch none 0.5)
		(connect_pads
			(clearance 0)
		)
		(min_thickness 0.25)
		(keepout
			(tracks not_allowed)
			(vias allowed)
			(pads allowed)
			(copperpour not_allowed)
			(footprints allowed)
		)
		(placement
			(enabled no)
			(sheetname "")
		)
		(fill
			(thermal_gap 0.5)
			(thermal_bridge_width 0.5)
			(island_removal_mode 0)
		)
		(polygon
			(pts
				(arc
					(start 285.485332 -304.682144)
					(mid 285.481612 -304.691124)
					(end 285.472632 -304.694844)
				)
				(arc
					(start 283.999432 -304.694844)
					(mid 283.990452 -304.691124)
					(end 283.986732 -304.682144)
				)
				(arc
					(start 283.986732 -304.187606)
					(mid 283.990452 -304.178626)
					(end 283.999432 -304.174906)
				)
				(arc
					(start 285.472632 -304.174906)
					(mid 285.481612 -304.178626)
					(end 285.485332 -304.187606)
				)
			)
		)
	)
	(zone
		(layer "In1.Cu")
		(hatch none 0.5)
		(connect_pads
			(clearance 0)
		)
		(min_thickness 0.25)
		(keepout
			(tracks not_allowed)
			(vias allowed)
			(pads allowed)
			(copperpour not_allowed)
			(footprints allowed)
		)
		(placement
			(enabled no)
			(sheetname "")
		)
		(fill
			(thermal_gap 0.5)
			(thermal_bridge_width 0.5)
			(island_removal_mode 0)
		)
		(polygon
			(pts
				(arc
					(start 93.918786 -383.440686)
					(mid 94.045786 -383.567686)
					(end 94.172786 -383.440686)
				)
				(arc
					(start 94.172786 -383.364486)
					(mid 94.045786 -383.237486)
					(end 93.918786 -383.364486)
				)
			)
		)
	)
	(zone
		(layer "In1.Cu")
		(hatch none 0.5)
		(connect_pads
			(clearance 0)
		)
		(min_thickness 0.25)
		(keepout
			(tracks not_allowed)
			(vias allowed)
			(pads allowed)
			(copperpour not_allowed)
			(footprints allowed)
		)
		(placement
			(enabled no)
			(sheetname "")
		)
		(fill
			(thermal_gap 0.5)
			(thermal_bridge_width 0.5)
			(island_removal_mode 0)
		)
		(polygon
			(pts
				(arc
					(start 415.089086 -397.156432)
					(mid 414.708086 -397.156432)
					(end 415.089086 -397.156432)
				)
			)
		)
	)
	(zone
		(layer "In1.Cu")
		(hatch none 0.5)
		(connect_pads
			(clearance 0)
		)
		(min_thickness 0.25)
		(keepout
			(tracks not_allowed)
			(vias allowed)
			(pads allowed)
			(copperpour not_allowed)
			(footprints allowed)
		)
		(placement
			(enabled no)
			(sheetname "")
		)
		(fill
			(thermal_gap 0.5)
			(thermal_bridge_width 0.5)
			(island_removal_mode 0)
		)
		(polygon
			(pts
				(arc
					(start 428.205392 -243.482114)
					(mid 428.201672 -243.491094)
					(end 428.192692 -243.494814)
				)
				(arc
					(start 426.719492 -243.494814)
					(mid 426.710512 -243.491094)
					(end 426.706792 -243.482114)
				)
				(arc
					(start 426.706792 -242.987576)
					(mid 426.710512 -242.978596)
					(end 426.719492 -242.974876)
				)
				(arc
					(start 428.192692 -242.974876)
					(mid 428.201672 -242.978596)
					(end 428.205392 -242.987576)
				)
			)
		)
	)
	(zone
		(layer "In1.Cu")
		(hatch none 0.5)
		(connect_pads
			(clearance 0)
		)
		(min_thickness 0.25)
		(keepout
			(tracks not_allowed)
			(vias allowed)
			(pads allowed)
			(copperpour not_allowed)
			(footprints allowed)
		)
		(placement
			(enabled no)
			(sheetname "")
		)
		(fill
			(thermal_gap 0.5)
			(thermal_bridge_width 0.5)
			(island_removal_mode 0)
		)
		(polygon
			(pts
				(arc
					(start 206.9973 -247.73255)
					(mid 206.99358 -247.74153)
					(end 206.9846 -247.74525)
				)
				(arc
					(start 205.5114 -247.74525)
					(mid 205.50242 -247.74153)
					(end 205.4987 -247.73255)
				)
				(arc
					(start 205.4987 -247.238012)
					(mid 205.50242 -247.229032)
					(end 205.5114 -247.225312)
				)
				(arc
					(start 206.9846 -247.225312)
					(mid 206.99358 -247.229032)
					(end 206.9973 -247.238012)
				)
			)
		)
	)
	(zone
		(layer "In1.Cu")
		(hatch none 0.5)
		(connect_pads
			(clearance 0)
		)
		(min_thickness 0.25)
		(keepout
			(tracks not_allowed)
			(vias allowed)
			(pads allowed)
			(copperpour not_allowed)
			(footprints allowed)
		)
		(placement
			(enabled no)
			(sheetname "")
		)
		(fill
			(thermal_gap 0.5)
			(thermal_bridge_width 0.5)
			(island_removal_mode 0)
		)
		(polygon
			(pts
				(arc
					(start 439.849514 -263.03224)
					(mid 439.845794 -263.04122)
					(end 439.836814 -263.04494)
				)
				(arc
					(start 438.363614 -263.04494)
					(mid 438.354634 -263.04122)
					(end 438.350914 -263.03224)
				)
				(arc
					(start 438.350914 -262.537702)
					(mid 438.354634 -262.528722)
					(end 438.363614 -262.525002)
				)
				(arc
					(start 439.836814 -262.525002)
					(mid 439.845794 -262.528722)
					(end 439.849514 -262.537702)
				)
			)
		)
	)
	(zone
		(layer "In1.Cu")
		(hatch none 0.5)
		(connect_pads
			(clearance 0)
		)
		(min_thickness 0.25)
		(keepout
			(tracks not_allowed)
			(vias allowed)
			(pads allowed)
			(copperpour not_allowed)
			(footprints allowed)
		)
		(placement
			(enabled no)
			(sheetname "")
		)
		(fill
			(thermal_gap 0.5)
			(thermal_bridge_width 0.5)
			(island_removal_mode 0)
		)
		(polygon
			(pts
				(arc
					(start 45.089318 -233.28249)
					(mid 45.085598 -233.29147)
					(end 45.076618 -233.29519)
				)
				(arc
					(start 43.603418 -233.29519)
					(mid 43.594438 -233.29147)
					(end 43.590718 -233.28249)
				)
				(arc
					(start 43.590718 -232.787952)
					(mid 43.594438 -232.778972)
					(end 43.603418 -232.775252)
				)
				(arc
					(start 45.076618 -232.775252)
					(mid 45.085598 -232.778972)
					(end 45.089318 -232.787952)
				)
			)
		)
	)
	(zone
		(layer "In1.Cu")
		(hatch none 0.5)
		(connect_pads
			(clearance 0)
		)
		(min_thickness 0.25)
		(keepout
			(tracks not_allowed)
			(vias allowed)
			(pads allowed)
			(copperpour not_allowed)
			(footprints allowed)
		)
		(placement
			(enabled no)
			(sheetname "")
		)
		(fill
			(thermal_gap 0.5)
			(thermal_bridge_width 0.5)
			(island_removal_mode 0)
		)
		(polygon
			(pts
				(arc
					(start 273.841464 -288.532316)
					(mid 273.837744 -288.541296)
					(end 273.828764 -288.545016)
				)
				(arc
					(start 272.355564 -288.545016)
					(mid 272.346584 -288.541296)
					(end 272.342864 -288.532316)
				)
				(arc
					(start 272.342864 -288.037778)
					(mid 272.346584 -288.028798)
					(end 272.355564 -288.025078)
				)
				(arc
					(start 273.828764 -288.025078)
					(mid 273.837744 -288.028798)
					(end 273.841464 -288.037778)
				)
			)
		)
	)
	(zone
		(layer "In1.Cu")
		(hatch none 0.5)
		(connect_pads
			(clearance 0)
		)
		(min_thickness 0.25)
		(keepout
			(tracks not_allowed)
			(vias allowed)
			(pads allowed)
			(copperpour not_allowed)
			(footprints allowed)
		)
		(placement
			(enabled no)
			(sheetname "")
		)
		(fill
			(thermal_gap 0.5)
			(thermal_bridge_width 0.5)
			(island_removal_mode 0)
		)
		(polygon
			(pts
				(arc
					(start 432.30546 -211.182204)
					(mid 432.30174 -211.191184)
					(end 432.29276 -211.194904)
				)
				(arc
					(start 430.81956 -211.194904)
					(mid 430.81058 -211.191184)
					(end 430.80686 -211.182204)
				)
				(arc
					(start 430.80686 -210.687666)
					(mid 430.81058 -210.678686)
					(end 430.81956 -210.674966)
				)
				(arc
					(start 432.29276 -210.674966)
					(mid 432.30174 -210.678686)
					(end 432.30546 -210.687666)
				)
			)
		)
	)
	(zone
		(layer "In1.Cu")
		(hatch none 0.5)
		(connect_pads
			(clearance 0)
		)
		(min_thickness 0.25)
		(keepout
			(tracks not_allowed)
			(vias allowed)
			(pads allowed)
			(copperpour not_allowed)
			(footprints allowed)
		)
		(placement
			(enabled no)
			(sheetname "")
		)
		(fill
			(thermal_gap 0.5)
			(thermal_bridge_width 0.5)
			(island_removal_mode 0)
		)
		(polygon
			(pts
				(arc
					(start 432.30546 -223.932242)
					(mid 432.30174 -223.941222)
					(end 432.29276 -223.944942)
				)
				(arc
					(start 430.81956 -223.944942)
					(mid 430.81058 -223.941222)
					(end 430.80686 -223.932242)
				)
				(arc
					(start 430.80686 -223.437704)
					(mid 430.81058 -223.428724)
					(end 430.81956 -223.425004)
				)
				(arc
					(start 432.29276 -223.425004)
					(mid 432.30174 -223.428724)
					(end 432.30546 -223.437704)
				)
			)
		)
	)
	(zone
		(layer "In1.Cu")
		(hatch none 0.5)
		(connect_pads
			(clearance 0)
		)
		(min_thickness 0.25)
		(keepout
			(tracks not_allowed)
			(vias allowed)
			(pads allowed)
			(copperpour not_allowed)
			(footprints allowed)
		)
		(placement
			(enabled no)
			(sheetname "")
		)
		(fill
			(thermal_gap 0.5)
			(thermal_bridge_width 0.5)
			(island_removal_mode 0)
		)
		(polygon
			(pts
				(arc
					(start 176.821338 -219.682568)
					(mid 176.817618 -219.691548)
					(end 176.808638 -219.695268)
				)
				(arc
					(start 175.335438 -219.695268)
					(mid 175.326458 -219.691548)
					(end 175.322738 -219.682568)
				)
				(arc
					(start 175.322738 -219.18803)
					(mid 175.326458 -219.17905)
					(end 175.335438 -219.17533)
				)
				(arc
					(start 176.808638 -219.17533)
					(mid 176.817618 -219.17905)
					(end 176.821338 -219.18803)
				)
			)
		)
	)
	(zone
		(layer "In1.Cu")
		(hatch none 0.5)
		(connect_pads
			(clearance 0)
		)
		(min_thickness 0.25)
		(keepout
			(tracks not_allowed)
			(vias allowed)
			(pads allowed)
			(copperpour not_allowed)
			(footprints allowed)
		)
		(placement
			(enabled no)
			(sheetname "")
		)
		(fill
			(thermal_gap 0.5)
			(thermal_bridge_width 0.5)
			(island_removal_mode 0)
		)
		(polygon
			(pts
				(arc
					(start 22.45741 -263.032494)
					(mid 22.45369 -263.041474)
					(end 22.44471 -263.045194)
				)
				(arc
					(start 20.97151 -263.045194)
					(mid 20.96253 -263.041474)
					(end 20.95881 -263.032494)
				)
				(arc
					(start 20.95881 -262.537956)
					(mid 20.96253 -262.528976)
					(end 20.97151 -262.525256)
				)
				(arc
					(start 22.44471 -262.525256)
					(mid 22.45369 -262.528976)
					(end 22.45741 -262.537956)
				)
			)
		)
	)
	(zone
		(layer "In1.Cu")
		(hatch none 0.5)
		(connect_pads
			(clearance 0)
		)
		(min_thickness 0.25)
		(keepout
			(tracks not_allowed)
			(vias allowed)
			(pads allowed)
			(copperpour not_allowed)
			(footprints allowed)
		)
		(placement
			(enabled no)
			(sheetname "")
		)
		(fill
			(thermal_gap 0.5)
			(thermal_bridge_width 0.5)
			(island_removal_mode 0)
		)
		(polygon
			(pts
				(arc
					(start 308.117494 -240.932208)
					(mid 308.113774 -240.941188)
					(end 308.104794 -240.944908)
				)
				(arc
					(start 306.631594 -240.944908)
					(mid 306.622614 -240.941188)
					(end 306.618894 -240.932208)
				)
				(arc
					(start 306.618894 -240.43767)
					(mid 306.622614 -240.42869)
					(end 306.631594 -240.42497)
				)
				(arc
					(start 308.104794 -240.42497)
					(mid 308.113774 -240.42869)
					(end 308.117494 -240.43767)
				)
			)
		)
	)
	(zone
		(layer "In1.Cu")
		(hatch none 0.5)
		(connect_pads
			(clearance 0)
		)
		(min_thickness 0.25)
		(keepout
			(tracks not_allowed)
			(vias allowed)
			(pads allowed)
			(copperpour not_allowed)
			(footprints allowed)
		)
		(placement
			(enabled no)
			(sheetname "")
		)
		(fill
			(thermal_gap 0.5)
			(thermal_bridge_width 0.5)
			(island_removal_mode 0)
		)
		(polygon
			(pts
				(arc
					(start 304.017426 -285.982156)
					(mid 304.013706 -285.991136)
					(end 304.004726 -285.994856)
				)
				(arc
					(start 302.531526 -285.994856)
					(mid 302.522546 -285.991136)
					(end 302.518826 -285.982156)
				)
				(arc
					(start 302.518826 -285.487618)
					(mid 302.522546 -285.478638)
					(end 302.531526 -285.474918)
				)
				(arc
					(start 304.004726 -285.474918)
					(mid 304.013706 -285.478638)
					(end 304.017426 -285.487618)
				)
			)
		)
	)
	(zone
		(layer "In1.Cu")
		(hatch none 0.5)
		(connect_pads
			(clearance 0)
		)
		(min_thickness 0.25)
		(keepout
			(tracks not_allowed)
			(vias allowed)
			(pads allowed)
			(copperpour not_allowed)
			(footprints allowed)
		)
		(placement
			(enabled no)
			(sheetname "")
		)
		(fill
			(thermal_gap 0.5)
			(thermal_bridge_width 0.5)
			(island_removal_mode 0)
		)
		(polygon
			(pts
				(arc
					(start 293.029386 -268.132306)
					(mid 293.025666 -268.141286)
					(end 293.016686 -268.145006)
				)
				(arc
					(start 291.543486 -268.145006)
					(mid 291.534506 -268.141286)
					(end 291.530786 -268.132306)
				)
				(arc
					(start 291.530786 -267.637768)
					(mid 291.534506 -267.628788)
					(end 291.543486 -267.625068)
				)
				(arc
					(start 293.016686 -267.625068)
					(mid 293.025666 -267.628788)
					(end 293.029386 -267.637768)
				)
			)
		)
	)
	(zone
		(layer "In1.Cu")
		(hatch none 0.5)
		(connect_pads
			(clearance 0)
		)
		(min_thickness 0.25)
		(keepout
			(tracks not_allowed)
			(vias allowed)
			(pads allowed)
			(copperpour not_allowed)
			(footprints allowed)
		)
		(placement
			(enabled no)
			(sheetname "")
		)
		(fill
			(thermal_gap 0.5)
			(thermal_bridge_width 0.5)
			(island_removal_mode 0)
		)
		(polygon
			(pts
				(arc
					(start 304.017426 -221.382082)
					(mid 304.013706 -221.391062)
					(end 304.004726 -221.394782)
				)
				(arc
					(start 302.531526 -221.394782)
					(mid 302.522546 -221.391062)
					(end 302.518826 -221.382082)
				)
				(arc
					(start 302.518826 -220.887544)
					(mid 302.522546 -220.878564)
					(end 302.531526 -220.874844)
				)
				(arc
					(start 304.004726 -220.874844)
					(mid 304.013706 -220.878564)
					(end 304.017426 -220.887544)
				)
			)
		)
	)
	(zone
		(layer "In1.Cu")
		(hatch none 0.5)
		(connect_pads
			(clearance 0)
		)
		(min_thickness 0.25)
		(keepout
			(tracks not_allowed)
			(vias allowed)
			(pads allowed)
			(copperpour not_allowed)
			(footprints allowed)
		)
		(placement
			(enabled no)
			(sheetname "")
		)
		(fill
			(thermal_gap 0.5)
			(thermal_bridge_width 0.5)
			(island_removal_mode 0)
		)
		(polygon
			(pts
				(arc
					(start 54.771544 -16.443198)
					(mid 54.793862 -16.49708)
					(end 54.847744 -16.519398)
				)
				(arc
					(start 55.043324 -16.519398)
					(mid 55.0652 -16.516266)
					(end 55.085234 -16.506952)
				)
				(arc
					(start 55.378858 -16.31442)
					(mid 55.420514 -16.302018)
					(end 55.46217 -16.31442)
				)
				(arc
					(start 55.757064 -16.506952)
					(mid 55.776988 -16.516188)
					(end 55.79872 -16.519398)
				)
				(arc
					(start 55.993284 -16.519398)
					(mid 56.047166 -16.49708)
					(end 56.069484 -16.443198)
				)
				(arc
					(start 56.069484 -15.757398)
					(mid 56.047166 -15.703516)
					(end 55.993284 -15.681198)
				)
				(arc
					(start 55.79872 -15.681198)
					(mid 55.776976 -15.684366)
					(end 55.757064 -15.693644)
				)
				(arc
					(start 55.4609 -15.88643)
					(mid 55.419216 -15.898652)
					(end 55.377588 -15.886176)
				)
				(arc
					(start 55.083964 -15.693644)
					(mid 55.06404 -15.684408)
					(end 55.042308 -15.681198)
				)
				(arc
					(start 54.847744 -15.681198)
					(mid 54.793862 -15.703516)
					(end 54.771544 -15.757398)
				)
			)
		)
	)
	(zone
		(layer "In1.Cu")
		(hatch none 0.5)
		(connect_pads
			(clearance 0)
		)
		(min_thickness 0.25)
		(keepout
			(tracks not_allowed)
			(vias allowed)
			(pads allowed)
			(copperpour not_allowed)
			(footprints allowed)
		)
		(placement
			(enabled no)
			(sheetname "")
		)
		(fill
			(thermal_gap 0.5)
			(thermal_bridge_width 0.5)
			(island_removal_mode 0)
		)
		(polygon
			(pts
				(arc
					(start 443.2935 -251.982224)
					(mid 443.28978 -251.991204)
					(end 443.2808 -251.994924)
				)
				(arc
					(start 441.8076 -251.994924)
					(mid 441.79862 -251.991204)
					(end 441.7949 -251.982224)
				)
				(arc
					(start 441.7949 -251.487686)
					(mid 441.79862 -251.478706)
					(end 441.8076 -251.474986)
				)
				(arc
					(start 443.2808 -251.474986)
					(mid 443.28978 -251.478706)
					(end 443.2935 -251.487686)
				)
			)
		)
	)
	(zone
		(layer "In1.Cu")
		(hatch none 0.5)
		(connect_pads
			(clearance 0)
		)
		(min_thickness 0.25)
		(keepout
			(tracks not_allowed)
			(vias allowed)
			(pads allowed)
			(copperpour not_allowed)
			(footprints allowed)
		)
		(placement
			(enabled no)
			(sheetname "")
		)
		(fill
			(thermal_gap 0.5)
			(thermal_bridge_width 0.5)
			(island_removal_mode 0)
		)
		(polygon
			(pts
				(arc
					(start 270.397478 -295.33215)
					(mid 270.393758 -295.34113)
					(end 270.384778 -295.34485)
				)
				(arc
					(start 268.911578 -295.34485)
					(mid 268.902598 -295.34113)
					(end 268.898878 -295.33215)
				)
				(arc
					(start 268.898878 -294.837612)
					(mid 268.902598 -294.828632)
					(end 268.911578 -294.824912)
				)
				(arc
					(start 270.384778 -294.824912)
					(mid 270.393758 -294.828632)
					(end 270.397478 -294.837612)
				)
			)
		)
	)
	(zone
		(layer "In1.Cu")
		(hatch none 0.5)
		(connect_pads
			(clearance 0)
		)
		(min_thickness 0.25)
		(keepout
			(tracks not_allowed)
			(vias allowed)
			(pads allowed)
			(copperpour not_allowed)
			(footprints allowed)
		)
		(placement
			(enabled no)
			(sheetname "")
		)
		(fill
			(thermal_gap 0.5)
			(thermal_bridge_width 0.5)
			(island_removal_mode 0)
		)
		(polygon
			(pts
				(arc
					(start 281.385264 -224.782126)
					(mid 281.381544 -224.791106)
					(end 281.372564 -224.794826)
				)
				(arc
					(start 279.899364 -224.794826)
					(mid 279.890384 -224.791106)
					(end 279.886664 -224.782126)
				)
				(arc
					(start 279.886664 -224.287588)
					(mid 279.890384 -224.278608)
					(end 279.899364 -224.274888)
				)
				(arc
					(start 281.372564 -224.274888)
					(mid 281.381544 -224.278608)
					(end 281.385264 -224.287588)
				)
			)
		)
	)
	(zone
		(layer "In1.Cu")
		(hatch none 0.5)
		(connect_pads
			(clearance 0)
		)
		(min_thickness 0.25)
		(keepout
			(tracks not_allowed)
			(vias allowed)
			(pads allowed)
			(copperpour not_allowed)
			(footprints allowed)
		)
		(placement
			(enabled no)
			(sheetname "")
		)
		(fill
			(thermal_gap 0.5)
			(thermal_bridge_width 0.5)
			(island_removal_mode 0)
		)
		(polygon
			(pts
				(arc
					(start 191.909446 -285.132526)
					(mid 191.905726 -285.141506)
					(end 191.896746 -285.145226)
				)
				(arc
					(start 190.423546 -285.145226)
					(mid 190.414566 -285.141506)
					(end 190.410846 -285.132526)
				)
				(arc
					(start 190.410846 -284.637988)
					(mid 190.414566 -284.629008)
					(end 190.423546 -284.625288)
				)
				(arc
					(start 191.896746 -284.625288)
					(mid 191.905726 -284.629008)
					(end 191.909446 -284.637988)
				)
			)
		)
	)
	(zone
		(layer "In1.Cu")
		(hatch none 0.5)
		(connect_pads
			(clearance 0)
		)
		(min_thickness 0.25)
		(keepout
			(tracks not_allowed)
			(vias allowed)
			(pads allowed)
			(copperpour not_allowed)
			(footprints allowed)
		)
		(placement
			(enabled no)
			(sheetname "")
		)
		(fill
			(thermal_gap 0.5)
			(thermal_bridge_width 0.5)
			(island_removal_mode 0)
		)
		(polygon
			(pts
				(arc
					(start 288.929318 -229.882192)
					(mid 288.925598 -229.891172)
					(end 288.916618 -229.894892)
				)
				(arc
					(start 287.443418 -229.894892)
					(mid 287.434438 -229.891172)
					(end 287.430718 -229.882192)
				)
				(arc
					(start 287.430718 -229.387654)
					(mid 287.434438 -229.378674)
					(end 287.443418 -229.374954)
				)
				(arc
					(start 288.916618 -229.374954)
					(mid 288.925598 -229.378674)
					(end 288.929318 -229.387654)
				)
			)
		)
	)
	(zone
		(layer "In1.Cu")
		(hatch none 0.5)
		(connect_pads
			(clearance 0)
		)
		(min_thickness 0.25)
		(keepout
			(tracks not_allowed)
			(vias allowed)
			(pads allowed)
			(copperpour not_allowed)
			(footprints allowed)
		)
		(placement
			(enabled no)
			(sheetname "")
		)
		(fill
			(thermal_gap 0.5)
			(thermal_bridge_width 0.5)
			(island_removal_mode 0)
		)
		(polygon
			(pts
				(arc
					(start 169.277284 -270.682466)
					(mid 169.273564 -270.691446)
					(end 169.264584 -270.695166)
				)
				(arc
					(start 167.791384 -270.695166)
					(mid 167.782404 -270.691446)
					(end 167.778684 -270.682466)
				)
				(arc
					(start 167.778684 -270.187928)
					(mid 167.782404 -270.178948)
					(end 167.791384 -270.175228)
				)
				(arc
					(start 169.264584 -270.175228)
					(mid 169.273564 -270.178948)
					(end 169.277284 -270.187928)
				)
			)
		)
	)
	(zone
		(layer "In1.Cu")
		(hatch none 0.5)
		(connect_pads
			(clearance 0)
		)
		(min_thickness 0.25)
		(keepout
			(tracks not_allowed)
			(vias allowed)
			(pads allowed)
			(copperpour not_allowed)
			(footprints allowed)
		)
		(placement
			(enabled no)
			(sheetname "")
		)
		(fill
			(thermal_gap 0.5)
			(thermal_bridge_width 0.5)
			(island_removal_mode 0)
		)
		(polygon
			(pts
				(arc
					(start 22.45741 -229.882446)
					(mid 22.45369 -229.891426)
					(end 22.44471 -229.895146)
				)
				(arc
					(start 20.97151 -229.895146)
					(mid 20.96253 -229.891426)
					(end 20.95881 -229.882446)
				)
				(arc
					(start 20.95881 -229.387908)
					(mid 20.96253 -229.378928)
					(end 20.97151 -229.375208)
				)
				(arc
					(start 22.44471 -229.375208)
					(mid 22.45369 -229.378928)
					(end 22.45741 -229.387908)
				)
			)
		)
	)
	(zone
		(layer "In1.Cu")
		(hatch none 0.5)
		(connect_pads
			(clearance 0)
		)
		(min_thickness 0.25)
		(keepout
			(tracks not_allowed)
			(vias allowed)
			(pads allowed)
			(copperpour not_allowed)
			(footprints allowed)
		)
		(placement
			(enabled no)
			(sheetname "")
		)
		(fill
			(thermal_gap 0.5)
			(thermal_bridge_width 0.5)
			(island_removal_mode 0)
		)
		(polygon
			(pts
				(arc
					(start 18.357342 -262.182356)
					(mid 18.353622 -262.191336)
					(end 18.344642 -262.195056)
				)
				(arc
					(start 16.871442 -262.195056)
					(mid 16.862462 -262.191336)
					(end 16.858742 -262.182356)
				)
				(arc
					(start 16.858742 -261.687818)
					(mid 16.862462 -261.678838)
					(end 16.871442 -261.675118)
				)
				(arc
					(start 18.344642 -261.675118)
					(mid 18.353622 -261.678838)
					(end 18.357342 -261.687818)
				)
			)
		)
	)
	(zone
		(layer "In1.Cu")
		(hatch none 0.5)
		(connect_pads
			(clearance 0)
		)
		(min_thickness 0.25)
		(keepout
			(tracks not_allowed)
			(vias allowed)
			(pads allowed)
			(copperpour not_allowed)
			(footprints allowed)
		)
		(placement
			(enabled no)
			(sheetname "")
		)
		(fill
			(thermal_gap 0.5)
			(thermal_bridge_width 0.5)
			(island_removal_mode 0)
		)
		(polygon
			(pts
				(arc
					(start 57.061354 -385.31038)
					(mid 56.680354 -385.31038)
					(end 57.061354 -385.31038)
				)
			)
		)
	)
	(zone
		(layer "In1.Cu")
		(hatch none 0.5)
		(connect_pads
			(clearance 0)
		)
		(min_thickness 0.25)
		(keepout
			(tracks not_allowed)
			(vias allowed)
			(pads allowed)
			(copperpour not_allowed)
			(footprints allowed)
		)
		(placement
			(enabled no)
			(sheetname "")
		)
		(fill
			(thermal_gap 0.5)
			(thermal_bridge_width 0.5)
			(island_removal_mode 0)
		)
		(polygon
			(pts
				(arc
					(start 25.901396 -280.882344)
					(mid 25.897676 -280.891324)
					(end 25.888696 -280.895044)
				)
				(arc
					(start 24.415496 -280.895044)
					(mid 24.406516 -280.891324)
					(end 24.402796 -280.882344)
				)
				(arc
					(start 24.402796 -280.387806)
					(mid 24.406516 -280.378826)
					(end 24.415496 -280.375106)
				)
				(arc
					(start 25.888696 -280.375106)
					(mid 25.897676 -280.378826)
					(end 25.901396 -280.387806)
				)
			)
		)
	)
	(zone
		(layer "In1.Cu")
		(hatch none 0.5)
		(connect_pads
			(clearance 0)
		)
		(min_thickness 0.25)
		(keepout
			(tracks not_allowed)
			(vias allowed)
			(pads allowed)
			(copperpour not_allowed)
			(footprints allowed)
		)
		(placement
			(enabled no)
			(sheetname "")
		)
		(fill
			(thermal_gap 0.5)
			(thermal_bridge_width 0.5)
			(island_removal_mode 0)
		)
		(polygon
			(pts
				(arc
					(start 199.4535 -285.98241)
					(mid 199.44978 -285.99139)
					(end 199.4408 -285.99511)
				)
				(arc
					(start 197.9676 -285.99511)
					(mid 197.95862 -285.99139)
					(end 197.9549 -285.98241)
				)
				(arc
					(start 197.9549 -285.487872)
					(mid 197.95862 -285.478892)
					(end 197.9676 -285.475172)
				)
				(arc
					(start 199.4408 -285.475172)
					(mid 199.44978 -285.478892)
					(end 199.4535 -285.487872)
				)
			)
		)
	)
	(zone
		(layer "In1.Cu")
		(hatch none 0.5)
		(connect_pads
			(clearance 0)
		)
		(min_thickness 0.25)
		(keepout
			(tracks not_allowed)
			(vias allowed)
			(pads allowed)
			(copperpour not_allowed)
			(footprints allowed)
		)
		(placement
			(enabled no)
			(sheetname "")
		)
		(fill
			(thermal_gap 0.5)
			(thermal_bridge_width 0.5)
			(island_removal_mode 0)
		)
		(polygon
			(pts
				(arc
					(start 56.077358 -304.682398)
					(mid 56.073638 -304.691378)
					(end 56.064658 -304.695098)
				)
				(arc
					(start 54.591458 -304.695098)
					(mid 54.582478 -304.691378)
					(end 54.578758 -304.682398)
				)
				(arc
					(start 54.578758 -304.18786)
					(mid 54.582478 -304.17888)
					(end 54.591458 -304.17516)
				)
				(arc
					(start 56.064658 -304.17516)
					(mid 56.073638 -304.17888)
					(end 56.077358 -304.18786)
				)
			)
		)
	)
	(zone
		(layer "In1.Cu")
		(hatch none 0.5)
		(connect_pads
			(clearance 0)
		)
		(min_thickness 0.25)
		(keepout
			(tracks not_allowed)
			(vias allowed)
			(pads allowed)
			(copperpour not_allowed)
			(footprints allowed)
		)
		(placement
			(enabled no)
			(sheetname "")
		)
		(fill
			(thermal_gap 0.5)
			(thermal_bridge_width 0.5)
			(island_removal_mode 0)
		)
		(polygon
			(pts
				(arc
					(start 417.217352 -225.632264)
					(mid 417.213632 -225.641244)
					(end 417.204652 -225.644964)
				)
				(arc
					(start 415.731452 -225.644964)
					(mid 415.722472 -225.641244)
					(end 415.718752 -225.632264)
				)
				(arc
					(start 415.718752 -225.137726)
					(mid 415.722472 -225.128746)
					(end 415.731452 -225.125026)
				)
				(arc
					(start 417.204652 -225.125026)
					(mid 417.213632 -225.128746)
					(end 417.217352 -225.137726)
				)
			)
		)
	)
	(zone
		(layer "In1.Cu")
		(hatch none 0.5)
		(connect_pads
			(clearance 0)
		)
		(min_thickness 0.25)
		(keepout
			(tracks not_allowed)
			(vias allowed)
			(pads allowed)
			(copperpour not_allowed)
			(footprints allowed)
		)
		(placement
			(enabled no)
			(sheetname "")
		)
		(fill
			(thermal_gap 0.5)
			(thermal_bridge_width 0.5)
			(island_removal_mode 0)
		)
		(polygon
			(pts
				(arc
					(start 60.177426 -311.482486)
					(mid 60.173706 -311.491466)
					(end 60.164726 -311.495186)
				)
				(arc
					(start 58.691526 -311.495186)
					(mid 58.682546 -311.491466)
					(end 58.678826 -311.482486)
				)
				(arc
					(start 58.678826 -310.987948)
					(mid 58.682546 -310.978968)
					(end 58.691526 -310.975248)
				)
				(arc
					(start 60.164726 -310.975248)
					(mid 60.173706 -310.978968)
					(end 60.177426 -310.987948)
				)
			)
		)
	)
	(zone
		(layer "In1.Cu")
		(hatch none 0.5)
		(connect_pads
			(clearance 0)
		)
		(min_thickness 0.25)
		(keepout
			(tracks not_allowed)
			(vias allowed)
			(pads allowed)
			(copperpour not_allowed)
			(footprints allowed)
		)
		(placement
			(enabled no)
			(sheetname "")
		)
		(fill
			(thermal_gap 0.5)
			(thermal_bridge_width 0.5)
			(island_removal_mode 0)
		)
		(polygon
			(pts
				(arc
					(start 52.633372 -249.432572)
					(mid 52.629652 -249.441552)
					(end 52.620672 -249.445272)
				)
				(arc
					(start 51.147472 -249.445272)
					(mid 51.138492 -249.441552)
					(end 51.134772 -249.432572)
				)
				(arc
					(start 51.134772 -248.938034)
					(mid 51.138492 -248.929054)
					(end 51.147472 -248.925334)
				)
				(arc
					(start 52.620672 -248.925334)
					(mid 52.629652 -248.929054)
					(end 52.633372 -248.938034)
				)
			)
		)
	)
	(zone
		(layer "In1.Cu")
		(hatch none 0.5)
		(connect_pads
			(clearance 0)
		)
		(min_thickness 0.25)
		(keepout
			(tracks not_allowed)
			(vias allowed)
			(pads allowed)
			(copperpour not_allowed)
			(footprints allowed)
		)
		(placement
			(enabled no)
			(sheetname "")
		)
		(fill
			(thermal_gap 0.5)
			(thermal_bridge_width 0.5)
			(island_removal_mode 0)
		)
		(polygon
			(pts
				(arc
					(start 33.307528 -426.148246)
					(mid 33.292649 -426.184167)
					(end 33.256728 -426.199046)
				)
				(arc
					(start 32.748728 -426.199046)
					(mid 32.712807 -426.184167)
					(end 32.697928 -426.148246)
				)
				(arc
					(start 32.697928 -425.671996)
					(mid 32.712807 -425.636075)
					(end 32.748728 -425.621196)
				)
				(arc
					(start 33.256728 -425.621196)
					(mid 33.292649 -425.636075)
					(end 33.307528 -425.671996)
				)
			)
		)
	)
	(zone
		(layer "In1.Cu")
		(hatch none 0.5)
		(connect_pads
			(clearance 0)
		)
		(min_thickness 0.25)
		(keepout
			(tracks not_allowed)
			(vias allowed)
			(pads allowed)
			(copperpour not_allowed)
			(footprints allowed)
		)
		(placement
			(enabled no)
			(sheetname "")
		)
		(fill
			(thermal_gap 0.5)
			(thermal_bridge_width 0.5)
			(island_removal_mode 0)
		)
		(polygon
			(pts
				(arc
					(start 281.385264 -235.832142)
					(mid 281.381544 -235.841122)
					(end 281.372564 -235.844842)
				)
				(arc
					(start 279.899364 -235.844842)
					(mid 279.890384 -235.841122)
					(end 279.886664 -235.832142)
				)
				(arc
					(start 279.886664 -235.337604)
					(mid 279.890384 -235.328624)
					(end 279.899364 -235.324904)
				)
				(arc
					(start 281.372564 -235.324904)
					(mid 281.381544 -235.328624)
					(end 281.385264 -235.337604)
				)
			)
		)
	)
	(zone
		(layer "In1.Cu")
		(hatch none 0.5)
		(connect_pads
			(clearance 0)
		)
		(min_thickness 0.25)
		(keepout
			(tracks not_allowed)
			(vias allowed)
			(pads allowed)
			(copperpour not_allowed)
			(footprints allowed)
		)
		(placement
			(enabled no)
			(sheetname "")
		)
		(fill
			(thermal_gap 0.5)
			(thermal_bridge_width 0.5)
			(island_removal_mode 0)
		)
		(polygon
			(pts
				(arc
					(start 33.445196 -314.88253)
					(mid 33.441476 -314.89151)
					(end 33.432496 -314.89523)
				)
				(arc
					(start 31.959296 -314.89523)
					(mid 31.950316 -314.89151)
					(end 31.946596 -314.88253)
				)
				(arc
					(start 31.946596 -314.387992)
					(mid 31.950316 -314.379012)
					(end 31.959296 -314.375292)
				)
				(arc
					(start 33.432496 -314.375292)
					(mid 33.441476 -314.379012)
					(end 33.445196 -314.387992)
				)
			)
		)
	)
	(zone
		(layer "In1.Cu")
		(hatch none 0.5)
		(connect_pads
			(clearance 0)
		)
		(min_thickness 0.25)
		(keepout
			(tracks not_allowed)
			(vias allowed)
			(pads allowed)
			(copperpour not_allowed)
			(footprints allowed)
		)
		(placement
			(enabled no)
			(sheetname "")
		)
		(fill
			(thermal_gap 0.5)
			(thermal_bridge_width 0.5)
			(island_removal_mode 0)
		)
		(polygon
			(pts
				(arc
					(start 266.29741 -250.282202)
					(mid 266.29369 -250.291182)
					(end 266.28471 -250.294902)
				)
				(arc
					(start 264.81151 -250.294902)
					(mid 264.80253 -250.291182)
					(end 264.79881 -250.282202)
				)
				(arc
					(start 264.79881 -249.787664)
					(mid 264.80253 -249.778684)
					(end 264.81151 -249.774964)
				)
				(arc
					(start 266.28471 -249.774964)
					(mid 266.29369 -249.778684)
					(end 266.29741 -249.787664)
				)
			)
		)
	)
	(zone
		(layer "In1.Cu")
		(hatch none 0.5)
		(connect_pads
			(clearance 0)
		)
		(min_thickness 0.25)
		(keepout
			(tracks not_allowed)
			(vias allowed)
			(pads allowed)
			(copperpour not_allowed)
			(footprints allowed)
		)
		(placement
			(enabled no)
			(sheetname "")
		)
		(fill
			(thermal_gap 0.5)
			(thermal_bridge_width 0.5)
			(island_removal_mode 0)
		)
		(polygon
			(pts
				(arc
					(start 169.277284 -247.73255)
					(mid 169.273564 -247.74153)
					(end 169.264584 -247.74525)
				)
				(arc
					(start 167.791384 -247.74525)
					(mid 167.782404 -247.74153)
					(end 167.778684 -247.73255)
				)
				(arc
					(start 167.778684 -247.238012)
					(mid 167.782404 -247.229032)
					(end 167.791384 -247.225312)
				)
				(arc
					(start 169.264584 -247.225312)
					(mid 169.273564 -247.229032)
					(end 169.277284 -247.238012)
				)
			)
		)
	)
	(zone
		(layer "In1.Cu")
		(hatch none 0.5)
		(connect_pads
			(clearance 0)
		)
		(min_thickness 0.25)
		(keepout
			(tracks not_allowed)
			(vias allowed)
			(pads allowed)
			(copperpour not_allowed)
			(footprints allowed)
		)
		(placement
			(enabled no)
			(sheetname "")
		)
		(fill
			(thermal_gap 0.5)
			(thermal_bridge_width 0.5)
			(island_removal_mode 0)
		)
		(polygon
			(pts
				(arc
					(start 45.089318 -287.682432)
					(mid 45.085598 -287.691412)
					(end 45.076618 -287.695132)
				)
				(arc
					(start 43.603418 -287.695132)
					(mid 43.594438 -287.691412)
					(end 43.590718 -287.682432)
				)
				(arc
					(start 43.590718 -287.187894)
					(mid 43.594438 -287.178914)
					(end 43.603418 -287.175194)
				)
				(arc
					(start 45.076618 -287.175194)
					(mid 45.085598 -287.178914)
					(end 45.089318 -287.187894)
				)
			)
		)
	)
	(zone
		(layer "In1.Cu")
		(hatch none 0.5)
		(connect_pads
			(clearance 0)
		)
		(min_thickness 0.25)
		(keepout
			(tracks not_allowed)
			(vias allowed)
			(pads allowed)
			(copperpour not_allowed)
			(footprints allowed)
		)
		(placement
			(enabled no)
			(sheetname "")
		)
		(fill
			(thermal_gap 0.5)
			(thermal_bridge_width 0.5)
			(island_removal_mode 0)
		)
		(polygon
			(pts
				(arc
					(start 300.57344 -229.032308)
					(mid 300.56972 -229.041288)
					(end 300.56074 -229.045008)
				)
				(arc
					(start 299.08754 -229.045008)
					(mid 299.07856 -229.041288)
					(end 299.07484 -229.032308)
				)
				(arc
					(start 299.07484 -228.53777)
					(mid 299.07856 -228.52879)
					(end 299.08754 -228.52507)
				)
				(arc
					(start 300.56074 -228.52507)
					(mid 300.56972 -228.52879)
					(end 300.57344 -228.53777)
				)
			)
		)
	)
	(zone
		(layer "In1.Cu")
		(hatch none 0.5)
		(connect_pads
			(clearance 0)
		)
		(min_thickness 0.25)
		(keepout
			(tracks not_allowed)
			(vias allowed)
			(pads allowed)
			(copperpour not_allowed)
			(footprints allowed)
		)
		(placement
			(enabled no)
			(sheetname "")
		)
		(fill
			(thermal_gap 0.5)
			(thermal_bridge_width 0.5)
			(island_removal_mode 0)
		)
		(polygon
			(pts
				(arc
					(start 281.385264 -211.182204)
					(mid 281.381544 -211.191184)
					(end 281.372564 -211.194904)
				)
				(arc
					(start 279.899364 -211.194904)
					(mid 279.890384 -211.191184)
					(end 279.886664 -211.182204)
				)
				(arc
					(start 279.886664 -210.687666)
					(mid 279.890384 -210.678686)
					(end 279.899364 -210.674966)
				)
				(arc
					(start 281.372564 -210.674966)
					(mid 281.381544 -210.678686)
					(end 281.385264 -210.687666)
				)
			)
		)
	)
	(zone
		(layer "In1.Cu")
		(hatch none 0.5)
		(connect_pads
			(clearance 0)
		)
		(min_thickness 0.25)
		(keepout
			(tracks not_allowed)
			(vias allowed)
			(pads allowed)
			(copperpour not_allowed)
			(footprints allowed)
		)
		(placement
			(enabled no)
			(sheetname "")
		)
		(fill
			(thermal_gap 0.5)
			(thermal_bridge_width 0.5)
			(island_removal_mode 0)
		)
		(polygon
			(pts
				(arc
					(start 202.897232 -217.132408)
					(mid 202.893512 -217.141388)
					(end 202.884532 -217.145108)
				)
				(arc
					(start 201.411332 -217.145108)
					(mid 201.402352 -217.141388)
					(end 201.398632 -217.132408)
				)
				(arc
					(start 201.398632 -216.63787)
					(mid 201.402352 -216.62889)
					(end 201.411332 -216.62517)
				)
				(arc
					(start 202.884532 -216.62517)
					(mid 202.893512 -216.62889)
					(end 202.897232 -216.63787)
				)
			)
		)
	)
	(zone
		(layer "In1.Cu")
		(hatch none 0.5)
		(connect_pads
			(clearance 0)
		)
		(min_thickness 0.25)
		(keepout
			(tracks not_allowed)
			(vias allowed)
			(pads allowed)
			(copperpour not_allowed)
			(footprints allowed)
		)
		(placement
			(enabled no)
			(sheetname "")
		)
		(fill
			(thermal_gap 0.5)
			(thermal_bridge_width 0.5)
			(island_removal_mode 0)
		)
		(polygon
			(pts
				(arc
					(start 37.545264 -220.532452)
					(mid 37.541544 -220.541432)
					(end 37.532564 -220.545152)
				)
				(arc
					(start 36.059364 -220.545152)
					(mid 36.050384 -220.541432)
					(end 36.046664 -220.532452)
				)
				(arc
					(start 36.046664 -220.037914)
					(mid 36.050384 -220.028934)
					(end 36.059364 -220.025214)
				)
				(arc
					(start 37.532564 -220.025214)
					(mid 37.541544 -220.028934)
					(end 37.545264 -220.037914)
				)
			)
		)
	)
	(zone
		(layer "In1.Cu")
		(hatch none 0.5)
		(connect_pads
			(clearance 0)
		)
		(min_thickness 0.25)
		(keepout
			(tracks not_allowed)
			(vias allowed)
			(pads allowed)
			(copperpour not_allowed)
			(footprints allowed)
		)
		(placement
			(enabled no)
			(sheetname "")
		)
		(fill
			(thermal_gap 0.5)
			(thermal_bridge_width 0.5)
			(island_removal_mode 0)
		)
		(polygon
			(pts
				(arc
					(start 377.291092 -399.701258)
					(mid 377.418092 -399.828258)
					(end 377.545092 -399.701258)
				)
				(arc
					(start 377.545092 -399.625058)
					(mid 377.418092 -399.498058)
					(end 377.291092 -399.625058)
				)
			)
		)
	)
	(zone
		(layer "In1.Cu")
		(hatch none 0.5)
		(connect_pads
			(clearance 0)
		)
		(min_thickness 0.25)
		(keepout
			(tracks not_allowed)
			(vias allowed)
			(pads allowed)
			(copperpour not_allowed)
			(footprints allowed)
		)
		(placement
			(enabled no)
			(sheetname "")
		)
		(fill
			(thermal_gap 0.5)
			(thermal_bridge_width 0.5)
			(island_removal_mode 0)
		)
		(polygon
			(pts
				(arc
					(start 347.801184 -294.031162)
					(mid 347.496384 -294.335962)
					(end 347.801184 -294.640762)
				)
				(arc
					(start 348.741238 -294.640762)
					(mid 349.046038 -294.335962)
					(end 348.741238 -294.031162)
				)
			)
		)
	)
	(zone
		(layer "In1.Cu")
		(hatch none 0.5)
		(connect_pads
			(clearance 0)
		)
		(min_thickness 0.25)
		(keepout
			(tracks not_allowed)
			(vias allowed)
			(pads allowed)
			(copperpour not_allowed)
			(footprints allowed)
		)
		(placement
			(enabled no)
			(sheetname "")
		)
		(fill
			(thermal_gap 0.5)
			(thermal_bridge_width 0.5)
			(island_removal_mode 0)
		)
		(polygon
			(pts
				(arc
					(start 420.661338 -221.382082)
					(mid 420.657618 -221.391062)
					(end 420.648638 -221.394782)
				)
				(arc
					(start 419.175438 -221.394782)
					(mid 419.166458 -221.391062)
					(end 419.162738 -221.382082)
				)
				(arc
					(start 419.162738 -220.887544)
					(mid 419.166458 -220.878564)
					(end 419.175438 -220.874844)
				)
				(arc
					(start 420.648638 -220.874844)
					(mid 420.657618 -220.878564)
					(end 420.661338 -220.887544)
				)
			)
		)
	)
	(zone
		(layer "In1.Cu")
		(hatch none 0.5)
		(connect_pads
			(clearance 0)
		)
		(min_thickness 0.25)
		(keepout
			(tracks not_allowed)
			(vias allowed)
			(pads allowed)
			(copperpour not_allowed)
			(footprints allowed)
		)
		(placement
			(enabled no)
			(sheetname "")
		)
		(fill
			(thermal_gap 0.5)
			(thermal_bridge_width 0.5)
			(island_removal_mode 0)
		)
		(polygon
			(pts
				(arc
					(start 285.485332 -222.23222)
					(mid 285.481612 -222.2412)
					(end 285.472632 -222.24492)
				)
				(arc
					(start 283.999432 -222.24492)
					(mid 283.990452 -222.2412)
					(end 283.986732 -222.23222)
				)
				(arc
					(start 283.986732 -221.737682)
					(mid 283.990452 -221.728702)
					(end 283.999432 -221.724982)
				)
				(arc
					(start 285.472632 -221.724982)
					(mid 285.481612 -221.728702)
					(end 285.485332 -221.737682)
				)
			)
		)
	)
	(zone
		(layer "In1.Cu")
		(hatch none 0.5)
		(connect_pads
			(clearance 0)
		)
		(min_thickness 0.25)
		(keepout
			(tracks not_allowed)
			(vias allowed)
			(pads allowed)
			(copperpour not_allowed)
			(footprints allowed)
		)
		(placement
			(enabled no)
			(sheetname "")
		)
		(fill
			(thermal_gap 0.5)
			(thermal_bridge_width 0.5)
			(island_removal_mode 0)
		)
		(polygon
			(pts
				(arc
					(start 304.017426 -212.032088)
					(mid 304.013706 -212.041068)
					(end 304.004726 -212.044788)
				)
				(arc
					(start 302.531526 -212.044788)
					(mid 302.522546 -212.041068)
					(end 302.518826 -212.032088)
				)
				(arc
					(start 302.518826 -211.53755)
					(mid 302.522546 -211.52857)
					(end 302.531526 -211.52485)
				)
				(arc
					(start 304.004726 -211.52485)
					(mid 304.013706 -211.52857)
					(end 304.017426 -211.53755)
				)
			)
		)
	)
	(zone
		(layer "In1.Cu")
		(hatch none 0.5)
		(connect_pads
			(clearance 0)
		)
		(min_thickness 0.25)
		(keepout
			(tracks not_allowed)
			(vias allowed)
			(pads allowed)
			(copperpour not_allowed)
			(footprints allowed)
		)
		(placement
			(enabled no)
			(sheetname "")
		)
		(fill
			(thermal_gap 0.5)
			(thermal_bridge_width 0.5)
			(island_removal_mode 0)
		)
		(polygon
			(pts
				(arc
					(start 270.397478 -269.832328)
					(mid 270.393758 -269.841308)
					(end 270.384778 -269.845028)
				)
				(arc
					(start 268.911578 -269.845028)
					(mid 268.902598 -269.841308)
					(end 268.898878 -269.832328)
				)
				(arc
					(start 268.898878 -269.33779)
					(mid 268.902598 -269.32881)
					(end 268.911578 -269.32509)
				)
				(arc
					(start 270.384778 -269.32509)
					(mid 270.393758 -269.32881)
					(end 270.397478 -269.33779)
				)
			)
		)
	)
	(zone
		(layer "In1.Cu")
		(hatch none 0.5)
		(connect_pads
			(clearance 0)
		)
		(min_thickness 0.25)
		(keepout
			(tracks not_allowed)
			(vias allowed)
			(pads allowed)
			(copperpour not_allowed)
			(footprints allowed)
		)
		(placement
			(enabled no)
			(sheetname "")
		)
		(fill
			(thermal_gap 0.5)
			(thermal_bridge_width 0.5)
			(island_removal_mode 0)
		)
		(polygon
			(pts
				(arc
					(start 187.809378 -302.982376)
					(mid 187.805658 -302.991356)
					(end 187.796678 -302.995076)
				)
				(arc
					(start 186.323478 -302.995076)
					(mid 186.314498 -302.991356)
					(end 186.310778 -302.982376)
				)
				(arc
					(start 186.310778 -302.487838)
					(mid 186.314498 -302.478858)
					(end 186.323478 -302.475138)
				)
				(arc
					(start 187.796678 -302.475138)
					(mid 187.805658 -302.478858)
					(end 187.809378 -302.487838)
				)
			)
		)
	)
	(zone
		(layer "In1.Cu")
		(hatch none 0.5)
		(connect_pads
			(clearance 0)
		)
		(min_thickness 0.25)
		(keepout
			(tracks not_allowed)
			(vias allowed)
			(pads allowed)
			(copperpour not_allowed)
			(footprints allowed)
		)
		(placement
			(enabled no)
			(sheetname "")
		)
		(fill
			(thermal_gap 0.5)
			(thermal_bridge_width 0.5)
			(island_removal_mode 0)
		)
		(polygon
			(pts
				(arc
					(start 304.017426 -230.73233)
					(mid 304.013706 -230.74131)
					(end 304.004726 -230.74503)
				)
				(arc
					(start 302.531526 -230.74503)
					(mid 302.522546 -230.74131)
					(end 302.518826 -230.73233)
				)
				(arc
					(start 302.518826 -230.237792)
					(mid 302.522546 -230.228812)
					(end 302.531526 -230.225092)
				)
				(arc
					(start 304.004726 -230.225092)
					(mid 304.013706 -230.228812)
					(end 304.017426 -230.237792)
				)
			)
		)
	)
	(zone
		(layer "In1.Cu")
		(hatch none 0.5)
		(connect_pads
			(clearance 0)
		)
		(min_thickness 0.25)
		(keepout
			(tracks not_allowed)
			(vias allowed)
			(pads allowed)
			(copperpour not_allowed)
			(footprints allowed)
		)
		(placement
			(enabled no)
			(sheetname "")
		)
		(fill
			(thermal_gap 0.5)
			(thermal_bridge_width 0.5)
			(island_removal_mode 0)
		)
		(polygon
			(pts
				(arc
					(start 377.761246 -393.69238)
					(mid 377.380246 -393.69238)
					(end 377.761246 -393.69238)
				)
			)
		)
	)
	(zone
		(layer "In1.Cu")
		(hatch none 0.5)
		(connect_pads
			(clearance 0)
		)
		(min_thickness 0.25)
		(keepout
			(tracks not_allowed)
			(vias allowed)
			(pads allowed)
			(copperpour not_allowed)
			(footprints allowed)
		)
		(placement
			(enabled no)
			(sheetname "")
		)
		(fill
			(thermal_gap 0.5)
			(thermal_bridge_width 0.5)
			(island_removal_mode 0)
		)
		(polygon
			(pts
				(arc
					(start 454.937368 -281.732228)
					(mid 454.933648 -281.741208)
					(end 454.924668 -281.744928)
				)
				(arc
					(start 453.451468 -281.744928)
					(mid 453.442488 -281.741208)
					(end 453.438768 -281.732228)
				)
				(arc
					(start 453.438768 -281.23769)
					(mid 453.442488 -281.22871)
					(end 453.451468 -281.22499)
				)
				(arc
					(start 454.924668 -281.22499)
					(mid 454.933648 -281.22871)
					(end 454.937368 -281.23769)
				)
			)
		)
	)
	(zone
		(layer "In1.Cu")
		(hatch none 0.5)
		(connect_pads
			(clearance 0)
		)
		(min_thickness 0.25)
		(keepout
			(tracks not_allowed)
			(vias allowed)
			(pads allowed)
			(copperpour not_allowed)
			(footprints allowed)
		)
		(placement
			(enabled no)
			(sheetname "")
		)
		(fill
			(thermal_gap 0.5)
			(thermal_bridge_width 0.5)
			(island_removal_mode 0)
		)
		(polygon
			(pts
				(arc
					(start 285.485332 -276.632162)
					(mid 285.481612 -276.641142)
					(end 285.472632 -276.644862)
				)
				(arc
					(start 283.999432 -276.644862)
					(mid 283.990452 -276.641142)
					(end 283.986732 -276.632162)
				)
				(arc
					(start 283.986732 -276.137624)
					(mid 283.990452 -276.128644)
					(end 283.999432 -276.124924)
				)
				(arc
					(start 285.472632 -276.124924)
					(mid 285.481612 -276.128644)
					(end 285.485332 -276.137624)
				)
			)
		)
	)
	(zone
		(layer "In1.Cu")
		(hatch none 0.5)
		(connect_pads
			(clearance 0)
		)
		(min_thickness 0.25)
		(keepout
			(tracks not_allowed)
			(vias allowed)
			(pads allowed)
			(copperpour not_allowed)
			(footprints allowed)
		)
		(placement
			(enabled no)
			(sheetname "")
		)
		(fill
			(thermal_gap 0.5)
			(thermal_bridge_width 0.5)
			(island_removal_mode 0)
		)
		(polygon
			(pts
				(arc
					(start 352.732848 -381.824484)
					(mid 352.752772 -381.83372)
					(end 352.774504 -381.83693)
				)
				(arc
					(start 352.969068 -381.83693)
					(mid 353.02295 -381.814612)
					(end 353.045268 -381.76073)
				)
				(arc
					(start 353.045268 -381.07493)
					(mid 353.02295 -381.021048)
					(end 352.969068 -380.99873)
				)
				(arc
					(start 352.774504 -380.99873)
					(mid 352.75276 -381.001898)
					(end 352.732848 -381.011176)
				)
				(arc
					(start 352.436684 -381.203962)
					(mid 352.395 -381.216184)
					(end 352.353372 -381.203708)
				)
				(arc
					(start 352.059748 -381.011176)
					(mid 352.039824 -381.00194)
					(end 352.018092 -380.99873)
				)
				(arc
					(start 351.823528 -380.99873)
					(mid 351.769646 -381.021048)
					(end 351.747328 -381.07493)
				)
				(arc
					(start 351.747328 -381.76073)
					(mid 351.769646 -381.814612)
					(end 351.823528 -381.83693)
				)
				(arc
					(start 352.019362 -381.83693)
					(mid 352.041106 -381.833762)
					(end 352.061018 -381.824484)
				)
				(arc
					(start 352.354642 -381.631952)
					(mid 352.396298 -381.61955)
					(end 352.437954 -381.631952)
				)
			)
		)
	)
	(zone
		(layer "In1.Cu")
		(hatch none 0.5)
		(connect_pads
			(clearance 0)
		)
		(min_thickness 0.25)
		(keepout
			(tracks not_allowed)
			(vias allowed)
			(pads allowed)
			(copperpour not_allowed)
			(footprints allowed)
		)
		(placement
			(enabled no)
			(sheetname "")
		)
		(fill
			(thermal_gap 0.5)
			(thermal_bridge_width 0.5)
			(island_removal_mode 0)
		)
		(polygon
			(pts
				(arc
					(start 128.49098 -391.319258)
					(mid 128.61798 -391.446258)
					(end 128.74498 -391.319258)
				)
				(arc
					(start 128.74498 -391.243058)
					(mid 128.61798 -391.116058)
					(end 128.49098 -391.243058)
				)
			)
		)
	)
	(zone
		(layer "In1.Cu")
		(hatch none 0.5)
		(connect_pads
			(clearance 0)
		)
		(min_thickness 0.25)
		(keepout
			(tracks not_allowed)
			(vias allowed)
			(pads allowed)
			(copperpour not_allowed)
			(footprints allowed)
		)
		(placement
			(enabled no)
			(sheetname "")
		)
		(fill
			(thermal_gap 0.5)
			(thermal_bridge_width 0.5)
			(island_removal_mode 0)
		)
		(polygon
			(pts
				(arc
					(start 428.205392 -251.982224)
					(mid 428.201672 -251.991204)
					(end 428.192692 -251.994924)
				)
				(arc
					(start 426.719492 -251.994924)
					(mid 426.710512 -251.991204)
					(end 426.706792 -251.982224)
				)
				(arc
					(start 426.706792 -251.487686)
					(mid 426.710512 -251.478706)
					(end 426.719492 -251.474986)
				)
				(arc
					(start 428.192692 -251.474986)
					(mid 428.201672 -251.478706)
					(end 428.205392 -251.487686)
				)
			)
		)
	)
	(zone
		(layer "In1.Cu")
		(hatch none 0.5)
		(connect_pads
			(clearance 0)
		)
		(min_thickness 0.25)
		(keepout
			(tracks not_allowed)
			(vias allowed)
			(pads allowed)
			(copperpour not_allowed)
			(footprints allowed)
		)
		(placement
			(enabled no)
			(sheetname "")
		)
		(fill
			(thermal_gap 0.5)
			(thermal_bridge_width 0.5)
			(island_removal_mode 0)
		)
		(polygon
			(pts
				(arc
					(start 428.205392 -314.032138)
					(mid 428.201672 -314.041118)
					(end 428.192692 -314.044838)
				)
				(arc
					(start 426.719492 -314.044838)
					(mid 426.710512 -314.041118)
					(end 426.706792 -314.032138)
				)
				(arc
					(start 426.706792 -313.5376)
					(mid 426.710512 -313.52862)
					(end 426.719492 -313.5249)
				)
				(arc
					(start 428.192692 -313.5249)
					(mid 428.201672 -313.52862)
					(end 428.205392 -313.5376)
				)
			)
		)
	)
	(zone
		(layer "In1.Cu")
		(hatch none 0.5)
		(connect_pads
			(clearance 0)
		)
		(min_thickness 0.25)
		(keepout
			(tracks not_allowed)
			(vias allowed)
			(pads allowed)
			(copperpour not_allowed)
			(footprints allowed)
		)
		(placement
			(enabled no)
			(sheetname "")
		)
		(fill
			(thermal_gap 0.5)
			(thermal_bridge_width 0.5)
			(island_removal_mode 0)
		)
		(polygon
			(pts
				(arc
					(start 277.941532 -313.182254)
					(mid 277.937812 -313.191234)
					(end 277.928832 -313.194954)
				)
				(arc
					(start 276.455632 -313.194954)
					(mid 276.446652 -313.191234)
					(end 276.442932 -313.182254)
				)
				(arc
					(start 276.442932 -312.687716)
					(mid 276.446652 -312.678736)
					(end 276.455632 -312.675016)
				)
				(arc
					(start 277.928832 -312.675016)
					(mid 277.937812 -312.678736)
					(end 277.941532 -312.687716)
				)
			)
		)
	)
	(zone
		(layer "In1.Cu")
		(hatch none 0.5)
		(connect_pads
			(clearance 0)
		)
		(min_thickness 0.25)
		(keepout
			(tracks not_allowed)
			(vias allowed)
			(pads allowed)
			(copperpour not_allowed)
			(footprints allowed)
		)
		(placement
			(enabled no)
			(sheetname "")
		)
		(fill
			(thermal_gap 0.5)
			(thermal_bridge_width 0.5)
			(island_removal_mode 0)
		)
		(polygon
			(pts
				(arc
					(start 420.661338 -295.33215)
					(mid 420.657618 -295.34113)
					(end 420.648638 -295.34485)
				)
				(arc
					(start 419.175438 -295.34485)
					(mid 419.166458 -295.34113)
					(end 419.162738 -295.33215)
				)
				(arc
					(start 419.162738 -294.837612)
					(mid 419.166458 -294.828632)
					(end 419.175438 -294.824912)
				)
				(arc
					(start 420.648638 -294.824912)
					(mid 420.657618 -294.828632)
					(end 420.661338 -294.837612)
				)
			)
		)
	)
	(zone
		(layer "In1.Cu")
		(hatch none 0.5)
		(connect_pads
			(clearance 0)
		)
		(min_thickness 0.25)
		(keepout
			(tracks not_allowed)
			(vias allowed)
			(pads allowed)
			(copperpour not_allowed)
			(footprints allowed)
		)
		(placement
			(enabled no)
			(sheetname "")
		)
		(fill
			(thermal_gap 0.5)
			(thermal_bridge_width 0.5)
			(island_removal_mode 0)
		)
		(polygon
			(pts
				(arc
					(start 50.590958 -391.319258)
					(mid 50.717958 -391.446258)
					(end 50.844958 -391.319258)
				)
				(arc
					(start 50.844958 -391.243058)
					(mid 50.717958 -391.116058)
					(end 50.590958 -391.243058)
				)
			)
		)
	)
	(zone
		(layer "In1.Cu")
		(hatch none 0.5)
		(connect_pads
			(clearance 0)
		)
		(min_thickness 0.25)
		(keepout
			(tracks not_allowed)
			(vias allowed)
			(pads allowed)
			(copperpour not_allowed)
			(footprints allowed)
		)
		(placement
			(enabled no)
			(sheetname "")
		)
		(fill
			(thermal_gap 0.5)
			(thermal_bridge_width 0.5)
			(island_removal_mode 0)
		)
		(polygon
			(pts
				(arc
					(start 184.365392 -285.132526)
					(mid 184.361672 -285.141506)
					(end 184.352692 -285.145226)
				)
				(arc
					(start 182.879492 -285.145226)
					(mid 182.870512 -285.141506)
					(end 182.866792 -285.132526)
				)
				(arc
					(start 182.866792 -284.637988)
					(mid 182.870512 -284.629008)
					(end 182.879492 -284.625288)
				)
				(arc
					(start 184.352692 -284.625288)
					(mid 184.361672 -284.629008)
					(end 184.365392 -284.637988)
				)
			)
		)
	)
	(zone
		(layer "In1.Cu")
		(hatch none 0.5)
		(connect_pads
			(clearance 0)
		)
		(min_thickness 0.25)
		(keepout
			(tracks not_allowed)
			(vias allowed)
			(pads allowed)
			(copperpour not_allowed)
			(footprints allowed)
		)
		(placement
			(enabled no)
			(sheetname "")
		)
		(fill
			(thermal_gap 0.5)
			(thermal_bridge_width 0.5)
			(island_removal_mode 0)
		)
		(polygon
			(pts
				(arc
					(start 450.8373 -280.88209)
					(mid 450.83358 -280.89107)
					(end 450.8246 -280.89479)
				)
				(arc
					(start 449.3514 -280.89479)
					(mid 449.34242 -280.89107)
					(end 449.3387 -280.88209)
				)
				(arc
					(start 449.3387 -280.387552)
					(mid 449.34242 -280.378572)
					(end 449.3514 -280.374852)
				)
				(arc
					(start 450.8246 -280.374852)
					(mid 450.83358 -280.378572)
					(end 450.8373 -280.387552)
				)
			)
		)
	)
	(zone
		(layer "In1.Cu")
		(hatch none 0.5)
		(connect_pads
			(clearance 0)
		)
		(min_thickness 0.25)
		(keepout
			(tracks not_allowed)
			(vias allowed)
			(pads allowed)
			(copperpour not_allowed)
			(footprints allowed)
		)
		(placement
			(enabled no)
			(sheetname "")
		)
		(fill
			(thermal_gap 0.5)
			(thermal_bridge_width 0.5)
			(island_removal_mode 0)
		)
		(polygon
			(pts
				(arc
					(start 265.87831 -238.985044)
					(mid 265.21791 -238.985044)
					(end 265.87831 -238.985044)
				)
			)
		)
	)
	(zone
		(layer "In1.Cu")
		(hatch none 0.5)
		(connect_pads
			(clearance 0)
		)
		(min_thickness 0.25)
		(keepout
			(tracks not_allowed)
			(vias allowed)
			(pads allowed)
			(copperpour not_allowed)
			(footprints allowed)
		)
		(placement
			(enabled no)
			(sheetname "")
		)
		(fill
			(thermal_gap 0.5)
			(thermal_bridge_width 0.5)
			(island_removal_mode 0)
		)
		(polygon
			(pts
				(arc
					(start 420.661338 -213.73211)
					(mid 420.657618 -213.74109)
					(end 420.648638 -213.74481)
				)
				(arc
					(start 419.175438 -213.74481)
					(mid 419.166458 -213.74109)
					(end 419.162738 -213.73211)
				)
				(arc
					(start 419.162738 -213.237572)
					(mid 419.166458 -213.228592)
					(end 419.175438 -213.224872)
				)
				(arc
					(start 420.648638 -213.224872)
					(mid 420.657618 -213.228592)
					(end 420.661338 -213.237572)
				)
			)
		)
	)
	(zone
		(layer "In1.Cu")
		(hatch none 0.5)
		(connect_pads
			(clearance 0)
		)
		(min_thickness 0.25)
		(keepout
			(tracks not_allowed)
			(vias allowed)
			(pads allowed)
			(copperpour not_allowed)
			(footprints allowed)
		)
		(placement
			(enabled no)
			(sheetname "")
		)
		(fill
			(thermal_gap 0.5)
			(thermal_bridge_width 0.5)
			(island_removal_mode 0)
		)
		(polygon
			(pts
				(arc
					(start 270.397478 -220.532198)
					(mid 270.393758 -220.541178)
					(end 270.384778 -220.544898)
				)
				(arc
					(start 268.911578 -220.544898)
					(mid 268.902598 -220.541178)
					(end 268.898878 -220.532198)
				)
				(arc
					(start 268.898878 -220.03766)
					(mid 268.902598 -220.02868)
					(end 268.911578 -220.02496)
				)
				(arc
					(start 270.384778 -220.02496)
					(mid 270.393758 -220.02868)
					(end 270.397478 -220.03766)
				)
			)
		)
	)
	(zone
		(layer "In1.Cu")
		(hatch none 0.5)
		(connect_pads
			(clearance 0)
		)
		(min_thickness 0.25)
		(keepout
			(tracks not_allowed)
			(vias allowed)
			(pads allowed)
			(copperpour not_allowed)
			(footprints allowed)
		)
		(placement
			(enabled no)
			(sheetname "")
		)
		(fill
			(thermal_gap 0.5)
			(thermal_bridge_width 0.5)
			(island_removal_mode 0)
		)
		(polygon
			(pts
				(arc
					(start 91.188794 -389.467344)
					(mid 90.807794 -389.467344)
					(end 91.188794 -389.467344)
				)
			)
		)
	)
	(zone
		(layer "In1.Cu")
		(hatch none 0.5)
		(connect_pads
			(clearance 0)
		)
		(min_thickness 0.25)
		(keepout
			(tracks not_allowed)
			(vias allowed)
			(pads allowed)
			(copperpour not_allowed)
			(footprints allowed)
		)
		(placement
			(enabled no)
			(sheetname "")
		)
		(fill
			(thermal_gap 0.5)
			(thermal_bridge_width 0.5)
			(island_removal_mode 0)
		)
		(polygon
			(pts
				(arc
					(start 443.2935 -312.332116)
					(mid 443.28978 -312.341096)
					(end 443.2808 -312.344816)
				)
				(arc
					(start 441.8076 -312.344816)
					(mid 441.79862 -312.341096)
					(end 441.7949 -312.332116)
				)
				(arc
					(start 441.7949 -311.837578)
					(mid 441.79862 -311.828598)
					(end 441.8076 -311.824878)
				)
				(arc
					(start 443.2808 -311.824878)
					(mid 443.28978 -311.828598)
					(end 443.2935 -311.837578)
				)
			)
		)
	)
	(zone
		(layer "In1.Cu")
		(hatch none 0.5)
		(connect_pads
			(clearance 0)
		)
		(min_thickness 0.25)
		(keepout
			(tracks not_allowed)
			(vias allowed)
			(pads allowed)
			(copperpour not_allowed)
			(footprints allowed)
		)
		(placement
			(enabled no)
			(sheetname "")
		)
		(fill
			(thermal_gap 0.5)
			(thermal_bridge_width 0.5)
			(island_removal_mode 0)
		)
		(polygon
			(pts
				(arc
					(start 60.177426 -264.732516)
					(mid 60.173706 -264.741496)
					(end 60.164726 -264.745216)
				)
				(arc
					(start 58.691526 -264.745216)
					(mid 58.682546 -264.741496)
					(end 58.678826 -264.732516)
				)
				(arc
					(start 58.678826 -264.237978)
					(mid 58.682546 -264.228998)
					(end 58.691526 -264.225278)
				)
				(arc
					(start 60.164726 -264.225278)
					(mid 60.173706 -264.228998)
					(end 60.177426 -264.237978)
				)
			)
		)
	)
	(zone
		(layer "In1.Cu")
		(hatch none 0.5)
		(connect_pads
			(clearance 0)
		)
		(min_thickness 0.25)
		(keepout
			(tracks not_allowed)
			(vias allowed)
			(pads allowed)
			(copperpour not_allowed)
			(footprints allowed)
		)
		(placement
			(enabled no)
			(sheetname "")
		)
		(fill
			(thermal_gap 0.5)
			(thermal_bridge_width 0.5)
			(island_removal_mode 0)
		)
		(polygon
			(pts
				(arc
					(start 64.261238 -388.774432)
					(mid 63.880238 -388.774432)
					(end 64.261238 -388.774432)
				)
			)
		)
	)
	(zone
		(layer "In1.Cu")
		(hatch none 0.5)
		(connect_pads
			(clearance 0)
		)
		(min_thickness 0.25)
		(keepout
			(tracks not_allowed)
			(vias allowed)
			(pads allowed)
			(copperpour not_allowed)
			(footprints allowed)
		)
		(placement
			(enabled no)
			(sheetname "")
		)
		(fill
			(thermal_gap 0.5)
			(thermal_bridge_width 0.5)
			(island_removal_mode 0)
		)
		(polygon
			(pts
				(arc
					(start 277.941532 -264.732262)
					(mid 277.937812 -264.741242)
					(end 277.928832 -264.744962)
				)
				(arc
					(start 276.455632 -264.744962)
					(mid 276.446652 -264.741242)
					(end 276.442932 -264.732262)
				)
				(arc
					(start 276.442932 -264.237724)
					(mid 276.446652 -264.228744)
					(end 276.455632 -264.225024)
				)
				(arc
					(start 277.928832 -264.225024)
					(mid 277.937812 -264.228744)
					(end 277.941532 -264.237724)
				)
			)
		)
	)
	(zone
		(layer "In1.Cu")
		(hatch none 0.5)
		(connect_pads
			(clearance 0)
		)
		(min_thickness 0.25)
		(keepout
			(tracks not_allowed)
			(vias allowed)
			(pads allowed)
			(copperpour not_allowed)
			(footprints allowed)
		)
		(placement
			(enabled no)
			(sheetname "")
		)
		(fill
			(thermal_gap 0.5)
			(thermal_bridge_width 0.5)
			(island_removal_mode 0)
		)
		(polygon
			(pts
				(arc
					(start 202.897232 -212.032342)
					(mid 202.893512 -212.041322)
					(end 202.884532 -212.045042)
				)
				(arc
					(start 201.411332 -212.045042)
					(mid 201.402352 -212.041322)
					(end 201.398632 -212.032342)
				)
				(arc
					(start 201.398632 -211.537804)
					(mid 201.402352 -211.528824)
					(end 201.411332 -211.525104)
				)
				(arc
					(start 202.884532 -211.525104)
					(mid 202.893512 -211.528824)
					(end 202.897232 -211.537804)
				)
			)
		)
	)
	(zone
		(layer "In1.Cu")
		(hatch none 0.5)
		(connect_pads
			(clearance 0)
		)
		(min_thickness 0.25)
		(keepout
			(tracks not_allowed)
			(vias allowed)
			(pads allowed)
			(copperpour not_allowed)
			(footprints allowed)
		)
		(placement
			(enabled no)
			(sheetname "")
		)
		(fill
			(thermal_gap 0.5)
			(thermal_bridge_width 0.5)
			(island_removal_mode 0)
		)
		(polygon
			(pts
				(arc
					(start 206.9973 -231.582468)
					(mid 206.99358 -231.591448)
					(end 206.9846 -231.595168)
				)
				(arc
					(start 205.5114 -231.595168)
					(mid 205.50242 -231.591448)
					(end 205.4987 -231.582468)
				)
				(arc
					(start 205.4987 -231.08793)
					(mid 205.50242 -231.07895)
					(end 205.5114 -231.07523)
				)
				(arc
					(start 206.9846 -231.07523)
					(mid 206.99358 -231.07895)
					(end 206.9973 -231.08793)
				)
			)
		)
	)
	(zone
		(layer "In1.Cu")
		(hatch none 0.5)
		(connect_pads
			(clearance 0)
		)
		(min_thickness 0.25)
		(keepout
			(tracks not_allowed)
			(vias allowed)
			(pads allowed)
			(copperpour not_allowed)
			(footprints allowed)
		)
		(placement
			(enabled no)
			(sheetname "")
		)
		(fill
			(thermal_gap 0.5)
			(thermal_bridge_width 0.5)
			(island_removal_mode 0)
		)
		(polygon
			(pts
				(arc
					(start 388.561072 -393.69238)
					(mid 388.180072 -393.69238)
					(end 388.561072 -393.69238)
				)
			)
		)
	)
	(zone
		(layer "In1.Cu")
		(hatch none 0.5)
		(connect_pads
			(clearance 0)
		)
		(min_thickness 0.25)
		(keepout
			(tracks not_allowed)
			(vias allowed)
			(pads allowed)
			(copperpour not_allowed)
			(footprints allowed)
		)
		(placement
			(enabled no)
			(sheetname "")
		)
		(fill
			(thermal_gap 0.5)
			(thermal_bridge_width 0.5)
			(island_removal_mode 0)
		)
		(polygon
			(pts
				(arc
					(start 379.070362 -399.143474)
					(mid 378.765562 -399.143474)
					(end 379.070362 -399.143474)
				)
			)
		)
	)
	(zone
		(layer "In1.Cu")
		(hatch none 0.5)
		(connect_pads
			(clearance 0)
		)
		(min_thickness 0.25)
		(keepout
			(tracks not_allowed)
			(vias allowed)
			(pads allowed)
			(copperpour not_allowed)
			(footprints allowed)
		)
		(placement
			(enabled no)
			(sheetname "")
		)
		(fill
			(thermal_gap 0.5)
			(thermal_bridge_width 0.5)
			(island_removal_mode 0)
		)
		(polygon
			(pts
				(arc
					(start 428.205392 -246.882158)
					(mid 428.201672 -246.891138)
					(end 428.192692 -246.894858)
				)
				(arc
					(start 426.719492 -246.894858)
					(mid 426.710512 -246.891138)
					(end 426.706792 -246.882158)
				)
				(arc
					(start 426.706792 -246.38762)
					(mid 426.710512 -246.37864)
					(end 426.719492 -246.37492)
				)
				(arc
					(start 428.192692 -246.37492)
					(mid 428.201672 -246.37864)
					(end 428.205392 -246.38762)
				)
			)
		)
	)
	(zone
		(layer "In1.Cu")
		(hatch none 0.5)
		(connect_pads
			(clearance 0)
		)
		(min_thickness 0.25)
		(keepout
			(tracks not_allowed)
			(vias allowed)
			(pads allowed)
			(copperpour not_allowed)
			(footprints allowed)
		)
		(placement
			(enabled no)
			(sheetname "")
		)
		(fill
			(thermal_gap 0.5)
			(thermal_bridge_width 0.5)
			(island_removal_mode 0)
		)
		(polygon
			(pts
				(arc
					(start 370.670328 -392.30427)
					(mid 370.365528 -392.30427)
					(end 370.670328 -392.30427)
				)
			)
		)
	)
	(zone
		(layer "In1.Cu")
		(hatch none 0.5)
		(connect_pads
			(clearance 0)
		)
		(min_thickness 0.25)
		(keepout
			(tracks not_allowed)
			(vias allowed)
			(pads allowed)
			(copperpour not_allowed)
			(footprints allowed)
		)
		(placement
			(enabled no)
			(sheetname "")
		)
		(fill
			(thermal_gap 0.5)
			(thermal_bridge_width 0.5)
			(island_removal_mode 0)
		)
		(polygon
			(pts
				(arc
					(start 405.888698 -394.385292)
					(mid 405.507698 -394.385292)
					(end 405.888698 -394.385292)
				)
			)
		)
	)
	(zone
		(layer "In1.Cu")
		(hatch none 0.5)
		(connect_pads
			(clearance 0)
		)
		(min_thickness 0.25)
		(keepout
			(tracks not_allowed)
			(vias allowed)
			(pads allowed)
			(copperpour not_allowed)
			(footprints allowed)
		)
		(placement
			(enabled no)
			(sheetname "")
		)
		(fill
			(thermal_gap 0.5)
			(thermal_bridge_width 0.5)
			(island_removal_mode 0)
		)
		(polygon
			(pts
				(arc
					(start 285.485332 -280.032206)
					(mid 285.481612 -280.041186)
					(end 285.472632 -280.044906)
				)
				(arc
					(start 283.999432 -280.044906)
					(mid 283.990452 -280.041186)
					(end 283.986732 -280.032206)
				)
				(arc
					(start 283.986732 -279.537668)
					(mid 283.990452 -279.528688)
					(end 283.999432 -279.524968)
				)
				(arc
					(start 285.472632 -279.524968)
					(mid 285.481612 -279.528688)
					(end 285.485332 -279.537668)
				)
			)
		)
	)
	(zone
		(layer "In1.Cu")
		(hatch none 0.5)
		(connect_pads
			(clearance 0)
		)
		(min_thickness 0.25)
		(keepout
			(tracks not_allowed)
			(vias allowed)
			(pads allowed)
			(copperpour not_allowed)
			(footprints allowed)
		)
		(placement
			(enabled no)
			(sheetname "")
		)
		(fill
			(thermal_gap 0.5)
			(thermal_bridge_width 0.5)
			(island_removal_mode 0)
		)
		(polygon
			(pts
				(arc
					(start 161.018728 -391.319258)
					(mid 161.145728 -391.446258)
					(end 161.272728 -391.319258)
				)
				(arc
					(start 161.272728 -391.243058)
					(mid 161.145728 -391.116058)
					(end 161.018728 -391.243058)
				)
			)
		)
	)
	(zone
		(layer "In1.Cu")
		(hatch none 0.5)
		(connect_pads
			(clearance 0)
		)
		(min_thickness 0.25)
		(keepout
			(tracks not_allowed)
			(vias allowed)
			(pads allowed)
			(copperpour not_allowed)
			(footprints allowed)
		)
		(placement
			(enabled no)
			(sheetname "")
		)
		(fill
			(thermal_gap 0.5)
			(thermal_bridge_width 0.5)
			(island_removal_mode 0)
		)
		(polygon
			(pts
				(arc
					(start 37.545264 -289.382454)
					(mid 37.541544 -289.391434)
					(end 37.532564 -289.395154)
				)
				(arc
					(start 36.059364 -289.395154)
					(mid 36.050384 -289.391434)
					(end 36.046664 -289.382454)
				)
				(arc
					(start 36.046664 -288.887916)
					(mid 36.050384 -288.878936)
					(end 36.059364 -288.875216)
				)
				(arc
					(start 37.532564 -288.875216)
					(mid 37.541544 -288.878936)
					(end 37.545264 -288.887916)
				)
			)
		)
	)
	(zone
		(layer "In1.Cu")
		(hatch none 0.5)
		(connect_pads
			(clearance 0)
		)
		(min_thickness 0.25)
		(keepout
			(tracks not_allowed)
			(vias allowed)
			(pads allowed)
			(copperpour not_allowed)
			(footprints allowed)
		)
		(placement
			(enabled no)
			(sheetname "")
		)
		(fill
			(thermal_gap 0.5)
			(thermal_bridge_width 0.5)
			(island_removal_mode 0)
		)
		(polygon
			(pts
				(arc
					(start 62.260988 -389.467344)
					(mid 61.879988 -389.467344)
					(end 62.260988 -389.467344)
				)
			)
		)
	)
	(zone
		(layer "In1.Cu")
		(hatch none 0.5)
		(connect_pads
			(clearance 0)
		)
		(min_thickness 0.25)
		(keepout
			(tracks not_allowed)
			(vias allowed)
			(pads allowed)
			(copperpour not_allowed)
			(footprints allowed)
		)
		(placement
			(enabled no)
			(sheetname "")
		)
		(fill
			(thermal_gap 0.5)
			(thermal_bridge_width 0.5)
			(island_removal_mode 0)
		)
		(polygon
			(pts
				(arc
					(start 48.533304 -276.632416)
					(mid 48.529584 -276.641396)
					(end 48.520604 -276.645116)
				)
				(arc
					(start 47.047404 -276.645116)
					(mid 47.038424 -276.641396)
					(end 47.034704 -276.632416)
				)
				(arc
					(start 47.034704 -276.137878)
					(mid 47.038424 -276.128898)
					(end 47.047404 -276.125178)
				)
				(arc
					(start 48.520604 -276.125178)
					(mid 48.529584 -276.128898)
					(end 48.533304 -276.137878)
				)
			)
		)
	)
	(zone
		(layer "In1.Cu")
		(hatch none 0.5)
		(connect_pads
			(clearance 0)
		)
		(min_thickness 0.25)
		(keepout
			(tracks not_allowed)
			(vias allowed)
			(pads allowed)
			(copperpour not_allowed)
			(footprints allowed)
		)
		(placement
			(enabled no)
			(sheetname "")
		)
		(fill
			(thermal_gap 0.5)
			(thermal_bridge_width 0.5)
			(island_removal_mode 0)
		)
		(polygon
			(pts
				(arc
					(start 48.533304 -296.182542)
					(mid 48.529584 -296.191522)
					(end 48.520604 -296.195242)
				)
				(arc
					(start 47.047404 -296.195242)
					(mid 47.038424 -296.191522)
					(end 47.034704 -296.182542)
				)
				(arc
					(start 47.034704 -295.688004)
					(mid 47.038424 -295.679024)
					(end 47.047404 -295.675304)
				)
				(arc
					(start 48.520604 -295.675304)
					(mid 48.529584 -295.679024)
					(end 48.533304 -295.688004)
				)
			)
		)
	)
	(zone
		(layer "In1.Cu")
		(hatch none 0.5)
		(connect_pads
			(clearance 0)
		)
		(min_thickness 0.25)
		(keepout
			(tracks not_allowed)
			(vias allowed)
			(pads allowed)
			(copperpour not_allowed)
			(footprints allowed)
		)
		(placement
			(enabled no)
			(sheetname "")
		)
		(fill
			(thermal_gap 0.5)
			(thermal_bridge_width 0.5)
			(island_removal_mode 0)
		)
		(polygon
			(pts
				(arc
					(start 296.473372 -310.632094)
					(mid 296.469652 -310.641074)
					(end 296.460672 -310.644794)
				)
				(arc
					(start 294.987472 -310.644794)
					(mid 294.978492 -310.641074)
					(end 294.974772 -310.632094)
				)
				(arc
					(start 294.974772 -310.137556)
					(mid 294.978492 -310.128576)
					(end 294.987472 -310.124856)
				)
				(arc
					(start 296.460672 -310.124856)
					(mid 296.469652 -310.128576)
					(end 296.473372 -310.137556)
				)
			)
		)
	)
	(zone
		(layer "In1.Cu")
		(hatch none 0.5)
		(connect_pads
			(clearance 0)
		)
		(min_thickness 0.25)
		(keepout
			(tracks not_allowed)
			(vias allowed)
			(pads allowed)
			(copperpour not_allowed)
			(footprints allowed)
		)
		(placement
			(enabled no)
			(sheetname "")
		)
		(fill
			(thermal_gap 0.5)
			(thermal_bridge_width 0.5)
			(island_removal_mode 0)
		)
		(polygon
			(pts
				(arc
					(start 191.909446 -285.98241)
					(mid 191.905726 -285.99139)
					(end 191.896746 -285.99511)
				)
				(arc
					(start 190.423546 -285.99511)
					(mid 190.414566 -285.99139)
					(end 190.410846 -285.98241)
				)
				(arc
					(start 190.410846 -285.487872)
					(mid 190.414566 -285.478892)
					(end 190.423546 -285.475172)
				)
				(arc
					(start 191.896746 -285.475172)
					(mid 191.905726 -285.478892)
					(end 191.909446 -285.487872)
				)
			)
		)
	)
	(zone
		(layer "In1.Cu")
		(hatch none 0.5)
		(connect_pads
			(clearance 0)
		)
		(min_thickness 0.25)
		(keepout
			(tracks not_allowed)
			(vias allowed)
			(pads allowed)
			(copperpour not_allowed)
			(footprints allowed)
		)
		(placement
			(enabled no)
			(sheetname "")
		)
		(fill
			(thermal_gap 0.5)
			(thermal_bridge_width 0.5)
			(island_removal_mode 0)
		)
		(polygon
			(pts
				(arc
					(start 56.077358 -301.282354)
					(mid 56.073638 -301.291334)
					(end 56.064658 -301.295054)
				)
				(arc
					(start 54.591458 -301.295054)
					(mid 54.582478 -301.291334)
					(end 54.578758 -301.282354)
				)
				(arc
					(start 54.578758 -300.787816)
					(mid 54.582478 -300.778836)
					(end 54.591458 -300.775116)
				)
				(arc
					(start 56.064658 -300.775116)
					(mid 56.073638 -300.778836)
					(end 56.077358 -300.787816)
				)
			)
		)
	)
	(zone
		(layer "In1.Cu")
		(hatch none 0.5)
		(connect_pads
			(clearance 0)
		)
		(min_thickness 0.25)
		(keepout
			(tracks not_allowed)
			(vias allowed)
			(pads allowed)
			(copperpour not_allowed)
			(footprints allowed)
		)
		(placement
			(enabled no)
			(sheetname "")
		)
		(fill
			(thermal_gap 0.5)
			(thermal_bridge_width 0.5)
			(island_removal_mode 0)
		)
		(polygon
			(pts
				(arc
					(start 450.8373 -314.882276)
					(mid 450.83358 -314.891256)
					(end 450.8246 -314.894976)
				)
				(arc
					(start 449.3514 -314.894976)
					(mid 449.34242 -314.891256)
					(end 449.3387 -314.882276)
				)
				(arc
					(start 449.3387 -314.387738)
					(mid 449.34242 -314.378758)
					(end 449.3514 -314.375038)
				)
				(arc
					(start 450.8246 -314.375038)
					(mid 450.83358 -314.378758)
					(end 450.8373 -314.387738)
				)
			)
		)
	)
	(zone
		(layer "In1.Cu")
		(hatch none 0.5)
		(connect_pads
			(clearance 0)
		)
		(min_thickness 0.25)
		(keepout
			(tracks not_allowed)
			(vias allowed)
			(pads allowed)
			(copperpour not_allowed)
			(footprints allowed)
		)
		(placement
			(enabled no)
			(sheetname "")
		)
		(fill
			(thermal_gap 0.5)
			(thermal_bridge_width 0.5)
			(island_removal_mode 0)
		)
		(polygon
			(pts
				(arc
					(start 52.633372 -314.032392)
					(mid 52.629652 -314.041372)
					(end 52.620672 -314.045092)
				)
				(arc
					(start 51.147472 -314.045092)
					(mid 51.138492 -314.041372)
					(end 51.134772 -314.032392)
				)
				(arc
					(start 51.134772 -313.537854)
					(mid 51.138492 -313.528874)
					(end 51.147472 -313.525154)
				)
				(arc
					(start 52.620672 -313.525154)
					(mid 52.629652 -313.528874)
					(end 52.633372 -313.537854)
				)
			)
		)
	)
	(zone
		(layer "In1.Cu")
		(hatch none 0.5)
		(connect_pads
			(clearance 0)
		)
		(min_thickness 0.25)
		(keepout
			(tracks not_allowed)
			(vias allowed)
			(pads allowed)
			(copperpour not_allowed)
			(footprints allowed)
		)
		(placement
			(enabled no)
			(sheetname "")
		)
		(fill
			(thermal_gap 0.5)
			(thermal_bridge_width 0.5)
			(island_removal_mode 0)
		)
		(polygon
			(pts
				(arc
					(start 296.473372 -263.882124)
					(mid 296.469652 -263.891104)
					(end 296.460672 -263.894824)
				)
				(arc
					(start 294.987472 -263.894824)
					(mid 294.978492 -263.891104)
					(end 294.974772 -263.882124)
				)
				(arc
					(start 294.974772 -263.387586)
					(mid 294.978492 -263.378606)
					(end 294.987472 -263.374886)
				)
				(arc
					(start 296.460672 -263.374886)
					(mid 296.469652 -263.378606)
					(end 296.473372 -263.387586)
				)
			)
		)
	)
	(zone
		(layer "In1.Cu")
		(hatch none 0.5)
		(connect_pads
			(clearance 0)
		)
		(min_thickness 0.25)
		(keepout
			(tracks not_allowed)
			(vias allowed)
			(pads allowed)
			(copperpour not_allowed)
			(footprints allowed)
		)
		(placement
			(enabled no)
			(sheetname "")
		)
		(fill
			(thermal_gap 0.5)
			(thermal_bridge_width 0.5)
			(island_removal_mode 0)
		)
		(polygon
			(pts
				(arc
					(start 376.670316 -399.143474)
					(mid 376.365516 -399.143474)
					(end 376.670316 -399.143474)
				)
			)
		)
	)
	(zone
		(layer "In1.Cu")
		(hatch none 0.5)
		(connect_pads
			(clearance 0)
		)
		(min_thickness 0.25)
		(keepout
			(tracks not_allowed)
			(vias allowed)
			(pads allowed)
			(copperpour not_allowed)
			(footprints allowed)
		)
		(placement
			(enabled no)
			(sheetname "")
		)
		(fill
			(thermal_gap 0.5)
			(thermal_bridge_width 0.5)
			(island_removal_mode 0)
		)
		(polygon
			(pts
				(arc
					(start 428.205392 -284.282134)
					(mid 428.201672 -284.291114)
					(end 428.192692 -284.294834)
				)
				(arc
					(start 426.719492 -284.294834)
					(mid 426.710512 -284.291114)
					(end 426.706792 -284.282134)
				)
				(arc
					(start 426.706792 -283.787596)
					(mid 426.710512 -283.778616)
					(end 426.719492 -283.774896)
				)
				(arc
					(start 428.192692 -283.774896)
					(mid 428.201672 -283.778616)
					(end 428.205392 -283.787596)
				)
			)
		)
	)
	(zone
		(layer "In1.Cu")
		(hatch none 0.5)
		(connect_pads
			(clearance 0)
		)
		(min_thickness 0.25)
		(keepout
			(tracks not_allowed)
			(vias allowed)
			(pads allowed)
			(copperpour not_allowed)
			(footprints allowed)
		)
		(placement
			(enabled no)
			(sheetname "")
		)
		(fill
			(thermal_gap 0.5)
			(thermal_bridge_width 0.5)
			(island_removal_mode 0)
		)
		(polygon
			(pts
				(arc
					(start 206.5782 -238.135414)
					(mid 205.9178 -238.135414)
					(end 206.5782 -238.135414)
				)
			)
		)
	)
	(zone
		(layer "In1.Cu")
		(hatch none 0.5)
		(connect_pads
			(clearance 0)
		)
		(min_thickness 0.25)
		(keepout
			(tracks not_allowed)
			(vias allowed)
			(pads allowed)
			(copperpour not_allowed)
			(footprints allowed)
		)
		(placement
			(enabled no)
			(sheetname "")
		)
		(fill
			(thermal_gap 0.5)
			(thermal_bridge_width 0.5)
			(island_removal_mode 0)
		)
		(polygon
			(pts
				(arc
					(start 206.5782 -300.185328)
					(mid 205.9178 -300.185328)
					(end 206.5782 -300.185328)
				)
			)
		)
	)
	(zone
		(layer "In1.Cu")
		(hatch none 0.5)
		(connect_pads
			(clearance 0)
		)
		(min_thickness 0.25)
		(keepout
			(tracks not_allowed)
			(vias allowed)
			(pads allowed)
			(copperpour not_allowed)
			(footprints allowed)
		)
		(placement
			(enabled no)
			(sheetname "")
		)
		(fill
			(thermal_gap 0.5)
			(thermal_bridge_width 0.5)
			(island_removal_mode 0)
		)
		(polygon
			(pts
				(arc
					(start 317.060834 -397.849344)
					(mid 316.679834 -397.849344)
					(end 317.060834 -397.849344)
				)
			)
		)
	)
	(zone
		(layer "In1.Cu")
		(hatch none 0.5)
		(connect_pads
			(clearance 0)
		)
		(min_thickness 0.25)
		(keepout
			(tracks not_allowed)
			(vias allowed)
			(pads allowed)
			(copperpour not_allowed)
			(footprints allowed)
		)
		(placement
			(enabled no)
			(sheetname "")
		)
		(fill
			(thermal_gap 0.5)
			(thermal_bridge_width 0.5)
			(island_removal_mode 0)
		)
		(polygon
			(pts
				(arc
					(start 165.177216 -232.432352)
					(mid 165.173496 -232.441332)
					(end 165.164516 -232.445052)
				)
				(arc
					(start 163.691316 -232.445052)
					(mid 163.682336 -232.441332)
					(end 163.678616 -232.432352)
				)
				(arc
					(start 163.678616 -231.937814)
					(mid 163.682336 -231.928834)
					(end 163.691316 -231.925114)
				)
				(arc
					(start 165.164516 -231.925114)
					(mid 165.173496 -231.928834)
					(end 165.177216 -231.937814)
				)
			)
		)
	)
	(zone
		(layer "In1.Cu")
		(hatch none 0.5)
		(connect_pads
			(clearance 0)
		)
		(min_thickness 0.25)
		(keepout
			(tracks not_allowed)
			(vias allowed)
			(pads allowed)
			(copperpour not_allowed)
			(footprints allowed)
		)
		(placement
			(enabled no)
			(sheetname "")
		)
		(fill
			(thermal_gap 0.5)
			(thermal_bridge_width 0.5)
			(island_removal_mode 0)
		)
		(polygon
			(pts
				(arc
					(start 296.473372 -218.832176)
					(mid 296.469652 -218.841156)
					(end 296.460672 -218.844876)
				)
				(arc
					(start 294.987472 -218.844876)
					(mid 294.978492 -218.841156)
					(end 294.974772 -218.832176)
				)
				(arc
					(start 294.974772 -218.337638)
					(mid 294.978492 -218.328658)
					(end 294.987472 -218.324938)
				)
				(arc
					(start 296.460672 -218.324938)
					(mid 296.469652 -218.328658)
					(end 296.473372 -218.337638)
				)
			)
		)
	)
	(zone
		(layer "In1.Cu")
		(hatch none 0.5)
		(connect_pads
			(clearance 0)
		)
		(min_thickness 0.25)
		(keepout
			(tracks not_allowed)
			(vias allowed)
			(pads allowed)
			(copperpour not_allowed)
			(footprints allowed)
		)
		(placement
			(enabled no)
			(sheetname "")
		)
		(fill
			(thermal_gap 0.5)
			(thermal_bridge_width 0.5)
			(island_removal_mode 0)
		)
		(polygon
			(pts
				(arc
					(start 435.749446 -221.382082)
					(mid 435.745726 -221.391062)
					(end 435.736746 -221.394782)
				)
				(arc
					(start 434.263546 -221.394782)
					(mid 434.254566 -221.391062)
					(end 434.250846 -221.382082)
				)
				(arc
					(start 434.250846 -220.887544)
					(mid 434.254566 -220.878564)
					(end 434.263546 -220.874844)
				)
				(arc
					(start 435.736746 -220.874844)
					(mid 435.745726 -220.878564)
					(end 435.749446 -220.887544)
				)
			)
		)
	)
	(zone
		(layer "In1.Cu")
		(hatch none 0.5)
		(connect_pads
			(clearance 0)
		)
		(min_thickness 0.25)
		(keepout
			(tracks not_allowed)
			(vias allowed)
			(pads allowed)
			(copperpour not_allowed)
			(footprints allowed)
		)
		(placement
			(enabled no)
			(sheetname "")
		)
		(fill
			(thermal_gap 0.5)
			(thermal_bridge_width 0.5)
			(island_removal_mode 0)
		)
		(polygon
			(pts
				(arc
					(start 435.749446 -206.082138)
					(mid 435.745726 -206.091118)
					(end 435.736746 -206.094838)
				)
				(arc
					(start 434.263546 -206.094838)
					(mid 434.254566 -206.091118)
					(end 434.250846 -206.082138)
				)
				(arc
					(start 434.250846 -205.5876)
					(mid 434.254566 -205.57862)
					(end 434.263546 -205.5749)
				)
				(arc
					(start 435.736746 -205.5749)
					(mid 435.745726 -205.57862)
					(end 435.749446 -205.5876)
				)
			)
		)
	)
	(zone
		(layer "In1.Cu")
		(hatch none 0.5)
		(connect_pads
			(clearance 0)
		)
		(min_thickness 0.25)
		(keepout
			(tracks not_allowed)
			(vias allowed)
			(pads allowed)
			(copperpour not_allowed)
			(footprints allowed)
		)
		(placement
			(enabled no)
			(sheetname "")
		)
		(fill
			(thermal_gap 0.5)
			(thermal_bridge_width 0.5)
			(island_removal_mode 0)
		)
		(polygon
			(pts
				(arc
					(start 64.261238 -385.31038)
					(mid 63.880238 -385.31038)
					(end 64.261238 -385.31038)
				)
			)
		)
	)
	(zone
		(layer "In1.Cu")
		(hatch none 0.5)
		(connect_pads
			(clearance 0)
		)
		(min_thickness 0.25)
		(keepout
			(tracks not_allowed)
			(vias allowed)
			(pads allowed)
			(copperpour not_allowed)
			(footprints allowed)
		)
		(placement
			(enabled no)
			(sheetname "")
		)
		(fill
			(thermal_gap 0.5)
			(thermal_bridge_width 0.5)
			(island_removal_mode 0)
		)
		(polygon
			(pts
				(arc
					(start 169.277284 -272.382488)
					(mid 169.273564 -272.391468)
					(end 169.264584 -272.395188)
				)
				(arc
					(start 167.791384 -272.395188)
					(mid 167.782404 -272.391468)
					(end 167.778684 -272.382488)
				)
				(arc
					(start 167.778684 -271.88795)
					(mid 167.782404 -271.87897)
					(end 167.791384 -271.87525)
				)
				(arc
					(start 169.264584 -271.87525)
					(mid 169.273564 -271.87897)
					(end 169.277284 -271.88795)
				)
			)
		)
	)
	(zone
		(layer "In1.Cu")
		(hatch none 0.5)
		(connect_pads
			(clearance 0)
		)
		(min_thickness 0.25)
		(keepout
			(tracks not_allowed)
			(vias allowed)
			(pads allowed)
			(copperpour not_allowed)
			(footprints allowed)
		)
		(placement
			(enabled no)
			(sheetname "")
		)
		(fill
			(thermal_gap 0.5)
			(thermal_bridge_width 0.5)
			(island_removal_mode 0)
		)
		(polygon
			(pts
				(arc
					(start 405.888698 -397.849344)
					(mid 405.507698 -397.849344)
					(end 405.888698 -397.849344)
				)
			)
		)
	)
	(zone
		(layer "In1.Cu")
		(hatch none 0.5)
		(connect_pads
			(clearance 0)
		)
		(min_thickness 0.25)
		(keepout
			(tracks not_allowed)
			(vias allowed)
			(pads allowed)
			(copperpour not_allowed)
			(footprints allowed)
		)
		(placement
			(enabled no)
			(sheetname "")
		)
		(fill
			(thermal_gap 0.5)
			(thermal_bridge_width 0.5)
			(island_removal_mode 0)
		)
		(polygon
			(pts
				(arc
					(start 339.988652 -394.385292)
					(mid 339.607652 -394.385292)
					(end 339.988652 -394.385292)
				)
			)
		)
	)
	(zone
		(layer "In1.Cu")
		(hatch none 0.5)
		(connect_pads
			(clearance 0)
		)
		(min_thickness 0.25)
		(keepout
			(tracks not_allowed)
			(vias allowed)
			(pads allowed)
			(copperpour not_allowed)
			(footprints allowed)
		)
		(placement
			(enabled no)
			(sheetname "")
		)
		(fill
			(thermal_gap 0.5)
			(thermal_bridge_width 0.5)
			(island_removal_mode 0)
		)
		(polygon
			(pts
				(arc
					(start 165.177216 -239.23244)
					(mid 165.173496 -239.24142)
					(end 165.164516 -239.24514)
				)
				(arc
					(start 163.691316 -239.24514)
					(mid 163.682336 -239.24142)
					(end 163.678616 -239.23244)
				)
				(arc
					(start 163.678616 -238.737902)
					(mid 163.682336 -238.728922)
					(end 163.691316 -238.725202)
				)
				(arc
					(start 165.164516 -238.725202)
					(mid 165.173496 -238.728922)
					(end 165.177216 -238.737902)
				)
			)
		)
	)
	(zone
		(layer "In1.Cu")
		(hatch none 0.5)
		(connect_pads
			(clearance 0)
		)
		(min_thickness 0.25)
		(keepout
			(tracks not_allowed)
			(vias allowed)
			(pads allowed)
			(copperpour not_allowed)
			(footprints allowed)
		)
		(placement
			(enabled no)
			(sheetname "")
		)
		(fill
			(thermal_gap 0.5)
			(thermal_bridge_width 0.5)
			(island_removal_mode 0)
		)
		(polygon
			(pts
				(arc
					(start 281.385264 -226.482148)
					(mid 281.381544 -226.491128)
					(end 281.372564 -226.494848)
				)
				(arc
					(start 279.899364 -226.494848)
					(mid 279.890384 -226.491128)
					(end 279.886664 -226.482148)
				)
				(arc
					(start 279.886664 -225.98761)
					(mid 279.890384 -225.97863)
					(end 279.899364 -225.97491)
				)
				(arc
					(start 281.372564 -225.97491)
					(mid 281.381544 -225.97863)
					(end 281.385264 -225.98761)
				)
			)
		)
	)
	(zone
		(layer "In1.Cu")
		(hatch none 0.5)
		(connect_pads
			(clearance 0)
		)
		(min_thickness 0.25)
		(keepout
			(tracks not_allowed)
			(vias allowed)
			(pads allowed)
			(copperpour not_allowed)
			(footprints allowed)
		)
		(placement
			(enabled no)
			(sheetname "")
		)
		(fill
			(thermal_gap 0.5)
			(thermal_bridge_width 0.5)
			(island_removal_mode 0)
		)
		(polygon
			(pts
				(arc
					(start 270.397478 -254.53213)
					(mid 270.393758 -254.54111)
					(end 270.384778 -254.54483)
				)
				(arc
					(start 268.911578 -254.54483)
					(mid 268.902598 -254.54111)
					(end 268.898878 -254.53213)
				)
				(arc
					(start 268.898878 -254.037592)
					(mid 268.902598 -254.028612)
					(end 268.911578 -254.024892)
				)
				(arc
					(start 270.384778 -254.024892)
					(mid 270.393758 -254.028612)
					(end 270.397478 -254.037592)
				)
			)
		)
	)
	(zone
		(layer "In1.Cu")
		(hatch none 0.5)
		(connect_pads
			(clearance 0)
		)
		(min_thickness 0.25)
		(keepout
			(tracks not_allowed)
			(vias allowed)
			(pads allowed)
			(copperpour not_allowed)
			(footprints allowed)
		)
		(placement
			(enabled no)
			(sheetname "")
		)
		(fill
			(thermal_gap 0.5)
			(thermal_bridge_width 0.5)
			(island_removal_mode 0)
		)
		(polygon
			(pts
				(arc
					(start 191.909446 -289.382454)
					(mid 191.905726 -289.391434)
					(end 191.896746 -289.395154)
				)
				(arc
					(start 190.423546 -289.395154)
					(mid 190.414566 -289.391434)
					(end 190.410846 -289.382454)
				)
				(arc
					(start 190.410846 -288.887916)
					(mid 190.414566 -288.878936)
					(end 190.423546 -288.875216)
				)
				(arc
					(start 191.896746 -288.875216)
					(mid 191.905726 -288.878936)
					(end 191.909446 -288.887916)
				)
			)
		)
	)
	(zone
		(layer "In1.Cu")
		(hatch none 0.5)
		(connect_pads
			(clearance 0)
		)
		(min_thickness 0.25)
		(keepout
			(tracks not_allowed)
			(vias allowed)
			(pads allowed)
			(copperpour not_allowed)
			(footprints allowed)
		)
		(placement
			(enabled no)
			(sheetname "")
		)
		(fill
			(thermal_gap 0.5)
			(thermal_bridge_width 0.5)
			(island_removal_mode 0)
		)
		(polygon
			(pts
				(arc
					(start 277.941532 -298.732194)
					(mid 277.937812 -298.741174)
					(end 277.928832 -298.744894)
				)
				(arc
					(start 276.455632 -298.744894)
					(mid 276.446652 -298.741174)
					(end 276.442932 -298.732194)
				)
				(arc
					(start 276.442932 -298.237656)
					(mid 276.446652 -298.228676)
					(end 276.455632 -298.224956)
				)
				(arc
					(start 277.928832 -298.224956)
					(mid 277.937812 -298.228676)
					(end 277.941532 -298.237656)
				)
			)
		)
	)
	(zone
		(layer "In1.Cu")
		(hatch none 0.5)
		(connect_pads
			(clearance 0)
		)
		(min_thickness 0.25)
		(keepout
			(tracks not_allowed)
			(vias allowed)
			(pads allowed)
			(copperpour not_allowed)
			(footprints allowed)
		)
		(placement
			(enabled no)
			(sheetname "")
		)
		(fill
			(thermal_gap 0.5)
			(thermal_bridge_width 0.5)
			(island_removal_mode 0)
		)
		(polygon
			(pts
				(arc
					(start 45.089318 -216.282524)
					(mid 45.085598 -216.291504)
					(end 45.076618 -216.295224)
				)
				(arc
					(start 43.603418 -216.295224)
					(mid 43.594438 -216.291504)
					(end 43.590718 -216.282524)
				)
				(arc
					(start 43.590718 -215.787986)
					(mid 43.594438 -215.779006)
					(end 43.603418 -215.775286)
				)
				(arc
					(start 45.076618 -215.775286)
					(mid 45.085598 -215.779006)
					(end 45.089318 -215.787986)
				)
			)
		)
	)
	(zone
		(layer "In1.Cu")
		(hatch none 0.5)
		(connect_pads
			(clearance 0)
		)
		(min_thickness 0.25)
		(keepout
			(tracks not_allowed)
			(vias allowed)
			(pads allowed)
			(copperpour not_allowed)
			(footprints allowed)
		)
		(placement
			(enabled no)
			(sheetname "")
		)
		(fill
			(thermal_gap 0.5)
			(thermal_bridge_width 0.5)
			(island_removal_mode 0)
		)
		(polygon
			(pts
				(arc
					(start 176.821338 -285.98241)
					(mid 176.817618 -285.99139)
					(end 176.808638 -285.99511)
				)
				(arc
					(start 175.335438 -285.99511)
					(mid 175.326458 -285.99139)
					(end 175.322738 -285.98241)
				)
				(arc
					(start 175.322738 -285.487872)
					(mid 175.326458 -285.478892)
					(end 175.335438 -285.475172)
				)
				(arc
					(start 176.808638 -285.475172)
					(mid 176.817618 -285.478892)
					(end 176.821338 -285.487872)
				)
			)
		)
	)
	(zone
		(layer "In1.Cu")
		(hatch none 0.5)
		(connect_pads
			(clearance 0)
		)
		(min_thickness 0.25)
		(keepout
			(tracks not_allowed)
			(vias allowed)
			(pads allowed)
			(copperpour not_allowed)
			(footprints allowed)
		)
		(placement
			(enabled no)
			(sheetname "")
		)
		(fill
			(thermal_gap 0.5)
			(thermal_bridge_width 0.5)
			(island_removal_mode 0)
		)
		(polygon
			(pts
				(arc
					(start 304.017426 -262.182102)
					(mid 304.013706 -262.191082)
					(end 304.004726 -262.194802)
				)
				(arc
					(start 302.531526 -262.194802)
					(mid 302.522546 -262.191082)
					(end 302.518826 -262.182102)
				)
				(arc
					(start 302.518826 -261.687564)
					(mid 302.522546 -261.678584)
					(end 302.531526 -261.674864)
				)
				(arc
					(start 304.004726 -261.674864)
					(mid 304.013706 -261.678584)
					(end 304.017426 -261.687564)
				)
			)
		)
	)
	(zone
		(layer "In1.Cu")
		(hatch none 0.5)
		(connect_pads
			(clearance 0)
		)
		(min_thickness 0.25)
		(keepout
			(tracks not_allowed)
			(vias allowed)
			(pads allowed)
			(copperpour not_allowed)
			(footprints allowed)
		)
		(placement
			(enabled no)
			(sheetname "")
		)
		(fill
			(thermal_gap 0.5)
			(thermal_bridge_width 0.5)
			(island_removal_mode 0)
		)
		(polygon
			(pts
				(arc
					(start 206.5782 -231.335326)
					(mid 205.9178 -231.335326)
					(end 206.5782 -231.335326)
				)
			)
		)
	)
	(zone
		(layer "In1.Cu")
		(hatch none 0.5)
		(connect_pads
			(clearance 0)
		)
		(min_thickness 0.25)
		(keepout
			(tracks not_allowed)
			(vias allowed)
			(pads allowed)
			(copperpour not_allowed)
			(footprints allowed)
		)
		(placement
			(enabled no)
			(sheetname "")
		)
		(fill
			(thermal_gap 0.5)
			(thermal_bridge_width 0.5)
			(island_removal_mode 0)
		)
		(polygon
			(pts
				(arc
					(start 48.533304 -232.432352)
					(mid 48.529584 -232.441332)
					(end 48.520604 -232.445052)
				)
				(arc
					(start 47.047404 -232.445052)
					(mid 47.038424 -232.441332)
					(end 47.034704 -232.432352)
				)
				(arc
					(start 47.034704 -231.937814)
					(mid 47.038424 -231.928834)
					(end 47.047404 -231.925114)
				)
				(arc
					(start 48.520604 -231.925114)
					(mid 48.529584 -231.928834)
					(end 48.533304 -231.937814)
				)
			)
		)
	)
	(zone
		(layer "In1.Cu")
		(hatch none 0.5)
		(connect_pads
			(clearance 0)
		)
		(min_thickness 0.25)
		(keepout
			(tracks not_allowed)
			(vias allowed)
			(pads allowed)
			(copperpour not_allowed)
			(footprints allowed)
		)
		(placement
			(enabled no)
			(sheetname "")
		)
		(fill
			(thermal_gap 0.5)
			(thermal_bridge_width 0.5)
			(island_removal_mode 0)
		)
		(polygon
			(pts
				(arc
					(start 428.205392 -277.4823)
					(mid 428.201672 -277.49128)
					(end 428.192692 -277.495)
				)
				(arc
					(start 426.719492 -277.495)
					(mid 426.710512 -277.49128)
					(end 426.706792 -277.4823)
				)
				(arc
					(start 426.706792 -276.987762)
					(mid 426.710512 -276.978782)
					(end 426.719492 -276.975062)
				)
				(arc
					(start 428.192692 -276.975062)
					(mid 428.201672 -276.978782)
					(end 428.205392 -276.987762)
				)
			)
		)
	)
	(zone
		(layer "In1.Cu")
		(hatch none 0.5)
		(connect_pads
			(clearance 0)
		)
		(min_thickness 0.25)
		(keepout
			(tracks not_allowed)
			(vias allowed)
			(pads allowed)
			(copperpour not_allowed)
			(footprints allowed)
		)
		(placement
			(enabled no)
			(sheetname "")
		)
		(fill
			(thermal_gap 0.5)
			(thermal_bridge_width 0.5)
			(island_removal_mode 0)
		)
		(polygon
			(pts
				(arc
					(start 351.697798 -399.143474)
					(mid 351.392998 -399.143474)
					(end 351.697798 -399.143474)
				)
			)
		)
	)
	(zone
		(layer "In1.Cu")
		(hatch none 0.5)
		(connect_pads
			(clearance 0)
		)
		(min_thickness 0.25)
		(keepout
			(tracks not_allowed)
			(vias allowed)
			(pads allowed)
			(copperpour not_allowed)
			(footprints allowed)
		)
		(placement
			(enabled no)
			(sheetname "")
		)
		(fill
			(thermal_gap 0.5)
			(thermal_bridge_width 0.5)
			(island_removal_mode 0)
		)
		(polygon
			(pts
				(arc
					(start 439.849514 -276.632162)
					(mid 439.845794 -276.641142)
					(end 439.836814 -276.644862)
				)
				(arc
					(start 438.363614 -276.644862)
					(mid 438.354634 -276.641142)
					(end 438.350914 -276.632162)
				)
				(arc
					(start 438.350914 -276.137624)
					(mid 438.354634 -276.128644)
					(end 438.363614 -276.124924)
				)
				(arc
					(start 439.836814 -276.124924)
					(mid 439.845794 -276.128644)
					(end 439.849514 -276.137624)
				)
			)
		)
	)
	(zone
		(layer "In1.Cu")
		(hatch none 0.5)
		(connect_pads
			(clearance 0)
		)
		(min_thickness 0.25)
		(keepout
			(tracks not_allowed)
			(vias allowed)
			(pads allowed)
			(copperpour not_allowed)
			(footprints allowed)
		)
		(placement
			(enabled no)
			(sheetname "")
		)
		(fill
			(thermal_gap 0.5)
			(thermal_bridge_width 0.5)
			(island_removal_mode 0)
		)
		(polygon
			(pts
				(arc
					(start 116.161058 -389.467344)
					(mid 115.780058 -389.467344)
					(end 116.161058 -389.467344)
				)
			)
		)
	)
	(zone
		(layer "In1.Cu")
		(hatch none 0.5)
		(connect_pads
			(clearance 0)
		)
		(min_thickness 0.25)
		(keepout
			(tracks not_allowed)
			(vias allowed)
			(pads allowed)
			(copperpour not_allowed)
			(footprints allowed)
		)
		(placement
			(enabled no)
			(sheetname "")
		)
		(fill
			(thermal_gap 0.5)
			(thermal_bridge_width 0.5)
			(island_removal_mode 0)
		)
		(polygon
			(pts
				(arc
					(start 206.5782 -197.335394)
					(mid 205.9178 -197.335394)
					(end 206.5782 -197.335394)
				)
			)
		)
	)
	(zone
		(layer "In1.Cu")
		(hatch none 0.5)
		(connect_pads
			(clearance 0)
		)
		(min_thickness 0.25)
		(keepout
			(tracks not_allowed)
			(vias allowed)
			(pads allowed)
			(copperpour not_allowed)
			(footprints allowed)
		)
		(placement
			(enabled no)
			(sheetname "")
		)
		(fill
			(thermal_gap 0.5)
			(thermal_bridge_width 0.5)
			(island_removal_mode 0)
		)
		(polygon
			(pts
				(arc
					(start 424.761406 -306.382166)
					(mid 424.757686 -306.391146)
					(end 424.748706 -306.394866)
				)
				(arc
					(start 423.275506 -306.394866)
					(mid 423.266526 -306.391146)
					(end 423.262806 -306.382166)
				)
				(arc
					(start 423.262806 -305.887628)
					(mid 423.266526 -305.878648)
					(end 423.275506 -305.874928)
				)
				(arc
					(start 424.748706 -305.874928)
					(mid 424.757686 -305.878648)
					(end 424.761406 -305.887628)
				)
			)
		)
	)
	(zone
		(layer "In1.Cu")
		(hatch none 0.5)
		(connect_pads
			(clearance 0)
		)
		(min_thickness 0.25)
		(keepout
			(tracks not_allowed)
			(vias allowed)
			(pads allowed)
			(copperpour not_allowed)
			(footprints allowed)
		)
		(placement
			(enabled no)
			(sheetname "")
		)
		(fill
			(thermal_gap 0.5)
			(thermal_bridge_width 0.5)
			(island_removal_mode 0)
		)
		(polygon
			(pts
				(arc
					(start 288.929318 -201.83221)
					(mid 288.925598 -201.84119)
					(end 288.916618 -201.84491)
				)
				(arc
					(start 287.443418 -201.84491)
					(mid 287.434438 -201.84119)
					(end 287.430718 -201.83221)
				)
				(arc
					(start 287.430718 -201.337672)
					(mid 287.434438 -201.328692)
					(end 287.443418 -201.324972)
				)
				(arc
					(start 288.916618 -201.324972)
					(mid 288.925598 -201.328692)
					(end 288.929318 -201.337672)
				)
			)
		)
	)
	(zone
		(layer "In1.Cu")
		(hatch none 0.5)
		(connect_pads
			(clearance 0)
		)
		(min_thickness 0.25)
		(keepout
			(tracks not_allowed)
			(vias allowed)
			(pads allowed)
			(copperpour not_allowed)
			(footprints allowed)
		)
		(placement
			(enabled no)
			(sheetname "")
		)
		(fill
			(thermal_gap 0.5)
			(thermal_bridge_width 0.5)
			(island_removal_mode 0)
		)
		(polygon
			(pts
				(arc
					(start 169.277284 -223.932496)
					(mid 169.273564 -223.941476)
					(end 169.264584 -223.945196)
				)
				(arc
					(start 167.791384 -223.945196)
					(mid 167.782404 -223.941476)
					(end 167.778684 -223.932496)
				)
				(arc
					(start 167.778684 -223.437958)
					(mid 167.782404 -223.428978)
					(end 167.791384 -223.425258)
				)
				(arc
					(start 169.264584 -223.425258)
					(mid 169.273564 -223.428978)
					(end 169.277284 -223.437958)
				)
			)
		)
	)
	(zone
		(layer "In1.Cu")
		(hatch none 0.5)
		(connect_pads
			(clearance 0)
		)
		(min_thickness 0.25)
		(keepout
			(tracks not_allowed)
			(vias allowed)
			(pads allowed)
			(copperpour not_allowed)
			(footprints allowed)
		)
		(placement
			(enabled no)
			(sheetname "")
		)
		(fill
			(thermal_gap 0.5)
			(thermal_bridge_width 0.5)
			(island_removal_mode 0)
		)
		(polygon
			(pts
				(arc
					(start 55.970424 -390.761474)
					(mid 55.665624 -390.761474)
					(end 55.970424 -390.761474)
				)
			)
		)
	)
	(zone
		(layer "In1.Cu")
		(hatch none 0.5)
		(connect_pads
			(clearance 0)
		)
		(min_thickness 0.25)
		(keepout
			(tracks not_allowed)
			(vias allowed)
			(pads allowed)
			(copperpour not_allowed)
			(footprints allowed)
		)
		(placement
			(enabled no)
			(sheetname "")
		)
		(fill
			(thermal_gap 0.5)
			(thermal_bridge_width 0.5)
			(island_removal_mode 0)
		)
		(polygon
			(pts
				(arc
					(start 372.161054 -394.385292)
					(mid 371.780054 -394.385292)
					(end 372.161054 -394.385292)
				)
			)
		)
	)
	(zone
		(layer "In1.Cu")
		(hatch none 0.5)
		(connect_pads
			(clearance 0)
		)
		(min_thickness 0.25)
		(keepout
			(tracks not_allowed)
			(vias allowed)
			(pads allowed)
			(copperpour not_allowed)
			(footprints allowed)
		)
		(placement
			(enabled no)
			(sheetname "")
		)
		(fill
			(thermal_gap 0.5)
			(thermal_bridge_width 0.5)
			(island_removal_mode 0)
		)
		(polygon
			(pts
				(arc
					(start 45.089318 -231.582468)
					(mid 45.085598 -231.591448)
					(end 45.076618 -231.595168)
				)
				(arc
					(start 43.603418 -231.595168)
					(mid 43.594438 -231.591448)
					(end 43.590718 -231.582468)
				)
				(arc
					(start 43.590718 -231.08793)
					(mid 43.594438 -231.07895)
					(end 43.603418 -231.07523)
				)
				(arc
					(start 45.076618 -231.07523)
					(mid 45.085598 -231.07895)
					(end 45.089318 -231.08793)
				)
			)
		)
	)
	(zone
		(layer "In1.Cu")
		(hatch none 0.5)
		(connect_pads
			(clearance 0)
		)
		(min_thickness 0.25)
		(keepout
			(tracks not_allowed)
			(vias allowed)
			(pads allowed)
			(copperpour not_allowed)
			(footprints allowed)
		)
		(placement
			(enabled no)
			(sheetname "")
		)
		(fill
			(thermal_gap 0.5)
			(thermal_bridge_width 0.5)
			(island_removal_mode 0)
		)
		(polygon
			(pts
				(arc
					(start 172.72127 -209.482436)
					(mid 172.71755 -209.491416)
					(end 172.70857 -209.495136)
				)
				(arc
					(start 171.23537 -209.495136)
					(mid 171.22639 -209.491416)
					(end 171.22267 -209.482436)
				)
				(arc
					(start 171.22267 -208.987898)
					(mid 171.22639 -208.978918)
					(end 171.23537 -208.975198)
				)
				(arc
					(start 172.70857 -208.975198)
					(mid 172.71755 -208.978918)
					(end 172.72127 -208.987898)
				)
			)
		)
	)
	(zone
		(layer "In1.Cu")
		(hatch none 0.5)
		(connect_pads
			(clearance 0)
		)
		(min_thickness 0.25)
		(keepout
			(tracks not_allowed)
			(vias allowed)
			(pads allowed)
			(copperpour not_allowed)
			(footprints allowed)
		)
		(placement
			(enabled no)
			(sheetname "")
		)
		(fill
			(thermal_gap 0.5)
			(thermal_bridge_width 0.5)
			(island_removal_mode 0)
		)
		(polygon
			(pts
				(arc
					(start 172.72127 -297.882564)
					(mid 172.71755 -297.891544)
					(end 172.70857 -297.895264)
				)
				(arc
					(start 171.23537 -297.895264)
					(mid 171.22639 -297.891544)
					(end 171.22267 -297.882564)
				)
				(arc
					(start 171.22267 -297.388026)
					(mid 171.22639 -297.379046)
					(end 171.23537 -297.375326)
				)
				(arc
					(start 172.70857 -297.375326)
					(mid 172.71755 -297.379046)
					(end 172.72127 -297.388026)
				)
			)
		)
	)
	(zone
		(layer "In1.Cu")
		(hatch none 0.5)
		(connect_pads
			(clearance 0)
		)
		(min_thickness 0.25)
		(keepout
			(tracks not_allowed)
			(vias allowed)
			(pads allowed)
			(copperpour not_allowed)
			(footprints allowed)
		)
		(placement
			(enabled no)
			(sheetname "")
		)
		(fill
			(thermal_gap 0.5)
			(thermal_bridge_width 0.5)
			(island_removal_mode 0)
		)
		(polygon
			(pts
				(arc
					(start 435.749446 -204.382116)
					(mid 435.745726 -204.391096)
					(end 435.736746 -204.394816)
				)
				(arc
					(start 434.263546 -204.394816)
					(mid 434.254566 -204.391096)
					(end 434.250846 -204.382116)
				)
				(arc
					(start 434.250846 -203.887578)
					(mid 434.254566 -203.878598)
					(end 434.263546 -203.874878)
				)
				(arc
					(start 435.736746 -203.874878)
					(mid 435.745726 -203.878598)
					(end 435.749446 -203.887578)
				)
			)
		)
	)
	(zone
		(layer "In1.Cu")
		(hatch none 0.5)
		(connect_pads
			(clearance 0)
		)
		(min_thickness 0.25)
		(keepout
			(tracks not_allowed)
			(vias allowed)
			(pads allowed)
			(copperpour not_allowed)
			(footprints allowed)
		)
		(placement
			(enabled no)
			(sheetname "")
		)
		(fill
			(thermal_gap 0.5)
			(thermal_bridge_width 0.5)
			(island_removal_mode 0)
		)
		(polygon
			(pts
				(arc
					(start 277.941532 -295.33215)
					(mid 277.937812 -295.34113)
					(end 277.928832 -295.34485)
				)
				(arc
					(start 276.455632 -295.34485)
					(mid 276.446652 -295.34113)
					(end 276.442932 -295.33215)
				)
				(arc
					(start 276.442932 -294.837612)
					(mid 276.446652 -294.828632)
					(end 276.455632 -294.824912)
				)
				(arc
					(start 277.928832 -294.824912)
					(mid 277.937812 -294.828632)
					(end 277.941532 -294.837612)
				)
			)
		)
	)
	(zone
		(layer "In1.Cu")
		(hatch none 0.5)
		(connect_pads
			(clearance 0)
		)
		(min_thickness 0.25)
		(keepout
			(tracks not_allowed)
			(vias allowed)
			(pads allowed)
			(copperpour not_allowed)
			(footprints allowed)
		)
		(placement
			(enabled no)
			(sheetname "")
		)
		(fill
			(thermal_gap 0.5)
			(thermal_bridge_width 0.5)
			(island_removal_mode 0)
		)
		(polygon
			(pts
				(arc
					(start 351.118424 -391.822686)
					(mid 351.245424 -391.949686)
					(end 351.372424 -391.822686)
				)
				(arc
					(start 351.372424 -391.746486)
					(mid 351.245424 -391.619486)
					(end 351.118424 -391.746486)
				)
			)
		)
	)
	(zone
		(layer "In1.Cu")
		(hatch none 0.5)
		(connect_pads
			(clearance 0)
		)
		(min_thickness 0.25)
		(keepout
			(tracks not_allowed)
			(vias allowed)
			(pads allowed)
			(copperpour not_allowed)
			(footprints allowed)
		)
		(placement
			(enabled no)
			(sheetname "")
		)
		(fill
			(thermal_gap 0.5)
			(thermal_bridge_width 0.5)
			(island_removal_mode 0)
		)
		(polygon
			(pts
				(arc
					(start 277.941532 -309.78221)
					(mid 277.937812 -309.79119)
					(end 277.928832 -309.79491)
				)
				(arc
					(start 276.455632 -309.79491)
					(mid 276.446652 -309.79119)
					(end 276.442932 -309.78221)
				)
				(arc
					(start 276.442932 -309.287672)
					(mid 276.446652 -309.278692)
					(end 276.455632 -309.274972)
				)
				(arc
					(start 277.928832 -309.274972)
					(mid 277.937812 -309.278692)
					(end 277.941532 -309.287672)
				)
			)
		)
	)
	(zone
		(layer "In1.Cu")
		(hatch none 0.5)
		(connect_pads
			(clearance 0)
		)
		(min_thickness 0.25)
		(keepout
			(tracks not_allowed)
			(vias allowed)
			(pads allowed)
			(copperpour not_allowed)
			(footprints allowed)
		)
		(placement
			(enabled no)
			(sheetname "")
		)
		(fill
			(thermal_gap 0.5)
			(thermal_bridge_width 0.5)
			(island_removal_mode 0)
		)
		(polygon
			(pts
				(arc
					(start 300.57344 -285.982156)
					(mid 300.56972 -285.991136)
					(end 300.56074 -285.994856)
				)
				(arc
					(start 299.08754 -285.994856)
					(mid 299.07856 -285.991136)
					(end 299.07484 -285.982156)
				)
				(arc
					(start 299.07484 -285.487618)
					(mid 299.07856 -285.478638)
					(end 299.08754 -285.474918)
				)
				(arc
					(start 300.56074 -285.474918)
					(mid 300.56972 -285.478638)
					(end 300.57344 -285.487618)
				)
			)
		)
	)
	(zone
		(layer "In1.Cu")
		(hatch none 0.5)
		(connect_pads
			(clearance 0)
		)
		(min_thickness 0.25)
		(keepout
			(tracks not_allowed)
			(vias allowed)
			(pads allowed)
			(copperpour not_allowed)
			(footprints allowed)
		)
		(placement
			(enabled no)
			(sheetname "")
		)
		(fill
			(thermal_gap 0.5)
			(thermal_bridge_width 0.5)
			(island_removal_mode 0)
		)
		(polygon
			(pts
				(arc
					(start 265.87831 -244.934994)
					(mid 265.21791 -244.934994)
					(end 265.87831 -244.934994)
				)
			)
		)
	)
	(zone
		(layer "In1.Cu")
		(hatch none 0.5)
		(connect_pads
			(clearance 0)
		)
		(min_thickness 0.25)
		(keepout
			(tracks not_allowed)
			(vias allowed)
			(pads allowed)
			(copperpour not_allowed)
			(footprints allowed)
		)
		(placement
			(enabled no)
			(sheetname "")
		)
		(fill
			(thermal_gap 0.5)
			(thermal_bridge_width 0.5)
			(island_removal_mode 0)
		)
		(polygon
			(pts
				(arc
					(start 308.117494 -292.782244)
					(mid 308.113774 -292.791224)
					(end 308.104794 -292.794944)
				)
				(arc
					(start 306.631594 -292.794944)
					(mid 306.622614 -292.791224)
					(end 306.618894 -292.782244)
				)
				(arc
					(start 306.618894 -292.287706)
					(mid 306.622614 -292.278726)
					(end 306.631594 -292.275006)
				)
				(arc
					(start 308.104794 -292.275006)
					(mid 308.113774 -292.278726)
					(end 308.117494 -292.287706)
				)
			)
		)
	)
	(zone
		(layer "In1.Cu")
		(hatch none 0.5)
		(connect_pads
			(clearance 0)
		)
		(min_thickness 0.25)
		(keepout
			(tracks not_allowed)
			(vias allowed)
			(pads allowed)
			(copperpour not_allowed)
			(footprints allowed)
		)
		(placement
			(enabled no)
			(sheetname "")
		)
		(fill
			(thermal_gap 0.5)
			(thermal_bridge_width 0.5)
			(island_removal_mode 0)
		)
		(polygon
			(pts
				(arc
					(start 37.545264 -239.23244)
					(mid 37.541544 -239.24142)
					(end 37.532564 -239.24514)
				)
				(arc
					(start 36.059364 -239.24514)
					(mid 36.050384 -239.24142)
					(end 36.046664 -239.23244)
				)
				(arc
					(start 36.046664 -238.737902)
					(mid 36.050384 -238.728922)
					(end 36.059364 -238.725202)
				)
				(arc
					(start 37.532564 -238.725202)
					(mid 37.541544 -238.728922)
					(end 37.545264 -238.737902)
				)
			)
		)
	)
	(zone
		(layer "In1.Cu")
		(hatch none 0.5)
		(connect_pads
			(clearance 0)
		)
		(min_thickness 0.25)
		(keepout
			(tracks not_allowed)
			(vias allowed)
			(pads allowed)
			(copperpour not_allowed)
			(footprints allowed)
		)
		(placement
			(enabled no)
			(sheetname "")
		)
		(fill
			(thermal_gap 0.5)
			(thermal_bridge_width 0.5)
			(island_removal_mode 0)
		)
		(polygon
			(pts
				(arc
					(start 454.937368 -227.332286)
					(mid 454.933648 -227.341266)
					(end 454.924668 -227.344986)
				)
				(arc
					(start 453.451468 -227.344986)
					(mid 453.442488 -227.341266)
					(end 453.438768 -227.332286)
				)
				(arc
					(start 453.438768 -226.837748)
					(mid 453.442488 -226.828768)
					(end 453.451468 -226.825048)
				)
				(arc
					(start 454.924668 -226.825048)
					(mid 454.933648 -226.828768)
					(end 454.937368 -226.837748)
				)
			)
		)
	)
	(zone
		(layer "In1.Cu")
		(hatch none 0.5)
		(connect_pads
			(clearance 0)
		)
		(min_thickness 0.25)
		(keepout
			(tracks not_allowed)
			(vias allowed)
			(pads allowed)
			(copperpour not_allowed)
			(footprints allowed)
		)
		(placement
			(enabled no)
			(sheetname "")
		)
		(fill
			(thermal_gap 0.5)
			(thermal_bridge_width 0.5)
			(island_removal_mode 0)
		)
		(polygon
			(pts
				(arc
					(start 450.8373 -318.28232)
					(mid 450.83358 -318.2913)
					(end 450.8246 -318.29502)
				)
				(arc
					(start 449.3514 -318.29502)
					(mid 449.34242 -318.2913)
					(end 449.3387 -318.28232)
				)
				(arc
					(start 449.3387 -317.787782)
					(mid 449.34242 -317.778802)
					(end 449.3514 -317.775082)
				)
				(arc
					(start 450.8246 -317.775082)
					(mid 450.83358 -317.778802)
					(end 450.8373 -317.787782)
				)
			)
		)
	)
	(zone
		(layer "In1.Cu")
		(hatch none 0.5)
		(connect_pads
			(clearance 0)
		)
		(min_thickness 0.25)
		(keepout
			(tracks not_allowed)
			(vias allowed)
			(pads allowed)
			(copperpour not_allowed)
			(footprints allowed)
		)
		(placement
			(enabled no)
			(sheetname "")
		)
		(fill
			(thermal_gap 0.5)
			(thermal_bridge_width 0.5)
			(island_removal_mode 0)
		)
		(polygon
			(pts
				(arc
					(start 115.870228 -383.92227)
					(mid 115.565428 -383.92227)
					(end 115.870228 -383.92227)
				)
			)
		)
	)
	(zone
		(layer "In1.Cu")
		(hatch none 0.5)
		(connect_pads
			(clearance 0)
		)
		(min_thickness 0.25)
		(keepout
			(tracks not_allowed)
			(vias allowed)
			(pads allowed)
			(copperpour not_allowed)
			(footprints allowed)
		)
		(placement
			(enabled no)
			(sheetname "")
		)
		(fill
			(thermal_gap 0.5)
			(thermal_bridge_width 0.5)
			(island_removal_mode 0)
		)
		(polygon
			(pts
				(arc
					(start 439.849514 -311.482232)
					(mid 439.845794 -311.491212)
					(end 439.836814 -311.494932)
				)
				(arc
					(start 438.363614 -311.494932)
					(mid 438.354634 -311.491212)
					(end 438.350914 -311.482232)
				)
				(arc
					(start 438.350914 -310.987694)
					(mid 438.354634 -310.978714)
					(end 438.363614 -310.974994)
				)
				(arc
					(start 439.836814 -310.974994)
					(mid 439.845794 -310.978714)
					(end 439.849514 -310.987694)
				)
			)
		)
	)
	(zone
		(layer "In1.Cu")
		(hatch none 0.5)
		(connect_pads
			(clearance 0)
		)
		(min_thickness 0.25)
		(keepout
			(tracks not_allowed)
			(vias allowed)
			(pads allowed)
			(copperpour not_allowed)
			(footprints allowed)
		)
		(placement
			(enabled no)
			(sheetname "")
		)
		(fill
			(thermal_gap 0.5)
			(thermal_bridge_width 0.5)
			(island_removal_mode 0)
		)
		(polygon
			(pts
				(arc
					(start 443.2935 -314.882276)
					(mid 443.28978 -314.891256)
					(end 443.2808 -314.894976)
				)
				(arc
					(start 441.8076 -314.894976)
					(mid 441.79862 -314.891256)
					(end 441.7949 -314.882276)
				)
				(arc
					(start 441.7949 -314.387738)
					(mid 441.79862 -314.378758)
					(end 441.8076 -314.375038)
				)
				(arc
					(start 443.2808 -314.375038)
					(mid 443.28978 -314.378758)
					(end 443.2935 -314.387738)
				)
			)
		)
	)
	(zone
		(layer "In1.Cu")
		(hatch none 0.5)
		(connect_pads
			(clearance 0)
		)
		(min_thickness 0.25)
		(keepout
			(tracks not_allowed)
			(vias allowed)
			(pads allowed)
			(copperpour not_allowed)
			(footprints allowed)
		)
		(placement
			(enabled no)
			(sheetname "")
		)
		(fill
			(thermal_gap 0.5)
			(thermal_bridge_width 0.5)
			(island_removal_mode 0)
		)
		(polygon
			(pts
				(arc
					(start 380.270258 -392.30427)
					(mid 379.965458 -392.30427)
					(end 380.270258 -392.30427)
				)
			)
		)
	)
	(zone
		(layer "In1.Cu")
		(hatch none 0.5)
		(connect_pads
			(clearance 0)
		)
		(min_thickness 0.25)
		(keepout
			(tracks not_allowed)
			(vias allowed)
			(pads allowed)
			(copperpour not_allowed)
			(footprints allowed)
		)
		(placement
			(enabled no)
			(sheetname "")
		)
		(fill
			(thermal_gap 0.5)
			(thermal_bridge_width 0.5)
			(island_removal_mode 0)
		)
		(polygon
			(pts
				(arc
					(start 22.45741 -264.732516)
					(mid 22.45369 -264.741496)
					(end 22.44471 -264.745216)
				)
				(arc
					(start 20.97151 -264.745216)
					(mid 20.96253 -264.741496)
					(end 20.95881 -264.732516)
				)
				(arc
					(start 20.95881 -264.237978)
					(mid 20.96253 -264.228998)
					(end 20.97151 -264.225278)
				)
				(arc
					(start 22.44471 -264.225278)
					(mid 22.45369 -264.228998)
					(end 22.45741 -264.237978)
				)
			)
		)
	)
	(zone
		(layer "In1.Cu")
		(hatch none 0.5)
		(connect_pads
			(clearance 0)
		)
		(min_thickness 0.25)
		(keepout
			(tracks not_allowed)
			(vias allowed)
			(pads allowed)
			(copperpour not_allowed)
			(footprints allowed)
		)
		(placement
			(enabled no)
			(sheetname "")
		)
		(fill
			(thermal_gap 0.5)
			(thermal_bridge_width 0.5)
			(island_removal_mode 0)
		)
		(polygon
			(pts
				(arc
					(start 40.98925 -251.982478)
					(mid 40.98553 -251.991458)
					(end 40.97655 -251.995178)
				)
				(arc
					(start 39.50335 -251.995178)
					(mid 39.49437 -251.991458)
					(end 39.49065 -251.982478)
				)
				(arc
					(start 39.49065 -251.48794)
					(mid 39.49437 -251.47896)
					(end 39.50335 -251.47524)
				)
				(arc
					(start 40.97655 -251.47524)
					(mid 40.98553 -251.47896)
					(end 40.98925 -251.48794)
				)
			)
		)
	)
	(zone
		(layer "In1.Cu")
		(hatch none 0.5)
		(connect_pads
			(clearance 0)
		)
		(min_thickness 0.25)
		(keepout
			(tracks not_allowed)
			(vias allowed)
			(pads allowed)
			(copperpour not_allowed)
			(footprints allowed)
		)
		(placement
			(enabled no)
			(sheetname "")
		)
		(fill
			(thermal_gap 0.5)
			(thermal_bridge_width 0.5)
			(island_removal_mode 0)
		)
		(polygon
			(pts
				(arc
					(start 273.841464 -262.182102)
					(mid 273.837744 -262.191082)
					(end 273.828764 -262.194802)
				)
				(arc
					(start 272.355564 -262.194802)
					(mid 272.346584 -262.191082)
					(end 272.342864 -262.182102)
				)
				(arc
					(start 272.342864 -261.687564)
					(mid 272.346584 -261.678584)
					(end 272.355564 -261.674864)
				)
				(arc
					(start 273.828764 -261.674864)
					(mid 273.837744 -261.678584)
					(end 273.841464 -261.687564)
				)
			)
		)
	)
	(zone
		(layer "In1.Cu")
		(hatch none 0.5)
		(connect_pads
			(clearance 0)
		)
		(min_thickness 0.25)
		(keepout
			(tracks not_allowed)
			(vias allowed)
			(pads allowed)
			(copperpour not_allowed)
			(footprints allowed)
		)
		(placement
			(enabled no)
			(sheetname "")
		)
		(fill
			(thermal_gap 0.5)
			(thermal_bridge_width 0.5)
			(island_removal_mode 0)
		)
		(polygon
			(pts
				(arc
					(start 308.117494 -300.432216)
					(mid 308.113774 -300.441196)
					(end 308.104794 -300.444916)
				)
				(arc
					(start 306.631594 -300.444916)
					(mid 306.622614 -300.441196)
					(end 306.618894 -300.432216)
				)
				(arc
					(start 306.618894 -299.937678)
					(mid 306.622614 -299.928698)
					(end 306.631594 -299.924978)
				)
				(arc
					(start 308.104794 -299.924978)
					(mid 308.113774 -299.928698)
					(end 308.117494 -299.937678)
				)
			)
		)
	)
	(zone
		(layer "In1.Cu")
		(hatch none 0.5)
		(connect_pads
			(clearance 0)
		)
		(min_thickness 0.25)
		(keepout
			(tracks not_allowed)
			(vias allowed)
			(pads allowed)
			(copperpour not_allowed)
			(footprints allowed)
		)
		(placement
			(enabled no)
			(sheetname "")
		)
		(fill
			(thermal_gap 0.5)
			(thermal_bridge_width 0.5)
			(island_removal_mode 0)
		)
		(polygon
			(pts
				(arc
					(start 161.488882 -385.31038)
					(mid 161.107882 -385.31038)
					(end 161.488882 -385.31038)
				)
			)
		)
	)
	(zone
		(layer "In1.Cu")
		(hatch none 0.5)
		(connect_pads
			(clearance 0)
		)
		(min_thickness 0.25)
		(keepout
			(tracks not_allowed)
			(vias allowed)
			(pads allowed)
			(copperpour not_allowed)
			(footprints allowed)
		)
		(placement
			(enabled no)
			(sheetname "")
		)
		(fill
			(thermal_gap 0.5)
			(thermal_bridge_width 0.5)
			(island_removal_mode 0)
		)
		(polygon
			(pts
				(arc
					(start 424.761406 -269.832328)
					(mid 424.757686 -269.841308)
					(end 424.748706 -269.845028)
				)
				(arc
					(start 423.275506 -269.845028)
					(mid 423.266526 -269.841308)
					(end 423.262806 -269.832328)
				)
				(arc
					(start 423.262806 -269.33779)
					(mid 423.266526 -269.32881)
					(end 423.275506 -269.32509)
				)
				(arc
					(start 424.748706 -269.32509)
					(mid 424.757686 -269.32881)
					(end 424.761406 -269.33779)
				)
			)
		)
	)
	(zone
		(layer "In1.Cu")
		(hatch none 0.5)
		(connect_pads
			(clearance 0)
		)
		(min_thickness 0.25)
		(keepout
			(tracks not_allowed)
			(vias allowed)
			(pads allowed)
			(copperpour not_allowed)
			(footprints allowed)
		)
		(placement
			(enabled no)
			(sheetname "")
		)
		(fill
			(thermal_gap 0.5)
			(thermal_bridge_width 0.5)
			(island_removal_mode 0)
		)
		(polygon
			(pts
				(arc
					(start 37.545264 -311.482486)
					(mid 37.541544 -311.491466)
					(end 37.532564 -311.495186)
				)
				(arc
					(start 36.059364 -311.495186)
					(mid 36.050384 -311.491466)
					(end 36.046664 -311.482486)
				)
				(arc
					(start 36.046664 -310.987948)
					(mid 36.050384 -310.978968)
					(end 36.059364 -310.975248)
				)
				(arc
					(start 37.532564 -310.975248)
					(mid 37.541544 -310.978968)
					(end 37.545264 -310.987948)
				)
			)
		)
	)
	(zone
		(layer "In1.Cu")
		(hatch none 0.5)
		(connect_pads
			(clearance 0)
		)
		(min_thickness 0.25)
		(keepout
			(tracks not_allowed)
			(vias allowed)
			(pads allowed)
			(copperpour not_allowed)
			(footprints allowed)
		)
		(placement
			(enabled no)
			(sheetname "")
		)
		(fill
			(thermal_gap 0.5)
			(thermal_bridge_width 0.5)
			(island_removal_mode 0)
		)
		(polygon
			(pts
				(arc
					(start 165.177216 -314.032392)
					(mid 165.173496 -314.041372)
					(end 165.164516 -314.045092)
				)
				(arc
					(start 163.691316 -314.045092)
					(mid 163.682336 -314.041372)
					(end 163.678616 -314.032392)
				)
				(arc
					(start 163.678616 -313.537854)
					(mid 163.682336 -313.528874)
					(end 163.691316 -313.525154)
				)
				(arc
					(start 165.164516 -313.525154)
					(mid 165.173496 -313.528874)
					(end 165.177216 -313.537854)
				)
			)
		)
	)
	(zone
		(layer "In1.Cu")
		(hatch none 0.5)
		(connect_pads
			(clearance 0)
		)
		(min_thickness 0.25)
		(keepout
			(tracks not_allowed)
			(vias allowed)
			(pads allowed)
			(copperpour not_allowed)
			(footprints allowed)
		)
		(placement
			(enabled no)
			(sheetname "")
		)
		(fill
			(thermal_gap 0.5)
			(thermal_bridge_width 0.5)
			(island_removal_mode 0)
		)
		(polygon
			(pts
				(arc
					(start 169.277284 -249.432572)
					(mid 169.273564 -249.441552)
					(end 169.264584 -249.445272)
				)
				(arc
					(start 167.791384 -249.445272)
					(mid 167.782404 -249.441552)
					(end 167.778684 -249.432572)
				)
				(arc
					(start 167.778684 -248.938034)
					(mid 167.782404 -248.929054)
					(end 167.791384 -248.925334)
				)
				(arc
					(start 169.264584 -248.925334)
					(mid 169.273564 -248.929054)
					(end 169.277284 -248.938034)
				)
			)
		)
	)
	(zone
		(layer "In1.Cu")
		(hatch none 0.5)
		(connect_pads
			(clearance 0)
		)
		(min_thickness 0.25)
		(keepout
			(tracks not_allowed)
			(vias allowed)
			(pads allowed)
			(copperpour not_allowed)
			(footprints allowed)
		)
		(placement
			(enabled no)
			(sheetname "")
		)
		(fill
			(thermal_gap 0.5)
			(thermal_bridge_width 0.5)
			(island_removal_mode 0)
		)
		(polygon
			(pts
				(arc
					(start 40.98925 -239.23244)
					(mid 40.98553 -239.24142)
					(end 40.97655 -239.24514)
				)
				(arc
					(start 39.50335 -239.24514)
					(mid 39.49437 -239.24142)
					(end 39.49065 -239.23244)
				)
				(arc
					(start 39.49065 -238.737902)
					(mid 39.49437 -238.728922)
					(end 39.50335 -238.725202)
				)
				(arc
					(start 40.97655 -238.725202)
					(mid 40.98553 -238.728922)
					(end 40.98925 -238.737902)
				)
			)
		)
	)
	(zone
		(layer "In1.Cu")
		(hatch none 0.5)
		(connect_pads
			(clearance 0)
		)
		(min_thickness 0.25)
		(keepout
			(tracks not_allowed)
			(vias allowed)
			(pads allowed)
			(copperpour not_allowed)
			(footprints allowed)
		)
		(placement
			(enabled no)
			(sheetname "")
		)
		(fill
			(thermal_gap 0.5)
			(thermal_bridge_width 0.5)
			(island_removal_mode 0)
		)
		(polygon
			(pts
				(arc
					(start 187.809378 -201.832464)
					(mid 187.805658 -201.841444)
					(end 187.796678 -201.845164)
				)
				(arc
					(start 186.323478 -201.845164)
					(mid 186.314498 -201.841444)
					(end 186.310778 -201.832464)
				)
				(arc
					(start 186.310778 -201.337926)
					(mid 186.314498 -201.328946)
					(end 186.323478 -201.325226)
				)
				(arc
					(start 187.796678 -201.325226)
					(mid 187.805658 -201.328946)
					(end 187.809378 -201.337926)
				)
			)
		)
	)
	(zone
		(layer "In1.Cu")
		(hatch none 0.5)
		(connect_pads
			(clearance 0)
		)
		(min_thickness 0.25)
		(keepout
			(tracks not_allowed)
			(vias allowed)
			(pads allowed)
			(copperpour not_allowed)
			(footprints allowed)
		)
		(placement
			(enabled no)
			(sheetname "")
		)
		(fill
			(thermal_gap 0.5)
			(thermal_bridge_width 0.5)
			(island_removal_mode 0)
		)
		(polygon
			(pts
				(arc
					(start 49.970436 -390.761474)
					(mid 49.665636 -390.761474)
					(end 49.970436 -390.761474)
				)
			)
		)
	)
	(zone
		(layer "In1.Cu")
		(hatch none 0.5)
		(connect_pads
			(clearance 0)
		)
		(min_thickness 0.25)
		(keepout
			(tracks not_allowed)
			(vias allowed)
			(pads allowed)
			(copperpour not_allowed)
			(footprints allowed)
		)
		(placement
			(enabled no)
			(sheetname "")
		)
		(fill
			(thermal_gap 0.5)
			(thermal_bridge_width 0.5)
			(island_removal_mode 0)
		)
		(polygon
			(pts
				(arc
					(start 33.445196 -288.53257)
					(mid 33.441476 -288.54155)
					(end 33.432496 -288.54527)
				)
				(arc
					(start 31.959296 -288.54527)
					(mid 31.950316 -288.54155)
					(end 31.946596 -288.53257)
				)
				(arc
					(start 31.946596 -288.038032)
					(mid 31.950316 -288.029052)
					(end 31.959296 -288.025332)
				)
				(arc
					(start 33.432496 -288.025332)
					(mid 33.441476 -288.029052)
					(end 33.445196 -288.038032)
				)
			)
		)
	)
	(zone
		(layer "In1.Cu")
		(hatch none 0.5)
		(connect_pads
			(clearance 0)
		)
		(min_thickness 0.25)
		(keepout
			(tracks not_allowed)
			(vias allowed)
			(pads allowed)
			(copperpour not_allowed)
			(footprints allowed)
		)
		(placement
			(enabled no)
			(sheetname "")
		)
		(fill
			(thermal_gap 0.5)
			(thermal_bridge_width 0.5)
			(island_removal_mode 0)
		)
		(polygon
			(pts
				(arc
					(start 420.661338 -307.232304)
					(mid 420.657618 -307.241284)
					(end 420.648638 -307.245004)
				)
				(arc
					(start 419.175438 -307.245004)
					(mid 419.166458 -307.241284)
					(end 419.162738 -307.232304)
				)
				(arc
					(start 419.162738 -306.737766)
					(mid 419.166458 -306.728786)
					(end 419.175438 -306.725066)
				)
				(arc
					(start 420.648638 -306.725066)
					(mid 420.657618 -306.728786)
					(end 420.661338 -306.737766)
				)
			)
		)
	)
	(zone
		(layer "In1.Cu")
		(hatch none 0.5)
		(connect_pads
			(clearance 0)
		)
		(min_thickness 0.25)
		(keepout
			(tracks not_allowed)
			(vias allowed)
			(pads allowed)
			(copperpour not_allowed)
			(footprints allowed)
		)
		(placement
			(enabled no)
			(sheetname "")
		)
		(fill
			(thermal_gap 0.5)
			(thermal_bridge_width 0.5)
			(island_removal_mode 0)
		)
		(polygon
			(pts
				(arc
					(start 443.2935 -282.582112)
					(mid 443.28978 -282.591092)
					(end 443.2808 -282.594812)
				)
				(arc
					(start 441.8076 -282.594812)
					(mid 441.79862 -282.591092)
					(end 441.7949 -282.582112)
				)
				(arc
					(start 441.7949 -282.087574)
					(mid 441.79862 -282.078594)
					(end 441.8076 -282.074874)
				)
				(arc
					(start 443.2808 -282.074874)
					(mid 443.28978 -282.078594)
					(end 443.2935 -282.087574)
				)
			)
		)
	)
	(zone
		(layer "In1.Cu")
		(hatch none 0.5)
		(connect_pads
			(clearance 0)
		)
		(min_thickness 0.25)
		(keepout
			(tracks not_allowed)
			(vias allowed)
			(pads allowed)
			(copperpour not_allowed)
			(footprints allowed)
		)
		(placement
			(enabled no)
			(sheetname "")
		)
		(fill
			(thermal_gap 0.5)
			(thermal_bridge_width 0.5)
			(island_removal_mode 0)
		)
		(polygon
			(pts
				(arc
					(start 277.941532 -263.03224)
					(mid 277.937812 -263.04122)
					(end 277.928832 -263.04494)
				)
				(arc
					(start 276.455632 -263.04494)
					(mid 276.446652 -263.04122)
					(end 276.442932 -263.03224)
				)
				(arc
					(start 276.442932 -262.537702)
					(mid 276.446652 -262.528722)
					(end 276.455632 -262.525002)
				)
				(arc
					(start 277.928832 -262.525002)
					(mid 277.937812 -262.528722)
					(end 277.941532 -262.537702)
				)
			)
		)
	)
	(zone
		(layer "In1.Cu")
		(hatch none 0.5)
		(connect_pads
			(clearance 0)
		)
		(min_thickness 0.25)
		(keepout
			(tracks not_allowed)
			(vias allowed)
			(pads allowed)
			(copperpour not_allowed)
			(footprints allowed)
		)
		(placement
			(enabled no)
			(sheetname "")
		)
		(fill
			(thermal_gap 0.5)
			(thermal_bridge_width 0.5)
			(island_removal_mode 0)
		)
		(polygon
			(pts
				(arc
					(start 195.353432 -241.782346)
					(mid 195.349712 -241.791326)
					(end 195.340732 -241.795046)
				)
				(arc
					(start 193.867532 -241.795046)
					(mid 193.858552 -241.791326)
					(end 193.854832 -241.782346)
				)
				(arc
					(start 193.854832 -241.287808)
					(mid 193.858552 -241.278828)
					(end 193.867532 -241.275108)
				)
				(arc
					(start 195.340732 -241.275108)
					(mid 195.349712 -241.278828)
					(end 195.353432 -241.287808)
				)
			)
		)
	)
	(zone
		(layer "In1.Cu")
		(hatch none 0.5)
		(connect_pads
			(clearance 0)
		)
		(min_thickness 0.25)
		(keepout
			(tracks not_allowed)
			(vias allowed)
			(pads allowed)
			(copperpour not_allowed)
			(footprints allowed)
		)
		(placement
			(enabled no)
			(sheetname "")
		)
		(fill
			(thermal_gap 0.5)
			(thermal_bridge_width 0.5)
			(island_removal_mode 0)
		)
		(polygon
			(pts
				(arc
					(start 308.117494 -220.532198)
					(mid 308.113774 -220.541178)
					(end 308.104794 -220.544898)
				)
				(arc
					(start 306.631594 -220.544898)
					(mid 306.622614 -220.541178)
					(end 306.618894 -220.532198)
				)
				(arc
					(start 306.618894 -220.03766)
					(mid 306.622614 -220.02868)
					(end 306.631594 -220.02496)
				)
				(arc
					(start 308.104794 -220.02496)
					(mid 308.113774 -220.02868)
					(end 308.117494 -220.03766)
				)
			)
		)
	)
	(zone
		(layer "In1.Cu")
		(hatch none 0.5)
		(connect_pads
			(clearance 0)
		)
		(min_thickness 0.25)
		(keepout
			(tracks not_allowed)
			(vias allowed)
			(pads allowed)
			(copperpour not_allowed)
			(footprints allowed)
		)
		(placement
			(enabled no)
			(sheetname "")
		)
		(fill
			(thermal_gap 0.5)
			(thermal_bridge_width 0.5)
			(island_removal_mode 0)
		)
		(polygon
			(pts
				(arc
					(start 349.188786 -397.156432)
					(mid 348.807786 -397.156432)
					(end 349.188786 -397.156432)
				)
			)
		)
	)
	(zone
		(layer "In1.Cu")
		(hatch none 0.5)
		(connect_pads
			(clearance 0)
		)
		(min_thickness 0.25)
		(keepout
			(tracks not_allowed)
			(vias allowed)
			(pads allowed)
			(copperpour not_allowed)
			(footprints allowed)
		)
		(placement
			(enabled no)
			(sheetname "")
		)
		(fill
			(thermal_gap 0.5)
			(thermal_bridge_width 0.5)
			(island_removal_mode 0)
		)
		(polygon
			(pts
				(arc
					(start 454.937368 -303.83226)
					(mid 454.933648 -303.84124)
					(end 454.924668 -303.84496)
				)
				(arc
					(start 453.451468 -303.84496)
					(mid 453.442488 -303.84124)
					(end 453.438768 -303.83226)
				)
				(arc
					(start 453.438768 -303.337722)
					(mid 453.442488 -303.328742)
					(end 453.451468 -303.325022)
				)
				(arc
					(start 454.924668 -303.325022)
					(mid 454.933648 -303.328742)
					(end 454.937368 -303.337722)
				)
			)
		)
	)
	(zone
		(layer "In1.Cu")
		(hatch none 0.5)
		(connect_pads
			(clearance 0)
		)
		(min_thickness 0.25)
		(keepout
			(tracks not_allowed)
			(vias allowed)
			(pads allowed)
			(copperpour not_allowed)
			(footprints allowed)
		)
		(placement
			(enabled no)
			(sheetname "")
		)
		(fill
			(thermal_gap 0.5)
			(thermal_bridge_width 0.5)
			(island_removal_mode 0)
		)
		(polygon
			(pts
				(arc
					(start 187.809378 -212.032342)
					(mid 187.805658 -212.041322)
					(end 187.796678 -212.045042)
				)
				(arc
					(start 186.323478 -212.045042)
					(mid 186.314498 -212.041322)
					(end 186.310778 -212.032342)
				)
				(arc
					(start 186.310778 -211.537804)
					(mid 186.314498 -211.528824)
					(end 186.323478 -211.525104)
				)
				(arc
					(start 187.796678 -211.525104)
					(mid 187.805658 -211.528824)
					(end 187.809378 -211.537804)
				)
			)
		)
	)
	(zone
		(layer "In1.Cu")
		(hatch none 0.5)
		(connect_pads
			(clearance 0)
		)
		(min_thickness 0.25)
		(keepout
			(tracks not_allowed)
			(vias allowed)
			(pads allowed)
			(copperpour not_allowed)
			(footprints allowed)
		)
		(placement
			(enabled no)
			(sheetname "")
		)
		(fill
			(thermal_gap 0.5)
			(thermal_bridge_width 0.5)
			(island_removal_mode 0)
		)
		(polygon
			(pts
				(arc
					(start 52.633372 -219.682568)
					(mid 52.629652 -219.691548)
					(end 52.620672 -219.695268)
				)
				(arc
					(start 51.147472 -219.695268)
					(mid 51.138492 -219.691548)
					(end 51.134772 -219.682568)
				)
				(arc
					(start 51.134772 -219.18803)
					(mid 51.138492 -219.17905)
					(end 51.147472 -219.17533)
				)
				(arc
					(start 52.620672 -219.17533)
					(mid 52.629652 -219.17905)
					(end 52.633372 -219.18803)
				)
			)
		)
	)
	(zone
		(layer "In1.Cu")
		(hatch none 0.5)
		(connect_pads
			(clearance 0)
		)
		(min_thickness 0.25)
		(keepout
			(tracks not_allowed)
			(vias allowed)
			(pads allowed)
			(copperpour not_allowed)
			(footprints allowed)
		)
		(placement
			(enabled no)
			(sheetname "")
		)
		(fill
			(thermal_gap 0.5)
			(thermal_bridge_width 0.5)
			(island_removal_mode 0)
		)
		(polygon
			(pts
				(arc
					(start 443.2935 -299.582332)
					(mid 443.28978 -299.591312)
					(end 443.2808 -299.595032)
				)
				(arc
					(start 441.8076 -299.595032)
					(mid 441.79862 -299.591312)
					(end 441.7949 -299.582332)
				)
				(arc
					(start 441.7949 -299.087794)
					(mid 441.79862 -299.078814)
					(end 441.8076 -299.075094)
				)
				(arc
					(start 443.2808 -299.075094)
					(mid 443.28978 -299.078814)
					(end 443.2935 -299.087794)
				)
			)
		)
	)
	(zone
		(layer "In1.Cu")
		(hatch none 0.5)
		(connect_pads
			(clearance 0)
		)
		(min_thickness 0.25)
		(keepout
			(tracks not_allowed)
			(vias allowed)
			(pads allowed)
			(copperpour not_allowed)
			(footprints allowed)
		)
		(placement
			(enabled no)
			(sheetname "")
		)
		(fill
			(thermal_gap 0.5)
			(thermal_bridge_width 0.5)
			(island_removal_mode 0)
		)
		(polygon
			(pts
				(arc
					(start 165.177216 -230.732584)
					(mid 165.173496 -230.741564)
					(end 165.164516 -230.745284)
				)
				(arc
					(start 163.691316 -230.745284)
					(mid 163.682336 -230.741564)
					(end 163.678616 -230.732584)
				)
				(arc
					(start 163.678616 -230.238046)
					(mid 163.682336 -230.229066)
					(end 163.691316 -230.225346)
				)
				(arc
					(start 165.164516 -230.225346)
					(mid 165.173496 -230.229066)
					(end 165.177216 -230.238046)
				)
			)
		)
	)
	(zone
		(layer "In1.Cu")
		(hatch none 0.5)
		(connect_pads
			(clearance 0)
		)
		(min_thickness 0.25)
		(keepout
			(tracks not_allowed)
			(vias allowed)
			(pads allowed)
			(copperpour not_allowed)
			(footprints allowed)
		)
		(placement
			(enabled no)
			(sheetname "")
		)
		(fill
			(thermal_gap 0.5)
			(thermal_bridge_width 0.5)
			(island_removal_mode 0)
		)
		(polygon
			(pts
				(arc
					(start 30.001464 -309.782464)
					(mid 29.997744 -309.791444)
					(end 29.988764 -309.795164)
				)
				(arc
					(start 28.515564 -309.795164)
					(mid 28.506584 -309.791444)
					(end 28.502864 -309.782464)
				)
				(arc
					(start 28.502864 -309.287926)
					(mid 28.506584 -309.278946)
					(end 28.515564 -309.275226)
				)
				(arc
					(start 29.988764 -309.275226)
					(mid 29.997744 -309.278946)
					(end 30.001464 -309.287926)
				)
			)
		)
	)
	(zone
		(layer "In1.Cu")
		(hatch none 0.5)
		(connect_pads
			(clearance 0)
		)
		(min_thickness 0.25)
		(keepout
			(tracks not_allowed)
			(vias allowed)
			(pads allowed)
			(copperpour not_allowed)
			(footprints allowed)
		)
		(placement
			(enabled no)
			(sheetname "")
		)
		(fill
			(thermal_gap 0.5)
			(thermal_bridge_width 0.5)
			(island_removal_mode 0)
		)
		(polygon
			(pts
				(arc
					(start 195.353432 -282.582366)
					(mid 195.349712 -282.591346)
					(end 195.340732 -282.595066)
				)
				(arc
					(start 193.867532 -282.595066)
					(mid 193.858552 -282.591346)
					(end 193.854832 -282.582366)
				)
				(arc
					(start 193.854832 -282.087828)
					(mid 193.858552 -282.078848)
					(end 193.867532 -282.075128)
				)
				(arc
					(start 195.340732 -282.075128)
					(mid 195.349712 -282.078848)
					(end 195.353432 -282.087828)
				)
			)
		)
	)
	(zone
		(layer "In1.Cu")
		(hatch none 0.5)
		(connect_pads
			(clearance 0)
		)
		(min_thickness 0.25)
		(keepout
			(tracks not_allowed)
			(vias allowed)
			(pads allowed)
			(copperpour not_allowed)
			(footprints allowed)
		)
		(placement
			(enabled no)
			(sheetname "")
		)
		(fill
			(thermal_gap 0.5)
			(thermal_bridge_width 0.5)
			(island_removal_mode 0)
		)
		(polygon
			(pts
				(arc
					(start 33.445196 -211.182458)
					(mid 33.441476 -211.191438)
					(end 33.432496 -211.195158)
				)
				(arc
					(start 31.959296 -211.195158)
					(mid 31.950316 -211.191438)
					(end 31.946596 -211.182458)
				)
				(arc
					(start 31.946596 -210.68792)
					(mid 31.950316 -210.67894)
					(end 31.959296 -210.67522)
				)
				(arc
					(start 33.432496 -210.67522)
					(mid 33.441476 -210.67894)
					(end 33.445196 -210.68792)
				)
			)
		)
	)
	(zone
		(layer "In1.Cu")
		(hatch none 0.5)
		(connect_pads
			(clearance 0)
		)
		(min_thickness 0.25)
		(keepout
			(tracks not_allowed)
			(vias allowed)
			(pads allowed)
			(copperpour not_allowed)
			(footprints allowed)
		)
		(placement
			(enabled no)
			(sheetname "")
		)
		(fill
			(thermal_gap 0.5)
			(thermal_bridge_width 0.5)
			(island_removal_mode 0)
		)
		(polygon
			(pts
				(arc
					(start 308.117494 -304.682144)
					(mid 308.113774 -304.691124)
					(end 308.104794 -304.694844)
				)
				(arc
					(start 306.631594 -304.694844)
					(mid 306.622614 -304.691124)
					(end 306.618894 -304.682144)
				)
				(arc
					(start 306.618894 -304.187606)
					(mid 306.622614 -304.178626)
					(end 306.631594 -304.174906)
				)
				(arc
					(start 308.104794 -304.174906)
					(mid 308.113774 -304.178626)
					(end 308.117494 -304.187606)
				)
			)
		)
	)
	(zone
		(layer "In1.Cu")
		(hatch none 0.5)
		(connect_pads
			(clearance 0)
		)
		(min_thickness 0.25)
		(keepout
			(tracks not_allowed)
			(vias allowed)
			(pads allowed)
			(copperpour not_allowed)
			(footprints allowed)
		)
		(placement
			(enabled no)
			(sheetname "")
		)
		(fill
			(thermal_gap 0.5)
			(thermal_bridge_width 0.5)
			(island_removal_mode 0)
		)
		(polygon
			(pts
				(arc
					(start 450.8373 -282.582112)
					(mid 450.83358 -282.591092)
					(end 450.8246 -282.594812)
				)
				(arc
					(start 449.3514 -282.594812)
					(mid 449.34242 -282.591092)
					(end 449.3387 -282.582112)
				)
				(arc
					(start 449.3387 -282.087574)
					(mid 449.34242 -282.078594)
					(end 449.3514 -282.074874)
				)
				(arc
					(start 450.8246 -282.074874)
					(mid 450.83358 -282.078594)
					(end 450.8373 -282.087574)
				)
			)
		)
	)
	(zone
		(layer "In1.Cu")
		(hatch none 0.5)
		(connect_pads
			(clearance 0)
		)
		(min_thickness 0.25)
		(keepout
			(tracks not_allowed)
			(vias allowed)
			(pads allowed)
			(copperpour not_allowed)
			(footprints allowed)
		)
		(placement
			(enabled no)
			(sheetname "")
		)
		(fill
			(thermal_gap 0.5)
			(thermal_bridge_width 0.5)
			(island_removal_mode 0)
		)
		(polygon
			(pts
				(arc
					(start 30.001464 -276.632416)
					(mid 29.997744 -276.641396)
					(end 29.988764 -276.645116)
				)
				(arc
					(start 28.515564 -276.645116)
					(mid 28.506584 -276.641396)
					(end 28.502864 -276.632416)
				)
				(arc
					(start 28.502864 -276.137878)
					(mid 28.506584 -276.128898)
					(end 28.515564 -276.125178)
				)
				(arc
					(start 29.988764 -276.125178)
					(mid 29.997744 -276.128898)
					(end 30.001464 -276.137878)
				)
			)
		)
	)
	(zone
		(layer "In1.Cu")
		(hatch none 0.5)
		(connect_pads
			(clearance 0)
		)
		(min_thickness 0.25)
		(keepout
			(tracks not_allowed)
			(vias allowed)
			(pads allowed)
			(copperpour not_allowed)
			(footprints allowed)
		)
		(placement
			(enabled no)
			(sheetname "")
		)
		(fill
			(thermal_gap 0.5)
			(thermal_bridge_width 0.5)
			(island_removal_mode 0)
		)
		(polygon
			(pts
				(arc
					(start 199.4535 -227.33254)
					(mid 199.44978 -227.34152)
					(end 199.4408 -227.34524)
				)
				(arc
					(start 197.9676 -227.34524)
					(mid 197.95862 -227.34152)
					(end 197.9549 -227.33254)
				)
				(arc
					(start 197.9549 -226.838002)
					(mid 197.95862 -226.829022)
					(end 197.9676 -226.825302)
				)
				(arc
					(start 199.4408 -226.825302)
					(mid 199.44978 -226.829022)
					(end 199.4535 -226.838002)
				)
			)
		)
	)
	(zone
		(layer "In1.Cu")
		(hatch none 0.5)
		(connect_pads
			(clearance 0)
		)
		(min_thickness 0.25)
		(keepout
			(tracks not_allowed)
			(vias allowed)
			(pads allowed)
			(copperpour not_allowed)
			(footprints allowed)
		)
		(placement
			(enabled no)
			(sheetname "")
		)
		(fill
			(thermal_gap 0.5)
			(thermal_bridge_width 0.5)
			(island_removal_mode 0)
		)
		(polygon
			(pts
				(arc
					(start 424.761406 -208.632298)
					(mid 424.757686 -208.641278)
					(end 424.748706 -208.644998)
				)
				(arc
					(start 423.275506 -208.644998)
					(mid 423.266526 -208.641278)
					(end 423.262806 -208.632298)
				)
				(arc
					(start 423.262806 -208.13776)
					(mid 423.266526 -208.12878)
					(end 423.275506 -208.12506)
				)
				(arc
					(start 424.748706 -208.12506)
					(mid 424.757686 -208.12878)
					(end 424.761406 -208.13776)
				)
			)
		)
	)
	(zone
		(layer "In1.Cu")
		(hatch none 0.5)
		(connect_pads
			(clearance 0)
		)
		(min_thickness 0.25)
		(keepout
			(tracks not_allowed)
			(vias allowed)
			(pads allowed)
			(copperpour not_allowed)
			(footprints allowed)
		)
		(placement
			(enabled no)
			(sheetname "")
		)
		(fill
			(thermal_gap 0.5)
			(thermal_bridge_width 0.5)
			(island_removal_mode 0)
		)
		(polygon
			(pts
				(arc
					(start 206.9973 -212.88248)
					(mid 206.99358 -212.89146)
					(end 206.9846 -212.89518)
				)
				(arc
					(start 205.5114 -212.89518)
					(mid 205.50242 -212.89146)
					(end 205.4987 -212.88248)
				)
				(arc
					(start 205.4987 -212.387942)
					(mid 205.50242 -212.378962)
					(end 205.5114 -212.375242)
				)
				(arc
					(start 206.9846 -212.375242)
					(mid 206.99358 -212.378962)
					(end 206.9973 -212.387942)
				)
			)
		)
	)
	(zone
		(layer "In1.Cu")
		(hatch none 0.5)
		(connect_pads
			(clearance 0)
		)
		(min_thickness 0.25)
		(keepout
			(tracks not_allowed)
			(vias allowed)
			(pads allowed)
			(copperpour not_allowed)
			(footprints allowed)
		)
		(placement
			(enabled no)
			(sheetname "")
		)
		(fill
			(thermal_gap 0.5)
			(thermal_bridge_width 0.5)
			(island_removal_mode 0)
		)
		(polygon
			(pts
				(arc
					(start 300.57344 -234.982258)
					(mid 300.56972 -234.991238)
					(end 300.56074 -234.994958)
				)
				(arc
					(start 299.08754 -234.994958)
					(mid 299.07856 -234.991238)
					(end 299.07484 -234.982258)
				)
				(arc
					(start 299.07484 -234.48772)
					(mid 299.07856 -234.47874)
					(end 299.08754 -234.47502)
				)
				(arc
					(start 300.56074 -234.47502)
					(mid 300.56972 -234.47874)
					(end 300.57344 -234.48772)
				)
			)
		)
	)
	(zone
		(layer "In1.Cu")
		(hatch none 0.5)
		(connect_pads
			(clearance 0)
		)
		(min_thickness 0.25)
		(keepout
			(tracks not_allowed)
			(vias allowed)
			(pads allowed)
			(copperpour not_allowed)
			(footprints allowed)
		)
		(placement
			(enabled no)
			(sheetname "")
		)
		(fill
			(thermal_gap 0.5)
			(thermal_bridge_width 0.5)
			(island_removal_mode 0)
		)
		(polygon
			(pts
				(arc
					(start 25.901396 -235.832396)
					(mid 25.897676 -235.841376)
					(end 25.888696 -235.845096)
				)
				(arc
					(start 24.415496 -235.845096)
					(mid 24.406516 -235.841376)
					(end 24.402796 -235.832396)
				)
				(arc
					(start 24.402796 -235.337858)
					(mid 24.406516 -235.328878)
					(end 24.415496 -235.325158)
				)
				(arc
					(start 25.888696 -235.325158)
					(mid 25.897676 -235.328878)
					(end 25.901396 -235.337858)
				)
			)
		)
	)
	(zone
		(layer "In1.Cu")
		(hatch none 0.5)
		(connect_pads
			(clearance 0)
		)
		(min_thickness 0.25)
		(keepout
			(tracks not_allowed)
			(vias allowed)
			(pads allowed)
			(copperpour not_allowed)
			(footprints allowed)
		)
		(placement
			(enabled no)
			(sheetname "")
		)
		(fill
			(thermal_gap 0.5)
			(thermal_bridge_width 0.5)
			(island_removal_mode 0)
		)
		(polygon
			(pts
				(arc
					(start 443.2935 -280.88209)
					(mid 443.28978 -280.89107)
					(end 443.2808 -280.89479)
				)
				(arc
					(start 441.8076 -280.89479)
					(mid 441.79862 -280.89107)
					(end 441.7949 -280.88209)
				)
				(arc
					(start 441.7949 -280.387552)
					(mid 441.79862 -280.378572)
					(end 441.8076 -280.374852)
				)
				(arc
					(start 443.2808 -280.374852)
					(mid 443.28978 -280.378572)
					(end 443.2935 -280.387552)
				)
			)
		)
	)
	(zone
		(layer "In1.Cu")
		(hatch none 0.5)
		(connect_pads
			(clearance 0)
		)
		(min_thickness 0.25)
		(keepout
			(tracks not_allowed)
			(vias allowed)
			(pads allowed)
			(copperpour not_allowed)
			(footprints allowed)
		)
		(placement
			(enabled no)
			(sheetname "")
		)
		(fill
			(thermal_gap 0.5)
			(thermal_bridge_width 0.5)
			(island_removal_mode 0)
		)
		(polygon
			(pts
				(arc
					(start 195.353432 -297.882564)
					(mid 195.349712 -297.891544)
					(end 195.340732 -297.895264)
				)
				(arc
					(start 193.867532 -297.895264)
					(mid 193.858552 -297.891544)
					(end 193.854832 -297.882564)
				)
				(arc
					(start 193.854832 -297.388026)
					(mid 193.858552 -297.379046)
					(end 193.867532 -297.375326)
				)
				(arc
					(start 195.340732 -297.375326)
					(mid 195.349712 -297.379046)
					(end 195.353432 -297.388026)
				)
			)
		)
	)
	(zone
		(layer "In1.Cu")
		(hatch none 0.5)
		(connect_pads
			(clearance 0)
		)
		(min_thickness 0.25)
		(keepout
			(tracks not_allowed)
			(vias allowed)
			(pads allowed)
			(copperpour not_allowed)
			(footprints allowed)
		)
		(placement
			(enabled no)
			(sheetname "")
		)
		(fill
			(thermal_gap 0.5)
			(thermal_bridge_width 0.5)
			(island_removal_mode 0)
		)
		(polygon
			(pts
				(arc
					(start 338.497926 -392.30427)
					(mid 338.193126 -392.30427)
					(end 338.497926 -392.30427)
				)
			)
		)
	)
	(zone
		(layer "In1.Cu")
		(hatch none 0.5)
		(connect_pads
			(clearance 0)
		)
		(min_thickness 0.25)
		(keepout
			(tracks not_allowed)
			(vias allowed)
			(pads allowed)
			(copperpour not_allowed)
			(footprints allowed)
		)
		(placement
			(enabled no)
			(sheetname "")
		)
		(fill
			(thermal_gap 0.5)
			(thermal_bridge_width 0.5)
			(island_removal_mode 0)
		)
		(polygon
			(pts
				(arc
					(start 432.30546 -197.582282)
					(mid 432.30174 -197.591262)
					(end 432.29276 -197.594982)
				)
				(arc
					(start 430.81956 -197.594982)
					(mid 430.81058 -197.591262)
					(end 430.80686 -197.582282)
				)
				(arc
					(start 430.80686 -197.087744)
					(mid 430.81058 -197.078764)
					(end 430.81956 -197.075044)
				)
				(arc
					(start 432.29276 -197.075044)
					(mid 432.30174 -197.078764)
					(end 432.30546 -197.087744)
				)
			)
		)
	)
	(zone
		(layer "In1.Cu")
		(hatch none 0.5)
		(connect_pads
			(clearance 0)
		)
		(min_thickness 0.25)
		(keepout
			(tracks not_allowed)
			(vias allowed)
			(pads allowed)
			(copperpour not_allowed)
			(footprints allowed)
		)
		(placement
			(enabled no)
			(sheetname "")
		)
		(fill
			(thermal_gap 0.5)
			(thermal_bridge_width 0.5)
			(island_removal_mode 0)
		)
		(polygon
			(pts
				(arc
					(start 270.397478 -300.432216)
					(mid 270.393758 -300.441196)
					(end 270.384778 -300.444916)
				)
				(arc
					(start 268.911578 -300.444916)
					(mid 268.902598 -300.441196)
					(end 268.898878 -300.432216)
				)
				(arc
					(start 268.898878 -299.937678)
					(mid 268.902598 -299.928698)
					(end 268.911578 -299.924978)
				)
				(arc
					(start 270.384778 -299.924978)
					(mid 270.393758 -299.928698)
					(end 270.397478 -299.937678)
				)
			)
		)
	)
	(zone
		(layer "In1.Cu")
		(hatch none 0.5)
		(connect_pads
			(clearance 0)
		)
		(min_thickness 0.25)
		(keepout
			(tracks not_allowed)
			(vias allowed)
			(pads allowed)
			(copperpour not_allowed)
			(footprints allowed)
		)
		(placement
			(enabled no)
			(sheetname "")
		)
		(fill
			(thermal_gap 0.5)
			(thermal_bridge_width 0.5)
			(island_removal_mode 0)
		)
		(polygon
			(pts
				(arc
					(start 169.277284 -227.33254)
					(mid 169.273564 -227.34152)
					(end 169.264584 -227.34524)
				)
				(arc
					(start 167.791384 -227.34524)
					(mid 167.782404 -227.34152)
					(end 167.778684 -227.33254)
				)
				(arc
					(start 167.778684 -226.838002)
					(mid 167.782404 -226.829022)
					(end 167.791384 -226.825302)
				)
				(arc
					(start 169.264584 -226.825302)
					(mid 169.273564 -226.829022)
					(end 169.277284 -226.838002)
				)
			)
		)
	)
	(zone
		(layer "In1.Cu")
		(hatch none 0.5)
		(connect_pads
			(clearance 0)
		)
		(min_thickness 0.25)
		(keepout
			(tracks not_allowed)
			(vias allowed)
			(pads allowed)
			(copperpour not_allowed)
			(footprints allowed)
		)
		(placement
			(enabled no)
			(sheetname "")
		)
		(fill
			(thermal_gap 0.5)
			(thermal_bridge_width 0.5)
			(island_removal_mode 0)
		)
		(polygon
			(pts
				(arc
					(start 302.990758 -399.701258)
					(mid 303.117758 -399.828258)
					(end 303.244758 -399.701258)
				)
				(arc
					(start 303.244758 -399.625058)
					(mid 303.117758 -399.498058)
					(end 302.990758 -399.625058)
				)
			)
		)
	)
	(zone
		(layer "In1.Cu")
		(hatch none 0.5)
		(connect_pads
			(clearance 0)
		)
		(min_thickness 0.25)
		(keepout
			(tracks not_allowed)
			(vias allowed)
			(pads allowed)
			(copperpour not_allowed)
			(footprints allowed)
		)
		(placement
			(enabled no)
			(sheetname "")
		)
		(fill
			(thermal_gap 0.5)
			(thermal_bridge_width 0.5)
			(island_removal_mode 0)
		)
		(polygon
			(pts
				(arc
					(start 132.783072 -33.607756)
					(mid 132.760754 -33.661638)
					(end 132.706872 -33.683956)
				)
				(arc
					(start 132.281422 -33.683956)
					(mid 132.22754 -33.661638)
					(end 132.205222 -33.607756)
				)
				(arc
					(start 132.205222 -32.439356)
					(mid 132.22754 -32.385474)
					(end 132.281422 -32.363156)
				)
				(arc
					(start 132.706872 -32.363156)
					(mid 132.760754 -32.385474)
					(end 132.783072 -32.439356)
				)
			)
		)
	)
	(zone
		(layer "In1.Cu")
		(hatch none 0.5)
		(connect_pads
			(clearance 0)
		)
		(min_thickness 0.25)
		(keepout
			(tracks not_allowed)
			(vias allowed)
			(pads allowed)
			(copperpour not_allowed)
			(footprints allowed)
		)
		(placement
			(enabled no)
			(sheetname "")
		)
		(fill
			(thermal_gap 0.5)
			(thermal_bridge_width 0.5)
			(island_removal_mode 0)
		)
		(polygon
			(pts
				(arc
					(start 202.897232 -312.33237)
					(mid 202.893512 -312.34135)
					(end 202.884532 -312.34507)
				)
				(arc
					(start 201.411332 -312.34507)
					(mid 201.402352 -312.34135)
					(end 201.398632 -312.33237)
				)
				(arc
					(start 201.398632 -311.837832)
					(mid 201.402352 -311.828852)
					(end 201.411332 -311.825132)
				)
				(arc
					(start 202.884532 -311.825132)
					(mid 202.893512 -311.828852)
					(end 202.897232 -311.837832)
				)
			)
		)
	)
	(zone
		(layer "In1.Cu")
		(hatch none 0.5)
		(connect_pads
			(clearance 0)
		)
		(min_thickness 0.25)
		(keepout
			(tracks not_allowed)
			(vias allowed)
			(pads allowed)
			(copperpour not_allowed)
			(footprints allowed)
		)
		(placement
			(enabled no)
			(sheetname "")
		)
		(fill
			(thermal_gap 0.5)
			(thermal_bridge_width 0.5)
			(island_removal_mode 0)
		)
		(polygon
			(pts
				(arc
					(start 132.670296 -383.92227)
					(mid 132.365496 -383.92227)
					(end 132.670296 -383.92227)
				)
			)
		)
	)
	(zone
		(layer "In1.Cu")
		(hatch none 0.5)
		(connect_pads
			(clearance 0)
		)
		(min_thickness 0.25)
		(keepout
			(tracks not_allowed)
			(vias allowed)
			(pads allowed)
			(copperpour not_allowed)
			(footprints allowed)
		)
		(placement
			(enabled no)
			(sheetname "")
		)
		(fill
			(thermal_gap 0.5)
			(thermal_bridge_width 0.5)
			(island_removal_mode 0)
		)
		(polygon
			(pts
				(arc
					(start 40.98925 -213.732364)
					(mid 40.98553 -213.741344)
					(end 40.97655 -213.745064)
				)
				(arc
					(start 39.50335 -213.745064)
					(mid 39.49437 -213.741344)
					(end 39.49065 -213.732364)
				)
				(arc
					(start 39.49065 -213.237826)
					(mid 39.49437 -213.228846)
					(end 39.50335 -213.225126)
				)
				(arc
					(start 40.97655 -213.225126)
					(mid 40.98553 -213.228846)
					(end 40.98925 -213.237826)
				)
			)
		)
	)
	(zone
		(layer "In1.Cu")
		(hatch none 0.5)
		(connect_pads
			(clearance 0)
		)
		(min_thickness 0.25)
		(keepout
			(tracks not_allowed)
			(vias allowed)
			(pads allowed)
			(copperpour not_allowed)
			(footprints allowed)
		)
		(placement
			(enabled no)
			(sheetname "")
		)
		(fill
			(thermal_gap 0.5)
			(thermal_bridge_width 0.5)
			(island_removal_mode 0)
		)
		(polygon
			(pts
				(arc
					(start 22.45741 -281.732482)
					(mid 22.45369 -281.741462)
					(end 22.44471 -281.745182)
				)
				(arc
					(start 20.97151 -281.745182)
					(mid 20.96253 -281.741462)
					(end 20.95881 -281.732482)
				)
				(arc
					(start 20.95881 -281.237944)
					(mid 20.96253 -281.228964)
					(end 20.97151 -281.225244)
				)
				(arc
					(start 22.44471 -281.225244)
					(mid 22.45369 -281.228964)
					(end 22.45741 -281.237944)
				)
			)
		)
	)
	(zone
		(layer "In1.Cu")
		(hatch none 0.5)
		(connect_pads
			(clearance 0)
		)
		(min_thickness 0.25)
		(keepout
			(tracks not_allowed)
			(vias allowed)
			(pads allowed)
			(copperpour not_allowed)
			(footprints allowed)
		)
		(placement
			(enabled no)
			(sheetname "")
		)
		(fill
			(thermal_gap 0.5)
			(thermal_bridge_width 0.5)
			(island_removal_mode 0)
		)
		(polygon
			(pts
				(arc
					(start 288.929318 -212.032088)
					(mid 288.925598 -212.041068)
					(end 288.916618 -212.044788)
				)
				(arc
					(start 287.443418 -212.044788)
					(mid 287.434438 -212.041068)
					(end 287.430718 -212.032088)
				)
				(arc
					(start 287.430718 -211.53755)
					(mid 287.434438 -211.52857)
					(end 287.443418 -211.52485)
				)
				(arc
					(start 288.916618 -211.52485)
					(mid 288.925598 -211.52857)
					(end 288.929318 -211.53755)
				)
			)
		)
	)
	(zone
		(layer "In1.Cu")
		(hatch none 0.5)
		(connect_pads
			(clearance 0)
		)
		(min_thickness 0.25)
		(keepout
			(tracks not_allowed)
			(vias allowed)
			(pads allowed)
			(copperpour not_allowed)
			(footprints allowed)
		)
		(placement
			(enabled no)
			(sheetname "")
		)
		(fill
			(thermal_gap 0.5)
			(thermal_bridge_width 0.5)
			(island_removal_mode 0)
		)
		(polygon
			(pts
				(arc
					(start 120.561354 -388.774432)
					(mid 120.180354 -388.774432)
					(end 120.561354 -388.774432)
				)
			)
		)
	)
	(zone
		(layer "In1.Cu")
		(hatch none 0.5)
		(connect_pads
			(clearance 0)
		)
		(min_thickness 0.25)
		(keepout
			(tracks not_allowed)
			(vias allowed)
			(pads allowed)
			(copperpour not_allowed)
			(footprints allowed)
		)
		(placement
			(enabled no)
			(sheetname "")
		)
		(fill
			(thermal_gap 0.5)
			(thermal_bridge_width 0.5)
			(island_removal_mode 0)
		)
		(polygon
			(pts
				(arc
					(start 52.370482 -383.92227)
					(mid 52.065682 -383.92227)
					(end 52.370482 -383.92227)
				)
			)
		)
	)
	(zone
		(layer "In1.Cu")
		(hatch none 0.5)
		(connect_pads
			(clearance 0)
		)
		(min_thickness 0.25)
		(keepout
			(tracks not_allowed)
			(vias allowed)
			(pads allowed)
			(copperpour not_allowed)
			(footprints allowed)
		)
		(placement
			(enabled no)
			(sheetname "")
		)
		(fill
			(thermal_gap 0.5)
			(thermal_bridge_width 0.5)
			(island_removal_mode 0)
		)
		(polygon
			(pts
				(arc
					(start 302.990758 -391.822686)
					(mid 303.117758 -391.949686)
					(end 303.244758 -391.822686)
				)
				(arc
					(start 303.244758 -391.746486)
					(mid 303.117758 -391.619486)
					(end 302.990758 -391.746486)
				)
			)
		)
	)
	(zone
		(layer "In1.Cu")
		(hatch none 0.5)
		(connect_pads
			(clearance 0)
		)
		(min_thickness 0.25)
		(keepout
			(tracks not_allowed)
			(vias allowed)
			(pads allowed)
			(copperpour not_allowed)
			(footprints allowed)
		)
		(placement
			(enabled no)
			(sheetname "")
		)
		(fill
			(thermal_gap 0.5)
			(thermal_bridge_width 0.5)
			(island_removal_mode 0)
		)
		(polygon
			(pts
				(arc
					(start 191.909446 -304.682398)
					(mid 191.905726 -304.691378)
					(end 191.896746 -304.695098)
				)
				(arc
					(start 190.423546 -304.695098)
					(mid 190.414566 -304.691378)
					(end 190.410846 -304.682398)
				)
				(arc
					(start 190.410846 -304.18786)
					(mid 190.414566 -304.17888)
					(end 190.423546 -304.17516)
				)
				(arc
					(start 191.896746 -304.17516)
					(mid 191.905726 -304.17888)
					(end 191.909446 -304.18786)
				)
			)
		)
	)
	(zone
		(layer "In1.Cu")
		(hatch none 0.5)
		(connect_pads
			(clearance 0)
		)
		(min_thickness 0.25)
		(keepout
			(tracks not_allowed)
			(vias allowed)
			(pads allowed)
			(copperpour not_allowed)
			(footprints allowed)
		)
		(placement
			(enabled no)
			(sheetname "")
		)
		(fill
			(thermal_gap 0.5)
			(thermal_bridge_width 0.5)
			(island_removal_mode 0)
		)
		(polygon
			(pts
				(arc
					(start 304.017426 -312.332116)
					(mid 304.013706 -312.341096)
					(end 304.004726 -312.344816)
				)
				(arc
					(start 302.531526 -312.344816)
					(mid 302.522546 -312.341096)
					(end 302.518826 -312.332116)
				)
				(arc
					(start 302.518826 -311.837578)
					(mid 302.522546 -311.828598)
					(end 302.531526 -311.824878)
				)
				(arc
					(start 304.004726 -311.824878)
					(mid 304.013706 -311.828598)
					(end 304.017426 -311.837578)
				)
			)
		)
	)
	(zone
		(layer "In1.Cu")
		(hatch none 0.5)
		(connect_pads
			(clearance 0)
		)
		(min_thickness 0.25)
		(keepout
			(tracks not_allowed)
			(vias allowed)
			(pads allowed)
			(copperpour not_allowed)
			(footprints allowed)
		)
		(placement
			(enabled no)
			(sheetname "")
		)
		(fill
			(thermal_gap 0.5)
			(thermal_bridge_width 0.5)
			(island_removal_mode 0)
		)
		(polygon
			(pts
				(arc
					(start 454.937368 -205.232254)
					(mid 454.933648 -205.241234)
					(end 454.924668 -205.244954)
				)
				(arc
					(start 453.451468 -205.244954)
					(mid 453.442488 -205.241234)
					(end 453.438768 -205.232254)
				)
				(arc
					(start 453.438768 -204.737716)
					(mid 453.442488 -204.728736)
					(end 453.451468 -204.725016)
				)
				(arc
					(start 454.924668 -204.725016)
					(mid 454.933648 -204.728736)
					(end 454.937368 -204.737716)
				)
			)
		)
	)
	(zone
		(layer "In1.Cu")
		(hatch none 0.5)
		(connect_pads
			(clearance 0)
		)
		(min_thickness 0.25)
		(keepout
			(tracks not_allowed)
			(vias allowed)
			(pads allowed)
			(copperpour not_allowed)
			(footprints allowed)
		)
		(placement
			(enabled no)
			(sheetname "")
		)
		(fill
			(thermal_gap 0.5)
			(thermal_bridge_width 0.5)
			(island_removal_mode 0)
		)
		(polygon
			(pts
				(arc
					(start 25.901396 -314.88253)
					(mid 25.897676 -314.89151)
					(end 25.888696 -314.89523)
				)
				(arc
					(start 24.415496 -314.89523)
					(mid 24.406516 -314.89151)
					(end 24.402796 -314.88253)
				)
				(arc
					(start 24.402796 -314.387992)
					(mid 24.406516 -314.379012)
					(end 24.415496 -314.375292)
				)
				(arc
					(start 25.888696 -314.375292)
					(mid 25.897676 -314.379012)
					(end 25.901396 -314.387992)
				)
			)
		)
	)
	(zone
		(layer "In1.Cu")
		(hatch none 0.5)
		(connect_pads
			(clearance 0)
		)
		(min_thickness 0.25)
		(keepout
			(tracks not_allowed)
			(vias allowed)
			(pads allowed)
			(copperpour not_allowed)
			(footprints allowed)
		)
		(placement
			(enabled no)
			(sheetname "")
		)
		(fill
			(thermal_gap 0.5)
			(thermal_bridge_width 0.5)
			(island_removal_mode 0)
		)
		(polygon
			(pts
				(arc
					(start 288.929318 -235.832142)
					(mid 288.925598 -235.841122)
					(end 288.916618 -235.844842)
				)
				(arc
					(start 287.443418 -235.844842)
					(mid 287.434438 -235.841122)
					(end 287.430718 -235.832142)
				)
				(arc
					(start 287.430718 -235.337604)
					(mid 287.434438 -235.328624)
					(end 287.443418 -235.324904)
				)
				(arc
					(start 288.916618 -235.324904)
					(mid 288.925598 -235.328624)
					(end 288.929318 -235.337604)
				)
			)
		)
	)
	(zone
		(layer "In1.Cu")
		(hatch none 0.5)
		(connect_pads
			(clearance 0)
		)
		(min_thickness 0.25)
		(keepout
			(tracks not_allowed)
			(vias allowed)
			(pads allowed)
			(copperpour not_allowed)
			(footprints allowed)
		)
		(placement
			(enabled no)
			(sheetname "")
		)
		(fill
			(thermal_gap 0.5)
			(thermal_bridge_width 0.5)
			(island_removal_mode 0)
		)
		(polygon
			(pts
				(arc
					(start 47.57039 -383.92227)
					(mid 47.26559 -383.92227)
					(end 47.57039 -383.92227)
				)
			)
		)
	)
	(zone
		(layer "In1.Cu")
		(hatch none 0.5)
		(connect_pads
			(clearance 0)
		)
		(min_thickness 0.25)
		(keepout
			(tracks not_allowed)
			(vias allowed)
			(pads allowed)
			(copperpour not_allowed)
			(footprints allowed)
		)
		(placement
			(enabled no)
			(sheetname "")
		)
		(fill
			(thermal_gap 0.5)
			(thermal_bridge_width 0.5)
			(island_removal_mode 0)
		)
		(polygon
			(pts
				(arc
					(start 266.29741 -304.682144)
					(mid 266.29369 -304.691124)
					(end 266.28471 -304.694844)
				)
				(arc
					(start 264.81151 -304.694844)
					(mid 264.80253 -304.691124)
					(end 264.79881 -304.682144)
				)
				(arc
					(start 264.79881 -304.187606)
					(mid 264.80253 -304.178626)
					(end 264.81151 -304.174906)
				)
				(arc
					(start 266.28471 -304.174906)
					(mid 266.29369 -304.178626)
					(end 266.29741 -304.187606)
				)
			)
		)
	)
	(zone
		(layer "In1.Cu")
		(hatch none 0.5)
		(connect_pads
			(clearance 0)
		)
		(min_thickness 0.25)
		(keepout
			(tracks not_allowed)
			(vias allowed)
			(pads allowed)
			(copperpour not_allowed)
			(footprints allowed)
		)
		(placement
			(enabled no)
			(sheetname "")
		)
		(fill
			(thermal_gap 0.5)
			(thermal_bridge_width 0.5)
			(island_removal_mode 0)
		)
		(polygon
			(pts
				(arc
					(start 176.821338 -200.98258)
					(mid 176.817618 -200.99156)
					(end 176.808638 -200.99528)
				)
				(arc
					(start 175.335438 -200.99528)
					(mid 175.326458 -200.99156)
					(end 175.322738 -200.98258)
				)
				(arc
					(start 175.322738 -200.488042)
					(mid 175.326458 -200.479062)
					(end 175.335438 -200.475342)
				)
				(arc
					(start 176.808638 -200.475342)
					(mid 176.817618 -200.479062)
					(end 176.821338 -200.488042)
				)
			)
		)
	)
	(zone
		(layer "In1.Cu")
		(hatch none 0.5)
		(connect_pads
			(clearance 0)
		)
		(min_thickness 0.25)
		(keepout
			(tracks not_allowed)
			(vias allowed)
			(pads allowed)
			(copperpour not_allowed)
			(footprints allowed)
		)
		(placement
			(enabled no)
			(sheetname "")
		)
		(fill
			(thermal_gap 0.5)
			(thermal_bridge_width 0.5)
			(island_removal_mode 0)
		)
		(polygon
			(pts
				(arc
					(start 377.870466 -399.143474)
					(mid 377.565666 -399.143474)
					(end 377.870466 -399.143474)
				)
			)
		)
	)
	(zone
		(layer "In1.Cu")
		(hatch none 0.5)
		(connect_pads
			(clearance 0)
		)
		(min_thickness 0.25)
		(keepout
			(tracks not_allowed)
			(vias allowed)
			(pads allowed)
			(copperpour not_allowed)
			(footprints allowed)
		)
		(placement
			(enabled no)
			(sheetname "")
		)
		(fill
			(thermal_gap 0.5)
			(thermal_bridge_width 0.5)
			(island_removal_mode 0)
		)
		(polygon
			(pts
				(arc
					(start 417.217352 -203.532232)
					(mid 417.213632 -203.541212)
					(end 417.204652 -203.544932)
				)
				(arc
					(start 415.731452 -203.544932)
					(mid 415.722472 -203.541212)
					(end 415.718752 -203.532232)
				)
				(arc
					(start 415.718752 -203.037694)
					(mid 415.722472 -203.028714)
					(end 415.731452 -203.024994)
				)
				(arc
					(start 417.204652 -203.024994)
					(mid 417.213632 -203.028714)
					(end 417.217352 -203.037694)
				)
			)
		)
	)
	(zone
		(layer "In1.Cu")
		(hatch none 0.5)
		(connect_pads
			(clearance 0)
		)
		(min_thickness 0.25)
		(keepout
			(tracks not_allowed)
			(vias allowed)
			(pads allowed)
			(copperpour not_allowed)
			(footprints allowed)
		)
		(placement
			(enabled no)
			(sheetname "")
		)
		(fill
			(thermal_gap 0.5)
			(thermal_bridge_width 0.5)
			(island_removal_mode 0)
		)
		(polygon
			(pts
				(arc
					(start 202.897232 -241.782346)
					(mid 202.893512 -241.791326)
					(end 202.884532 -241.795046)
				)
				(arc
					(start 201.411332 -241.795046)
					(mid 201.402352 -241.791326)
					(end 201.398632 -241.782346)
				)
				(arc
					(start 201.398632 -241.287808)
					(mid 201.402352 -241.278828)
					(end 201.411332 -241.275108)
				)
				(arc
					(start 202.884532 -241.275108)
					(mid 202.893512 -241.278828)
					(end 202.897232 -241.287808)
				)
			)
		)
	)
	(zone
		(layer "In1.Cu")
		(hatch none 0.5)
		(connect_pads
			(clearance 0)
		)
		(min_thickness 0.25)
		(keepout
			(tracks not_allowed)
			(vias allowed)
			(pads allowed)
			(copperpour not_allowed)
			(footprints allowed)
		)
		(placement
			(enabled no)
			(sheetname "")
		)
		(fill
			(thermal_gap 0.5)
			(thermal_bridge_width 0.5)
			(island_removal_mode 0)
		)
		(polygon
			(pts
				(arc
					(start 420.661338 -296.182288)
					(mid 420.657618 -296.191268)
					(end 420.648638 -296.194988)
				)
				(arc
					(start 419.175438 -296.194988)
					(mid 419.166458 -296.191268)
					(end 419.162738 -296.182288)
				)
				(arc
					(start 419.162738 -295.68775)
					(mid 419.166458 -295.67877)
					(end 419.175438 -295.67505)
				)
				(arc
					(start 420.648638 -295.67505)
					(mid 420.657618 -295.67877)
					(end 420.661338 -295.68775)
				)
			)
		)
	)
	(zone
		(layer "In1.Cu")
		(hatch none 0.5)
		(connect_pads
			(clearance 0)
		)
		(min_thickness 0.25)
		(keepout
			(tracks not_allowed)
			(vias allowed)
			(pads allowed)
			(copperpour not_allowed)
			(footprints allowed)
		)
		(placement
			(enabled no)
			(sheetname "")
		)
		(fill
			(thermal_gap 0.5)
			(thermal_bridge_width 0.5)
			(island_removal_mode 0)
		)
		(polygon
			(pts
				(arc
					(start 281.385264 -301.2821)
					(mid 281.381544 -301.29108)
					(end 281.372564 -301.2948)
				)
				(arc
					(start 279.899364 -301.2948)
					(mid 279.890384 -301.29108)
					(end 279.886664 -301.2821)
				)
				(arc
					(start 279.886664 -300.787562)
					(mid 279.890384 -300.778582)
					(end 279.899364 -300.774862)
				)
				(arc
					(start 281.372564 -300.774862)
					(mid 281.381544 -300.778582)
					(end 281.385264 -300.787562)
				)
			)
		)
	)
	(zone
		(layer "In1.Cu")
		(hatch none 0.5)
		(connect_pads
			(clearance 0)
		)
		(min_thickness 0.25)
		(keepout
			(tracks not_allowed)
			(vias allowed)
			(pads allowed)
			(copperpour not_allowed)
			(footprints allowed)
		)
		(placement
			(enabled no)
			(sheetname "")
		)
		(fill
			(thermal_gap 0.5)
			(thermal_bridge_width 0.5)
			(island_removal_mode 0)
		)
		(polygon
			(pts
				(arc
					(start 206.9973 -252.832362)
					(mid 206.99358 -252.841342)
					(end 206.9846 -252.845062)
				)
				(arc
					(start 205.5114 -252.845062)
					(mid 205.50242 -252.841342)
					(end 205.4987 -252.832362)
				)
				(arc
					(start 205.4987 -252.337824)
					(mid 205.50242 -252.328844)
					(end 205.5114 -252.325124)
				)
				(arc
					(start 206.9846 -252.325124)
					(mid 206.99358 -252.328844)
					(end 206.9973 -252.337824)
				)
			)
		)
	)
	(zone
		(layer "In1.Cu")
		(hatch none 0.5)
		(connect_pads
			(clearance 0)
		)
		(min_thickness 0.25)
		(keepout
			(tracks not_allowed)
			(vias allowed)
			(pads allowed)
			(copperpour not_allowed)
			(footprints allowed)
		)
		(placement
			(enabled no)
			(sheetname "")
		)
		(fill
			(thermal_gap 0.5)
			(thermal_bridge_width 0.5)
			(island_removal_mode 0)
		)
		(polygon
			(pts
				(arc
					(start 172.72127 -291.93236)
					(mid 172.71755 -291.94134)
					(end 172.70857 -291.94506)
				)
				(arc
					(start 171.23537 -291.94506)
					(mid 171.22639 -291.94134)
					(end 171.22267 -291.93236)
				)
				(arc
					(start 171.22267 -291.437822)
					(mid 171.22639 -291.428842)
					(end 171.23537 -291.425122)
				)
				(arc
					(start 172.70857 -291.425122)
					(mid 172.71755 -291.428842)
					(end 172.72127 -291.437822)
				)
			)
		)
	)
	(zone
		(layer "In1.Cu")
		(hatch none 0.5)
		(connect_pads
			(clearance 0)
		)
		(min_thickness 0.25)
		(keepout
			(tracks not_allowed)
			(vias allowed)
			(pads allowed)
			(copperpour not_allowed)
			(footprints allowed)
		)
		(placement
			(enabled no)
			(sheetname "")
		)
		(fill
			(thermal_gap 0.5)
			(thermal_bridge_width 0.5)
			(island_removal_mode 0)
		)
		(polygon
			(pts
				(arc
					(start 202.897232 -207.782414)
					(mid 202.893512 -207.791394)
					(end 202.884532 -207.795114)
				)
				(arc
					(start 201.411332 -207.795114)
					(mid 201.402352 -207.791394)
					(end 201.398632 -207.782414)
				)
				(arc
					(start 201.398632 -207.287876)
					(mid 201.402352 -207.278896)
					(end 201.411332 -207.275176)
				)
				(arc
					(start 202.884532 -207.275176)
					(mid 202.893512 -207.278896)
					(end 202.897232 -207.287876)
				)
			)
		)
	)
	(zone
		(layer "In1.Cu")
		(hatch none 0.5)
		(connect_pads
			(clearance 0)
		)
		(min_thickness 0.25)
		(keepout
			(tracks not_allowed)
			(vias allowed)
			(pads allowed)
			(copperpour not_allowed)
			(footprints allowed)
		)
		(placement
			(enabled no)
			(sheetname "")
		)
		(fill
			(thermal_gap 0.5)
			(thermal_bridge_width 0.5)
			(island_removal_mode 0)
		)
		(polygon
			(pts
				(arc
					(start 337.918552 -391.822686)
					(mid 338.045552 -391.949686)
					(end 338.172552 -391.822686)
				)
				(arc
					(start 338.172552 -391.746486)
					(mid 338.045552 -391.619486)
					(end 337.918552 -391.746486)
				)
			)
		)
	)
	(zone
		(layer "In1.Cu")
		(hatch none 0.5)
		(connect_pads
			(clearance 0)
		)
		(min_thickness 0.25)
		(keepout
			(tracks not_allowed)
			(vias allowed)
			(pads allowed)
			(copperpour not_allowed)
			(footprints allowed)
		)
		(placement
			(enabled no)
			(sheetname "")
		)
		(fill
			(thermal_gap 0.5)
			(thermal_bridge_width 0.5)
			(island_removal_mode 0)
		)
		(polygon
			(pts
				(arc
					(start 88.498172 -390.761474)
					(mid 88.193372 -390.761474)
					(end 88.498172 -390.761474)
				)
			)
		)
	)
	(zone
		(layer "In1.Cu")
		(hatch none 0.5)
		(connect_pads
			(clearance 0)
		)
		(min_thickness 0.25)
		(keepout
			(tracks not_allowed)
			(vias allowed)
			(pads allowed)
			(copperpour not_allowed)
			(footprints allowed)
		)
		(placement
			(enabled no)
			(sheetname "")
		)
		(fill
			(thermal_gap 0.5)
			(thermal_bridge_width 0.5)
			(island_removal_mode 0)
		)
		(polygon
			(pts
				(arc
					(start 206.9973 -287.682432)
					(mid 206.99358 -287.691412)
					(end 206.9846 -287.695132)
				)
				(arc
					(start 205.5114 -287.695132)
					(mid 205.50242 -287.691412)
					(end 205.4987 -287.682432)
				)
				(arc
					(start 205.4987 -287.187894)
					(mid 205.50242 -287.178914)
					(end 205.5114 -287.175194)
				)
				(arc
					(start 206.9846 -287.175194)
					(mid 206.99358 -287.178914)
					(end 206.9973 -287.187894)
				)
			)
		)
	)
	(zone
		(layer "In1.Cu")
		(hatch none 0.5)
		(connect_pads
			(clearance 0)
		)
		(min_thickness 0.25)
		(keepout
			(tracks not_allowed)
			(vias allowed)
			(pads allowed)
			(copperpour not_allowed)
			(footprints allowed)
		)
		(placement
			(enabled no)
			(sheetname "")
		)
		(fill
			(thermal_gap 0.5)
			(thermal_bridge_width 0.5)
			(island_removal_mode 0)
		)
		(polygon
			(pts
				(arc
					(start 172.72127 -286.832548)
					(mid 172.71755 -286.841528)
					(end 172.70857 -286.845248)
				)
				(arc
					(start 171.23537 -286.845248)
					(mid 171.22639 -286.841528)
					(end 171.22267 -286.832548)
				)
				(arc
					(start 171.22267 -286.33801)
					(mid 171.22639 -286.32903)
					(end 171.23537 -286.32531)
				)
				(arc
					(start 172.70857 -286.32531)
					(mid 172.71755 -286.32903)
					(end 172.72127 -286.33801)
				)
			)
		)
	)
	(zone
		(layer "In1.Cu")
		(hatch none 0.5)
		(connect_pads
			(clearance 0)
		)
		(min_thickness 0.25)
		(keepout
			(tracks not_allowed)
			(vias allowed)
			(pads allowed)
			(copperpour not_allowed)
			(footprints allowed)
		)
		(placement
			(enabled no)
			(sheetname "")
		)
		(fill
			(thermal_gap 0.5)
			(thermal_bridge_width 0.5)
			(island_removal_mode 0)
		)
		(polygon
			(pts
				(arc
					(start 454.937368 -244.332252)
					(mid 454.933648 -244.341232)
					(end 454.924668 -244.344952)
				)
				(arc
					(start 453.451468 -244.344952)
					(mid 453.442488 -244.341232)
					(end 453.438768 -244.332252)
				)
				(arc
					(start 453.438768 -243.837714)
					(mid 453.442488 -243.828734)
					(end 453.451468 -243.825014)
				)
				(arc
					(start 454.924668 -243.825014)
					(mid 454.933648 -243.828734)
					(end 454.937368 -243.837714)
				)
			)
		)
	)
	(zone
		(layer "In1.Cu")
		(hatch none 0.5)
		(connect_pads
			(clearance 0)
		)
		(min_thickness 0.25)
		(keepout
			(tracks not_allowed)
			(vias allowed)
			(pads allowed)
			(copperpour not_allowed)
			(footprints allowed)
		)
		(placement
			(enabled no)
			(sheetname "")
		)
		(fill
			(thermal_gap 0.5)
			(thermal_bridge_width 0.5)
			(island_removal_mode 0)
		)
		(polygon
			(pts
				(arc
					(start 56.077358 -299.582586)
					(mid 56.073638 -299.591566)
					(end 56.064658 -299.595286)
				)
				(arc
					(start 54.591458 -299.595286)
					(mid 54.582478 -299.591566)
					(end 54.578758 -299.582586)
				)
				(arc
					(start 54.578758 -299.088048)
					(mid 54.582478 -299.079068)
					(end 54.591458 -299.075348)
				)
				(arc
					(start 56.064658 -299.075348)
					(mid 56.073638 -299.079068)
					(end 56.077358 -299.088048)
				)
			)
		)
	)
	(zone
		(layer "In1.Cu")
		(hatch none 0.5)
		(connect_pads
			(clearance 0)
		)
		(min_thickness 0.25)
		(keepout
			(tracks not_allowed)
			(vias allowed)
			(pads allowed)
			(copperpour not_allowed)
			(footprints allowed)
		)
		(placement
			(enabled no)
			(sheetname "")
		)
		(fill
			(thermal_gap 0.5)
			(thermal_bridge_width 0.5)
			(island_removal_mode 0)
		)
		(polygon
			(pts
				(arc
					(start 304.017426 -220.532198)
					(mid 304.013706 -220.541178)
					(end 304.004726 -220.544898)
				)
				(arc
					(start 302.531526 -220.544898)
					(mid 302.522546 -220.541178)
					(end 302.518826 -220.532198)
				)
				(arc
					(start 302.518826 -220.03766)
					(mid 302.522546 -220.02868)
					(end 302.531526 -220.02496)
				)
				(arc
					(start 304.004726 -220.02496)
					(mid 304.013706 -220.02868)
					(end 304.017426 -220.03766)
				)
			)
		)
	)
	(zone
		(layer "In1.Cu")
		(hatch none 0.5)
		(connect_pads
			(clearance 0)
		)
		(min_thickness 0.25)
		(keepout
			(tracks not_allowed)
			(vias allowed)
			(pads allowed)
			(copperpour not_allowed)
			(footprints allowed)
		)
		(placement
			(enabled no)
			(sheetname "")
		)
		(fill
			(thermal_gap 0.5)
			(thermal_bridge_width 0.5)
			(island_removal_mode 0)
		)
		(polygon
			(pts
				(arc
					(start 417.217352 -315.73216)
					(mid 417.213632 -315.74114)
					(end 417.204652 -315.74486)
				)
				(arc
					(start 415.731452 -315.74486)
					(mid 415.722472 -315.74114)
					(end 415.718752 -315.73216)
				)
				(arc
					(start 415.718752 -315.237622)
					(mid 415.722472 -315.228642)
					(end 415.731452 -315.224922)
				)
				(arc
					(start 417.204652 -315.224922)
					(mid 417.213632 -315.228642)
					(end 417.217352 -315.237622)
				)
			)
		)
	)
	(zone
		(layer "In1.Cu")
		(hatch none 0.5)
		(connect_pads
			(clearance 0)
		)
		(min_thickness 0.25)
		(keepout
			(tracks not_allowed)
			(vias allowed)
			(pads allowed)
			(copperpour not_allowed)
			(footprints allowed)
		)
		(placement
			(enabled no)
			(sheetname "")
		)
		(fill
			(thermal_gap 0.5)
			(thermal_bridge_width 0.5)
			(island_removal_mode 0)
		)
		(polygon
			(pts
				(arc
					(start 199.4535 -201.832464)
					(mid 199.44978 -201.841444)
					(end 199.4408 -201.845164)
				)
				(arc
					(start 197.9676 -201.845164)
					(mid 197.95862 -201.841444)
					(end 197.9549 -201.832464)
				)
				(arc
					(start 197.9549 -201.337926)
					(mid 197.95862 -201.328946)
					(end 197.9676 -201.325226)
				)
				(arc
					(start 199.4408 -201.325226)
					(mid 199.44978 -201.328946)
					(end 199.4535 -201.337926)
				)
			)
		)
	)
	(zone
		(layer "In1.Cu")
		(hatch none 0.5)
		(connect_pads
			(clearance 0)
		)
		(min_thickness 0.25)
		(keepout
			(tracks not_allowed)
			(vias allowed)
			(pads allowed)
			(copperpour not_allowed)
			(footprints allowed)
		)
		(placement
			(enabled no)
			(sheetname "")
		)
		(fill
			(thermal_gap 0.5)
			(thermal_bridge_width 0.5)
			(island_removal_mode 0)
		)
		(polygon
			(pts
				(arc
					(start 176.821338 -276.632416)
					(mid 176.817618 -276.641396)
					(end 176.808638 -276.645116)
				)
				(arc
					(start 175.335438 -276.645116)
					(mid 175.326458 -276.641396)
					(end 175.322738 -276.632416)
				)
				(arc
					(start 175.322738 -276.137878)
					(mid 175.326458 -276.128898)
					(end 175.335438 -276.125178)
				)
				(arc
					(start 176.808638 -276.125178)
					(mid 176.817618 -276.128898)
					(end 176.821338 -276.137878)
				)
			)
		)
	)
	(zone
		(layer "In1.Cu")
		(hatch none 0.5)
		(connect_pads
			(clearance 0)
		)
		(min_thickness 0.25)
		(keepout
			(tracks not_allowed)
			(vias allowed)
			(pads allowed)
			(copperpour not_allowed)
			(footprints allowed)
		)
		(placement
			(enabled no)
			(sheetname "")
		)
		(fill
			(thermal_gap 0.5)
			(thermal_bridge_width 0.5)
			(island_removal_mode 0)
		)
		(polygon
			(pts
				(arc
					(start 265.87831 -232.184956)
					(mid 265.21791 -232.184956)
					(end 265.87831 -232.184956)
				)
			)
		)
	)
	(zone
		(layer "In1.Cu")
		(hatch none 0.5)
		(connect_pads
			(clearance 0)
		)
		(min_thickness 0.25)
		(keepout
			(tracks not_allowed)
			(vias allowed)
			(pads allowed)
			(copperpour not_allowed)
			(footprints allowed)
		)
		(placement
			(enabled no)
			(sheetname "")
		)
		(fill
			(thermal_gap 0.5)
			(thermal_bridge_width 0.5)
			(island_removal_mode 0)
		)
		(polygon
			(pts
				(arc
					(start 265.87831 -295.935146)
					(mid 265.21791 -295.935146)
					(end 265.87831 -295.935146)
				)
			)
		)
	)
	(zone
		(layer "In1.Cu")
		(hatch none 0.5)
		(connect_pads
			(clearance 0)
		)
		(min_thickness 0.25)
		(keepout
			(tracks not_allowed)
			(vias allowed)
			(pads allowed)
			(copperpour not_allowed)
			(footprints allowed)
		)
		(placement
			(enabled no)
			(sheetname "")
		)
		(fill
			(thermal_gap 0.5)
			(thermal_bridge_width 0.5)
			(island_removal_mode 0)
		)
		(polygon
			(pts
				(arc
					(start 169.277284 -244.332506)
					(mid 169.273564 -244.341486)
					(end 169.264584 -244.345206)
				)
				(arc
					(start 167.791384 -244.345206)
					(mid 167.782404 -244.341486)
					(end 167.778684 -244.332506)
				)
				(arc
					(start 167.778684 -243.837968)
					(mid 167.782404 -243.828988)
					(end 167.791384 -243.825268)
				)
				(arc
					(start 169.264584 -243.825268)
					(mid 169.273564 -243.828988)
					(end 169.277284 -243.837968)
				)
			)
		)
	)
	(zone
		(layer "In1.Cu")
		(hatch none 0.5)
		(connect_pads
			(clearance 0)
		)
		(min_thickness 0.25)
		(keepout
			(tracks not_allowed)
			(vias allowed)
			(pads allowed)
			(copperpour not_allowed)
			(footprints allowed)
		)
		(placement
			(enabled no)
			(sheetname "")
		)
		(fill
			(thermal_gap 0.5)
			(thermal_bridge_width 0.5)
			(island_removal_mode 0)
		)
		(polygon
			(pts
				(arc
					(start 307.061108 -393.69238)
					(mid 306.680108 -393.69238)
					(end 307.061108 -393.69238)
				)
			)
		)
	)
	(zone
		(layer "In1.Cu")
		(hatch none 0.5)
		(connect_pads
			(clearance 0)
		)
		(min_thickness 0.25)
		(keepout
			(tracks not_allowed)
			(vias allowed)
			(pads allowed)
			(copperpour not_allowed)
			(footprints allowed)
		)
		(placement
			(enabled no)
			(sheetname "")
		)
		(fill
			(thermal_gap 0.5)
			(thermal_bridge_width 0.5)
			(island_removal_mode 0)
		)
		(polygon
			(pts
				(arc
					(start 172.72127 -307.232558)
					(mid 172.71755 -307.241538)
					(end 172.70857 -307.245258)
				)
				(arc
					(start 171.23537 -307.245258)
					(mid 171.22639 -307.241538)
					(end 171.22267 -307.232558)
				)
				(arc
					(start 171.22267 -306.73802)
					(mid 171.22639 -306.72904)
					(end 171.23537 -306.72532)
				)
				(arc
					(start 172.70857 -306.72532)
					(mid 172.71755 -306.72904)
					(end 172.72127 -306.73802)
				)
			)
		)
	)
	(zone
		(layer "In1.Cu")
		(hatch none 0.5)
		(connect_pads
			(clearance 0)
		)
		(min_thickness 0.25)
		(keepout
			(tracks not_allowed)
			(vias allowed)
			(pads allowed)
			(copperpour not_allowed)
			(footprints allowed)
		)
		(placement
			(enabled no)
			(sheetname "")
		)
		(fill
			(thermal_gap 0.5)
			(thermal_bridge_width 0.5)
			(island_removal_mode 0)
		)
		(polygon
			(pts
				(arc
					(start 371.29085 -391.822686)
					(mid 371.41785 -391.949686)
					(end 371.54485 -391.822686)
				)
				(arc
					(start 371.54485 -391.746486)
					(mid 371.41785 -391.619486)
					(end 371.29085 -391.746486)
				)
			)
		)
	)
	(zone
		(layer "In1.Cu")
		(hatch none 0.5)
		(connect_pads
			(clearance 0)
		)
		(min_thickness 0.25)
		(keepout
			(tracks not_allowed)
			(vias allowed)
			(pads allowed)
			(copperpour not_allowed)
			(footprints allowed)
		)
		(placement
			(enabled no)
			(sheetname "")
		)
		(fill
			(thermal_gap 0.5)
			(thermal_bridge_width 0.5)
			(island_removal_mode 0)
		)
		(polygon
			(pts
				(arc
					(start 52.633372 -313.182508)
					(mid 52.629652 -313.191488)
					(end 52.620672 -313.195208)
				)
				(arc
					(start 51.147472 -313.195208)
					(mid 51.138492 -313.191488)
					(end 51.134772 -313.182508)
				)
				(arc
					(start 51.134772 -312.68797)
					(mid 51.138492 -312.67899)
					(end 51.147472 -312.67527)
				)
				(arc
					(start 52.620672 -312.67527)
					(mid 52.629652 -312.67899)
					(end 52.633372 -312.68797)
				)
			)
		)
	)
	(zone
		(layer "In1.Cu")
		(hatch none 0.5)
		(connect_pads
			(clearance 0)
		)
		(min_thickness 0.25)
		(keepout
			(tracks not_allowed)
			(vias allowed)
			(pads allowed)
			(copperpour not_allowed)
			(footprints allowed)
		)
		(placement
			(enabled no)
			(sheetname "")
		)
		(fill
			(thermal_gap 0.5)
			(thermal_bridge_width 0.5)
			(island_removal_mode 0)
		)
		(polygon
			(pts
				(arc
					(start 344.388694 -397.156432)
					(mid 344.007694 -397.156432)
					(end 344.388694 -397.156432)
				)
			)
		)
	)
	(zone
		(layer "In1.Cu")
		(hatch none 0.5)
		(connect_pads
			(clearance 0)
		)
		(min_thickness 0.25)
		(keepout
			(tracks not_allowed)
			(vias allowed)
			(pads allowed)
			(copperpour not_allowed)
			(footprints allowed)
		)
		(placement
			(enabled no)
			(sheetname "")
		)
		(fill
			(thermal_gap 0.5)
			(thermal_bridge_width 0.5)
			(island_removal_mode 0)
		)
		(polygon
			(pts
				(arc
					(start 428.205392 -229.882192)
					(mid 428.201672 -229.891172)
					(end 428.192692 -229.894892)
				)
				(arc
					(start 426.719492 -229.894892)
					(mid 426.710512 -229.891172)
					(end 426.706792 -229.882192)
				)
				(arc
					(start 426.706792 -229.387654)
					(mid 426.710512 -229.378674)
					(end 426.719492 -229.374954)
				)
				(arc
					(start 428.192692 -229.374954)
					(mid 428.201672 -229.378674)
					(end 428.205392 -229.387654)
				)
			)
		)
	)
	(zone
		(layer "In1.Cu")
		(hatch none 0.5)
		(connect_pads
			(clearance 0)
		)
		(min_thickness 0.25)
		(keepout
			(tracks not_allowed)
			(vias allowed)
			(pads allowed)
			(copperpour not_allowed)
			(footprints allowed)
		)
		(placement
			(enabled no)
			(sheetname "")
		)
		(fill
			(thermal_gap 0.5)
			(thermal_bridge_width 0.5)
			(island_removal_mode 0)
		)
		(polygon
			(pts
				(arc
					(start 415.198052 -392.30427)
					(mid 414.893252 -392.30427)
					(end 415.198052 -392.30427)
				)
			)
		)
	)
	(zone
		(layer "In1.Cu")
		(hatch none 0.5)
		(connect_pads
			(clearance 0)
		)
		(min_thickness 0.25)
		(keepout
			(tracks not_allowed)
			(vias allowed)
			(pads allowed)
			(copperpour not_allowed)
			(footprints allowed)
		)
		(placement
			(enabled no)
			(sheetname "")
		)
		(fill
			(thermal_gap 0.5)
			(thermal_bridge_width 0.5)
			(island_removal_mode 0)
		)
		(polygon
			(pts
				(arc
					(start 180.265324 -268.982444)
					(mid 180.261604 -268.991424)
					(end 180.252624 -268.995144)
				)
				(arc
					(start 178.779424 -268.995144)
					(mid 178.770444 -268.991424)
					(end 178.766724 -268.982444)
				)
				(arc
					(start 178.766724 -268.487906)
					(mid 178.770444 -268.478926)
					(end 178.779424 -268.475206)
				)
				(arc
					(start 180.252624 -268.475206)
					(mid 180.261604 -268.478926)
					(end 180.265324 -268.487906)
				)
			)
		)
	)
	(zone
		(layer "In1.Cu")
		(hatch none 0.5)
		(connect_pads
			(clearance 0)
		)
		(min_thickness 0.25)
		(keepout
			(tracks not_allowed)
			(vias allowed)
			(pads allowed)
			(copperpour not_allowed)
			(footprints allowed)
		)
		(placement
			(enabled no)
			(sheetname "")
		)
		(fill
			(thermal_gap 0.5)
			(thermal_bridge_width 0.5)
			(island_removal_mode 0)
		)
		(polygon
			(pts
				(arc
					(start 56.077358 -230.732584)
					(mid 56.073638 -230.741564)
					(end 56.064658 -230.745284)
				)
				(arc
					(start 54.591458 -230.745284)
					(mid 54.582478 -230.741564)
					(end 54.578758 -230.732584)
				)
				(arc
					(start 54.578758 -230.238046)
					(mid 54.582478 -230.229066)
					(end 54.591458 -230.225346)
				)
				(arc
					(start 56.064658 -230.225346)
					(mid 56.073638 -230.229066)
					(end 56.077358 -230.238046)
				)
			)
		)
	)
	(zone
		(layer "In1.Cu")
		(hatch none 0.5)
		(connect_pads
			(clearance 0)
		)
		(min_thickness 0.25)
		(keepout
			(tracks not_allowed)
			(vias allowed)
			(pads allowed)
			(copperpour not_allowed)
			(footprints allowed)
		)
		(placement
			(enabled no)
			(sheetname "")
		)
		(fill
			(thermal_gap 0.5)
			(thermal_bridge_width 0.5)
			(island_removal_mode 0)
		)
		(polygon
			(pts
				(arc
					(start 89.589102 -385.31038)
					(mid 89.208102 -385.31038)
					(end 89.589102 -385.31038)
				)
			)
		)
	)
	(zone
		(layer "In1.Cu")
		(hatch none 0.5)
		(connect_pads
			(clearance 0)
		)
		(min_thickness 0.25)
		(keepout
			(tracks not_allowed)
			(vias allowed)
			(pads allowed)
			(copperpour not_allowed)
			(footprints allowed)
		)
		(placement
			(enabled no)
			(sheetname "")
		)
		(fill
			(thermal_gap 0.5)
			(thermal_bridge_width 0.5)
			(island_removal_mode 0)
		)
		(polygon
			(pts
				(arc
					(start 420.661338 -229.882192)
					(mid 420.657618 -229.891172)
					(end 420.648638 -229.894892)
				)
				(arc
					(start 419.175438 -229.894892)
					(mid 419.166458 -229.891172)
					(end 419.162738 -229.882192)
				)
				(arc
					(start 419.162738 -229.387654)
					(mid 419.166458 -229.378674)
					(end 419.175438 -229.374954)
				)
				(arc
					(start 420.648638 -229.374954)
					(mid 420.657618 -229.378674)
					(end 420.661338 -229.387654)
				)
			)
		)
	)
	(zone
		(layer "In1.Cu")
		(hatch none 0.5)
		(connect_pads
			(clearance 0)
		)
		(min_thickness 0.25)
		(keepout
			(tracks not_allowed)
			(vias allowed)
			(pads allowed)
			(copperpour not_allowed)
			(footprints allowed)
		)
		(placement
			(enabled no)
			(sheetname "")
		)
		(fill
			(thermal_gap 0.5)
			(thermal_bridge_width 0.5)
			(island_removal_mode 0)
		)
		(polygon
			(pts
				(arc
					(start 150.798022 -390.761474)
					(mid 150.493222 -390.761474)
					(end 150.798022 -390.761474)
				)
			)
		)
	)
	(zone
		(layer "In1.Cu")
		(hatch none 0.5)
		(connect_pads
			(clearance 0)
		)
		(min_thickness 0.25)
		(keepout
			(tracks not_allowed)
			(vias allowed)
			(pads allowed)
			(copperpour not_allowed)
			(footprints allowed)
		)
		(placement
			(enabled no)
			(sheetname "")
		)
		(fill
			(thermal_gap 0.5)
			(thermal_bridge_width 0.5)
			(island_removal_mode 0)
		)
		(polygon
			(pts
				(arc
					(start 180.265324 -215.432386)
					(mid 180.261604 -215.441366)
					(end 180.252624 -215.445086)
				)
				(arc
					(start 178.779424 -215.445086)
					(mid 178.770444 -215.441366)
					(end 178.766724 -215.432386)
				)
				(arc
					(start 178.766724 -214.937848)
					(mid 178.770444 -214.928868)
					(end 178.779424 -214.925148)
				)
				(arc
					(start 180.252624 -214.925148)
					(mid 180.261604 -214.928868)
					(end 180.265324 -214.937848)
				)
			)
		)
	)
	(zone
		(layer "In1.Cu")
		(hatch none 0.5)
		(connect_pads
			(clearance 0)
		)
		(min_thickness 0.25)
		(keepout
			(tracks not_allowed)
			(vias allowed)
			(pads allowed)
			(copperpour not_allowed)
			(footprints allowed)
		)
		(placement
			(enabled no)
			(sheetname "")
		)
		(fill
			(thermal_gap 0.5)
			(thermal_bridge_width 0.5)
			(island_removal_mode 0)
		)
		(polygon
			(pts
				(arc
					(start 293.029386 -304.682144)
					(mid 293.025666 -304.691124)
					(end 293.016686 -304.694844)
				)
				(arc
					(start 291.543486 -304.694844)
					(mid 291.534506 -304.691124)
					(end 291.530786 -304.682144)
				)
				(arc
					(start 291.530786 -304.187606)
					(mid 291.534506 -304.178626)
					(end 291.543486 -304.174906)
				)
				(arc
					(start 293.016686 -304.174906)
					(mid 293.025666 -304.178626)
					(end 293.029386 -304.187606)
				)
			)
		)
	)
	(zone
		(layer "In1.Cu")
		(hatch none 0.5)
		(connect_pads
			(clearance 0)
		)
		(min_thickness 0.25)
		(keepout
			(tracks not_allowed)
			(vias allowed)
			(pads allowed)
			(copperpour not_allowed)
			(footprints allowed)
		)
		(placement
			(enabled no)
			(sheetname "")
		)
		(fill
			(thermal_gap 0.5)
			(thermal_bridge_width 0.5)
			(island_removal_mode 0)
		)
		(polygon
			(pts
				(arc
					(start 314.370212 -399.143474)
					(mid 314.065412 -399.143474)
					(end 314.370212 -399.143474)
				)
			)
		)
	)
	(zone
		(layer "In1.Cu")
		(hatch none 0.5)
		(connect_pads
			(clearance 0)
		)
		(min_thickness 0.25)
		(keepout
			(tracks not_allowed)
			(vias allowed)
			(pads allowed)
			(copperpour not_allowed)
			(footprints allowed)
		)
		(placement
			(enabled no)
			(sheetname "")
		)
		(fill
			(thermal_gap 0.5)
			(thermal_bridge_width 0.5)
			(island_removal_mode 0)
		)
		(polygon
			(pts
				(arc
					(start 37.545264 -297.032426)
					(mid 37.541544 -297.041406)
					(end 37.532564 -297.045126)
				)
				(arc
					(start 36.059364 -297.045126)
					(mid 36.050384 -297.041406)
					(end 36.046664 -297.032426)
				)
				(arc
					(start 36.046664 -296.537888)
					(mid 36.050384 -296.528908)
					(end 36.059364 -296.525188)
				)
				(arc
					(start 37.532564 -296.525188)
					(mid 37.541544 -296.528908)
					(end 37.545264 -296.537888)
				)
			)
		)
	)
	(zone
		(layer "In1.Cu")
		(hatch none 0.5)
		(connect_pads
			(clearance 0)
		)
		(min_thickness 0.25)
		(keepout
			(tracks not_allowed)
			(vias allowed)
			(pads allowed)
			(copperpour not_allowed)
			(footprints allowed)
		)
		(placement
			(enabled no)
			(sheetname "")
		)
		(fill
			(thermal_gap 0.5)
			(thermal_bridge_width 0.5)
			(island_removal_mode 0)
		)
		(polygon
			(pts
				(arc
					(start 443.2935 -277.4823)
					(mid 443.28978 -277.49128)
					(end 443.2808 -277.495)
				)
				(arc
					(start 441.8076 -277.495)
					(mid 441.79862 -277.49128)
					(end 441.7949 -277.4823)
				)
				(arc
					(start 441.7949 -276.987762)
					(mid 441.79862 -276.978782)
					(end 441.8076 -276.975062)
				)
				(arc
					(start 443.2808 -276.975062)
					(mid 443.28978 -276.978782)
					(end 443.2935 -276.987762)
				)
			)
		)
	)
	(zone
		(layer "In1.Cu")
		(hatch none 0.5)
		(connect_pads
			(clearance 0)
		)
		(min_thickness 0.25)
		(keepout
			(tracks not_allowed)
			(vias allowed)
			(pads allowed)
			(copperpour not_allowed)
			(footprints allowed)
		)
		(placement
			(enabled no)
			(sheetname "")
		)
		(fill
			(thermal_gap 0.5)
			(thermal_bridge_width 0.5)
			(island_removal_mode 0)
		)
		(polygon
			(pts
				(arc
					(start 265.87831 -286.585152)
					(mid 265.21791 -286.585152)
					(end 265.87831 -286.585152)
				)
			)
		)
	)
	(zone
		(layer "In1.Cu")
		(hatch none 0.5)
		(connect_pads
			(clearance 0)
		)
		(min_thickness 0.25)
		(keepout
			(tracks not_allowed)
			(vias allowed)
			(pads allowed)
			(copperpour not_allowed)
			(footprints allowed)
		)
		(placement
			(enabled no)
			(sheetname "")
		)
		(fill
			(thermal_gap 0.5)
			(thermal_bridge_width 0.5)
			(island_removal_mode 0)
		)
		(polygon
			(pts
				(arc
					(start 169.277284 -292.782498)
					(mid 169.273564 -292.791478)
					(end 169.264584 -292.795198)
				)
				(arc
					(start 167.791384 -292.795198)
					(mid 167.782404 -292.791478)
					(end 167.778684 -292.782498)
				)
				(arc
					(start 167.778684 -292.28796)
					(mid 167.782404 -292.27898)
					(end 167.791384 -292.27526)
				)
				(arc
					(start 169.264584 -292.27526)
					(mid 169.273564 -292.27898)
					(end 169.277284 -292.28796)
				)
			)
		)
	)
	(zone
		(layer "In1.Cu")
		(hatch none 0.5)
		(connect_pads
			(clearance 0)
		)
		(min_thickness 0.25)
		(keepout
			(tracks not_allowed)
			(vias allowed)
			(pads allowed)
			(copperpour not_allowed)
			(footprints allowed)
		)
		(placement
			(enabled no)
			(sheetname "")
		)
		(fill
			(thermal_gap 0.5)
			(thermal_bridge_width 0.5)
			(island_removal_mode 0)
		)
		(polygon
			(pts
				(arc
					(start 45.089318 -246.032528)
					(mid 45.085598 -246.041508)
					(end 45.076618 -246.045228)
				)
				(arc
					(start 43.603418 -246.045228)
					(mid 43.594438 -246.041508)
					(end 43.590718 -246.032528)
				)
				(arc
					(start 43.590718 -245.53799)
					(mid 43.594438 -245.52901)
					(end 43.603418 -245.52529)
				)
				(arc
					(start 45.076618 -245.52529)
					(mid 45.085598 -245.52901)
					(end 45.089318 -245.53799)
				)
			)
		)
	)
	(zone
		(layer "In1.Cu")
		(hatch none 0.5)
		(connect_pads
			(clearance 0)
		)
		(min_thickness 0.25)
		(keepout
			(tracks not_allowed)
			(vias allowed)
			(pads allowed)
			(copperpour not_allowed)
			(footprints allowed)
		)
		(placement
			(enabled no)
			(sheetname "")
		)
		(fill
			(thermal_gap 0.5)
			(thermal_bridge_width 0.5)
			(island_removal_mode 0)
		)
		(polygon
			(pts
				(arc
					(start 37.545264 -308.082442)
					(mid 37.541544 -308.091422)
					(end 37.532564 -308.095142)
				)
				(arc
					(start 36.059364 -308.095142)
					(mid 36.050384 -308.091422)
					(end 36.046664 -308.082442)
				)
				(arc
					(start 36.046664 -307.587904)
					(mid 36.050384 -307.578924)
					(end 36.059364 -307.575204)
				)
				(arc
					(start 37.532564 -307.575204)
					(mid 37.541544 -307.578924)
					(end 37.545264 -307.587904)
				)
			)
		)
	)
	(zone
		(layer "In1.Cu")
		(hatch none 0.5)
		(connect_pads
			(clearance 0)
		)
		(min_thickness 0.25)
		(keepout
			(tracks not_allowed)
			(vias allowed)
			(pads allowed)
			(copperpour not_allowed)
			(footprints allowed)
		)
		(placement
			(enabled no)
			(sheetname "")
		)
		(fill
			(thermal_gap 0.5)
			(thermal_bridge_width 0.5)
			(island_removal_mode 0)
		)
		(polygon
			(pts
				(arc
					(start 163.418774 -391.319258)
					(mid 163.545774 -391.446258)
					(end 163.672774 -391.319258)
				)
				(arc
					(start 163.672774 -391.243058)
					(mid 163.545774 -391.116058)
					(end 163.418774 -391.243058)
				)
			)
		)
	)
	(zone
		(layer "In1.Cu")
		(hatch none 0.5)
		(connect_pads
			(clearance 0)
		)
		(min_thickness 0.25)
		(keepout
			(tracks not_allowed)
			(vias allowed)
			(pads allowed)
			(copperpour not_allowed)
			(footprints allowed)
		)
		(placement
			(enabled no)
			(sheetname "")
		)
		(fill
			(thermal_gap 0.5)
			(thermal_bridge_width 0.5)
			(island_removal_mode 0)
		)
		(polygon
			(pts
				(arc
					(start 56.077358 -253.6825)
					(mid 56.073638 -253.69148)
					(end 56.064658 -253.6952)
				)
				(arc
					(start 54.591458 -253.6952)
					(mid 54.582478 -253.69148)
					(end 54.578758 -253.6825)
				)
				(arc
					(start 54.578758 -253.187962)
					(mid 54.582478 -253.178982)
					(end 54.591458 -253.175262)
				)
				(arc
					(start 56.064658 -253.175262)
					(mid 56.073638 -253.178982)
					(end 56.077358 -253.187962)
				)
			)
		)
	)
	(zone
		(layer "In1.Cu")
		(hatch none 0.5)
		(connect_pads
			(clearance 0)
		)
		(min_thickness 0.25)
		(keepout
			(tracks not_allowed)
			(vias allowed)
			(pads allowed)
			(copperpour not_allowed)
			(footprints allowed)
		)
		(placement
			(enabled no)
			(sheetname "")
		)
		(fill
			(thermal_gap 0.5)
			(thermal_bridge_width 0.5)
			(island_removal_mode 0)
		)
		(polygon
			(pts
				(arc
					(start 450.8373 -277.4823)
					(mid 450.83358 -277.49128)
					(end 450.8246 -277.495)
				)
				(arc
					(start 449.3514 -277.495)
					(mid 449.34242 -277.49128)
					(end 449.3387 -277.4823)
				)
				(arc
					(start 449.3387 -276.987762)
					(mid 449.34242 -276.978782)
					(end 449.3514 -276.975062)
				)
				(arc
					(start 450.8246 -276.975062)
					(mid 450.83358 -276.978782)
					(end 450.8373 -276.987762)
				)
			)
		)
	)
	(zone
		(layer "In1.Cu")
		(hatch none 0.5)
		(connect_pads
			(clearance 0)
		)
		(min_thickness 0.25)
		(keepout
			(tracks not_allowed)
			(vias allowed)
			(pads allowed)
			(copperpour not_allowed)
			(footprints allowed)
		)
		(placement
			(enabled no)
			(sheetname "")
		)
		(fill
			(thermal_gap 0.5)
			(thermal_bridge_width 0.5)
			(island_removal_mode 0)
		)
		(polygon
			(pts
				(arc
					(start 417.217352 -292.782244)
					(mid 417.213632 -292.791224)
					(end 417.204652 -292.794944)
				)
				(arc
					(start 415.731452 -292.794944)
					(mid 415.722472 -292.791224)
					(end 415.718752 -292.782244)
				)
				(arc
					(start 415.718752 -292.287706)
					(mid 415.722472 -292.278726)
					(end 415.731452 -292.275006)
				)
				(arc
					(start 417.204652 -292.275006)
					(mid 417.213632 -292.278726)
					(end 417.217352 -292.287706)
				)
			)
		)
	)
	(zone
		(layer "In1.Cu")
		(hatch none 0.5)
		(connect_pads
			(clearance 0)
		)
		(min_thickness 0.25)
		(keepout
			(tracks not_allowed)
			(vias allowed)
			(pads allowed)
			(copperpour not_allowed)
			(footprints allowed)
		)
		(placement
			(enabled no)
			(sheetname "")
		)
		(fill
			(thermal_gap 0.5)
			(thermal_bridge_width 0.5)
			(island_removal_mode 0)
		)
		(polygon
			(pts
				(arc
					(start 354.388674 -394.385292)
					(mid 354.007674 -394.385292)
					(end 354.388674 -394.385292)
				)
			)
		)
	)
	(zone
		(layer "In1.Cu")
		(hatch none 0.5)
		(connect_pads
			(clearance 0)
		)
		(min_thickness 0.25)
		(keepout
			(tracks not_allowed)
			(vias allowed)
			(pads allowed)
			(copperpour not_allowed)
			(footprints allowed)
		)
		(placement
			(enabled no)
			(sheetname "")
		)
		(fill
			(thermal_gap 0.5)
			(thermal_bridge_width 0.5)
			(island_removal_mode 0)
		)
		(polygon
			(pts
				(arc
					(start 288.929318 -295.33215)
					(mid 288.925598 -295.34113)
					(end 288.916618 -295.34485)
				)
				(arc
					(start 287.443418 -295.34485)
					(mid 287.434438 -295.34113)
					(end 287.430718 -295.33215)
				)
				(arc
					(start 287.430718 -294.837612)
					(mid 287.434438 -294.828632)
					(end 287.443418 -294.824912)
				)
				(arc
					(start 288.916618 -294.824912)
					(mid 288.925598 -294.828632)
					(end 288.929318 -294.837612)
				)
			)
		)
	)
	(zone
		(layer "In1.Cu")
		(hatch none 0.5)
		(connect_pads
			(clearance 0)
		)
		(min_thickness 0.25)
		(keepout
			(tracks not_allowed)
			(vias allowed)
			(pads allowed)
			(copperpour not_allowed)
			(footprints allowed)
		)
		(placement
			(enabled no)
			(sheetname "")
		)
		(fill
			(thermal_gap 0.5)
			(thermal_bridge_width 0.5)
			(island_removal_mode 0)
		)
		(polygon
			(pts
				(arc
					(start 150.689056 -388.774432)
					(mid 150.308056 -388.774432)
					(end 150.689056 -388.774432)
				)
			)
		)
	)
	(zone
		(layer "In1.Cu")
		(hatch none 0.5)
		(connect_pads
			(clearance 0)
		)
		(min_thickness 0.25)
		(keepout
			(tracks not_allowed)
			(vias allowed)
			(pads allowed)
			(copperpour not_allowed)
			(footprints allowed)
		)
		(placement
			(enabled no)
			(sheetname "")
		)
		(fill
			(thermal_gap 0.5)
			(thermal_bridge_width 0.5)
			(island_removal_mode 0)
		)
		(polygon
			(pts
				(arc
					(start 172.72127 -288.53257)
					(mid 172.71755 -288.54155)
					(end 172.70857 -288.54527)
				)
				(arc
					(start 171.23537 -288.54527)
					(mid 171.22639 -288.54155)
					(end 171.22267 -288.53257)
				)
				(arc
					(start 171.22267 -288.038032)
					(mid 171.22639 -288.029052)
					(end 171.23537 -288.025332)
				)
				(arc
					(start 172.70857 -288.025332)
					(mid 172.71755 -288.029052)
					(end 172.72127 -288.038032)
				)
			)
		)
	)
	(zone
		(layer "In1.Cu")
		(hatch none 0.5)
		(connect_pads
			(clearance 0)
		)
		(min_thickness 0.25)
		(keepout
			(tracks not_allowed)
			(vias allowed)
			(pads allowed)
			(copperpour not_allowed)
			(footprints allowed)
		)
		(placement
			(enabled no)
			(sheetname "")
		)
		(fill
			(thermal_gap 0.5)
			(thermal_bridge_width 0.5)
			(island_removal_mode 0)
		)
		(polygon
			(pts
				(arc
					(start 65.570354 -390.761474)
					(mid 65.265554 -390.761474)
					(end 65.570354 -390.761474)
				)
			)
		)
	)
	(zone
		(layer "In1.Cu")
		(hatch none 0.5)
		(connect_pads
			(clearance 0)
		)
		(min_thickness 0.25)
		(keepout
			(tracks not_allowed)
			(vias allowed)
			(pads allowed)
			(copperpour not_allowed)
			(footprints allowed)
		)
		(placement
			(enabled no)
			(sheetname "")
		)
		(fill
			(thermal_gap 0.5)
			(thermal_bridge_width 0.5)
			(island_removal_mode 0)
		)
		(polygon
			(pts
				(arc
					(start 428.07255 -7.672324)
					(mid 428.094868 -7.618442)
					(end 428.14875 -7.596124)
				)
				(arc
					(start 429.185324 -7.596124)
					(mid 429.239206 -7.618442)
					(end 429.261524 -7.672324)
				)
				(arc
					(start 429.261524 -9.071864)
					(mid 429.239206 -9.125746)
					(end 429.185324 -9.148064)
				)
				(arc
					(start 428.14875 -9.148064)
					(mid 428.094868 -9.125746)
					(end 428.07255 -9.071864)
				)
			)
		)
	)
	(zone
		(layer "In1.Cu")
		(hatch none 0.5)
		(connect_pads
			(clearance 0)
		)
		(min_thickness 0.25)
		(keepout
			(tracks not_allowed)
			(vias allowed)
			(pads allowed)
			(copperpour not_allowed)
			(footprints allowed)
		)
		(placement
			(enabled no)
			(sheetname "")
		)
		(fill
			(thermal_gap 0.5)
			(thermal_bridge_width 0.5)
			(island_removal_mode 0)
		)
		(polygon
			(pts
				(arc
					(start 432.30546 -229.882192)
					(mid 432.30174 -229.891172)
					(end 432.29276 -229.894892)
				)
				(arc
					(start 430.81956 -229.894892)
					(mid 430.81058 -229.891172)
					(end 430.80686 -229.882192)
				)
				(arc
					(start 430.80686 -229.387654)
					(mid 430.81058 -229.378674)
					(end 430.81956 -229.374954)
				)
				(arc
					(start 432.29276 -229.374954)
					(mid 432.30174 -229.378674)
					(end 432.30546 -229.387654)
				)
			)
		)
	)
	(zone
		(layer "In1.Cu")
		(hatch none 0.5)
		(connect_pads
			(clearance 0)
		)
		(min_thickness 0.25)
		(keepout
			(tracks not_allowed)
			(vias allowed)
			(pads allowed)
			(copperpour not_allowed)
			(footprints allowed)
		)
		(placement
			(enabled no)
			(sheetname "")
		)
		(fill
			(thermal_gap 0.5)
			(thermal_bridge_width 0.5)
			(island_removal_mode 0)
		)
		(polygon
			(pts
				(arc
					(start 273.841464 -268.98219)
					(mid 273.837744 -268.99117)
					(end 273.828764 -268.99489)
				)
				(arc
					(start 272.355564 -268.99489)
					(mid 272.346584 -268.99117)
					(end 272.342864 -268.98219)
				)
				(arc
					(start 272.342864 -268.487652)
					(mid 272.346584 -268.478672)
					(end 272.355564 -268.474952)
				)
				(arc
					(start 273.828764 -268.474952)
					(mid 273.837744 -268.478672)
					(end 273.841464 -268.487652)
				)
			)
		)
	)
	(zone
		(layer "In1.Cu")
		(hatch none 0.5)
		(connect_pads
			(clearance 0)
		)
		(min_thickness 0.25)
		(keepout
			(tracks not_allowed)
			(vias allowed)
			(pads allowed)
			(copperpour not_allowed)
			(footprints allowed)
		)
		(placement
			(enabled no)
			(sheetname "")
		)
		(fill
			(thermal_gap 0.5)
			(thermal_bridge_width 0.5)
			(island_removal_mode 0)
		)
		(polygon
			(pts
				(arc
					(start 439.849514 -291.082222)
					(mid 439.845794 -291.091202)
					(end 439.836814 -291.094922)
				)
				(arc
					(start 438.363614 -291.094922)
					(mid 438.354634 -291.091202)
					(end 438.350914 -291.082222)
				)
				(arc
					(start 438.350914 -290.587684)
					(mid 438.354634 -290.578704)
					(end 438.363614 -290.574984)
				)
				(arc
					(start 439.836814 -290.574984)
					(mid 439.845794 -290.578704)
					(end 439.849514 -290.587684)
				)
			)
		)
	)
	(zone
		(layer "In1.Cu")
		(hatch none 0.5)
		(connect_pads
			(clearance 0)
		)
		(min_thickness 0.25)
		(keepout
			(tracks not_allowed)
			(vias allowed)
			(pads allowed)
			(copperpour not_allowed)
			(footprints allowed)
		)
		(placement
			(enabled no)
			(sheetname "")
		)
		(fill
			(thermal_gap 0.5)
			(thermal_bridge_width 0.5)
			(island_removal_mode 0)
		)
		(polygon
			(pts
				(arc
					(start 60.177426 -313.182508)
					(mid 60.173706 -313.191488)
					(end 60.164726 -313.195208)
				)
				(arc
					(start 58.691526 -313.195208)
					(mid 58.682546 -313.191488)
					(end 58.678826 -313.182508)
				)
				(arc
					(start 58.678826 -312.68797)
					(mid 58.682546 -312.67899)
					(end 58.691526 -312.67527)
				)
				(arc
					(start 60.164726 -312.67527)
					(mid 60.173706 -312.67899)
					(end 60.177426 -312.68797)
				)
			)
		)
	)
	(zone
		(layer "In1.Cu")
		(hatch none 0.5)
		(connect_pads
			(clearance 0)
		)
		(min_thickness 0.25)
		(keepout
			(tracks not_allowed)
			(vias allowed)
			(pads allowed)
			(copperpour not_allowed)
			(footprints allowed)
		)
		(placement
			(enabled no)
			(sheetname "")
		)
		(fill
			(thermal_gap 0.5)
			(thermal_bridge_width 0.5)
			(island_removal_mode 0)
		)
		(polygon
			(pts
				(arc
					(start 266.29741 -274.93214)
					(mid 266.29369 -274.94112)
					(end 266.28471 -274.94484)
				)
				(arc
					(start 264.81151 -274.94484)
					(mid 264.80253 -274.94112)
					(end 264.79881 -274.93214)
				)
				(arc
					(start 264.79881 -274.437602)
					(mid 264.80253 -274.428622)
					(end 264.81151 -274.424902)
				)
				(arc
					(start 266.28471 -274.424902)
					(mid 266.29369 -274.428622)
					(end 266.29741 -274.437602)
				)
			)
		)
	)
	(zone
		(layer "In1.Cu")
		(hatch none 0.5)
		(connect_pads
			(clearance 0)
		)
		(min_thickness 0.25)
		(keepout
			(tracks not_allowed)
			(vias allowed)
			(pads allowed)
			(copperpour not_allowed)
			(footprints allowed)
		)
		(placement
			(enabled no)
			(sheetname "")
		)
		(fill
			(thermal_gap 0.5)
			(thermal_bridge_width 0.5)
			(island_removal_mode 0)
		)
		(polygon
			(pts
				(arc
					(start 407.888948 -393.69238)
					(mid 407.507948 -393.69238)
					(end 407.888948 -393.69238)
				)
			)
		)
	)
	(zone
		(layer "In1.Cu")
		(hatch none 0.5)
		(connect_pads
			(clearance 0)
		)
		(min_thickness 0.25)
		(keepout
			(tracks not_allowed)
			(vias allowed)
			(pads allowed)
			(copperpour not_allowed)
			(footprints allowed)
		)
		(placement
			(enabled no)
			(sheetname "")
		)
		(fill
			(thermal_gap 0.5)
			(thermal_bridge_width 0.5)
			(island_removal_mode 0)
		)
		(polygon
			(pts
				(arc
					(start 45.089318 -304.682398)
					(mid 45.085598 -304.691378)
					(end 45.076618 -304.695098)
				)
				(arc
					(start 43.603418 -304.695098)
					(mid 43.594438 -304.691378)
					(end 43.590718 -304.682398)
				)
				(arc
					(start 43.590718 -304.18786)
					(mid 43.594438 -304.17888)
					(end 43.603418 -304.17516)
				)
				(arc
					(start 45.076618 -304.17516)
					(mid 45.085598 -304.17888)
					(end 45.089318 -304.18786)
				)
			)
		)
	)
	(zone
		(layer "In1.Cu")
		(hatch none 0.5)
		(connect_pads
			(clearance 0)
		)
		(min_thickness 0.25)
		(keepout
			(tracks not_allowed)
			(vias allowed)
			(pads allowed)
			(copperpour not_allowed)
			(footprints allowed)
		)
		(placement
			(enabled no)
			(sheetname "")
		)
		(fill
			(thermal_gap 0.5)
			(thermal_bridge_width 0.5)
			(island_removal_mode 0)
		)
		(polygon
			(pts
				(arc
					(start 347.188536 -397.849344)
					(mid 346.807536 -397.849344)
					(end 347.188536 -397.849344)
				)
			)
		)
	)
	(zone
		(layer "In1.Cu")
		(hatch none 0.5)
		(connect_pads
			(clearance 0)
		)
		(min_thickness 0.25)
		(keepout
			(tracks not_allowed)
			(vias allowed)
			(pads allowed)
			(copperpour not_allowed)
			(footprints allowed)
		)
		(placement
			(enabled no)
			(sheetname "")
		)
		(fill
			(thermal_gap 0.5)
			(thermal_bridge_width 0.5)
			(island_removal_mode 0)
		)
		(polygon
			(pts
				(arc
					(start 85.518752 -383.440686)
					(mid 85.645752 -383.567686)
					(end 85.772752 -383.440686)
				)
				(arc
					(start 85.772752 -383.364486)
					(mid 85.645752 -383.237486)
					(end 85.518752 -383.364486)
				)
			)
		)
	)
	(zone
		(layer "In1.Cu")
		(hatch none 0.5)
		(connect_pads
			(clearance 0)
		)
		(min_thickness 0.25)
		(keepout
			(tracks not_allowed)
			(vias allowed)
			(pads allowed)
			(copperpour not_allowed)
			(footprints allowed)
		)
		(placement
			(enabled no)
			(sheetname "")
		)
		(fill
			(thermal_gap 0.5)
			(thermal_bridge_width 0.5)
			(island_removal_mode 0)
		)
		(polygon
			(pts
				(arc
					(start 308.117494 -216.28227)
					(mid 308.113774 -216.29125)
					(end 308.104794 -216.29497)
				)
				(arc
					(start 306.631594 -216.29497)
					(mid 306.622614 -216.29125)
					(end 306.618894 -216.28227)
				)
				(arc
					(start 306.618894 -215.787732)
					(mid 306.622614 -215.778752)
					(end 306.631594 -215.775032)
				)
				(arc
					(start 308.104794 -215.775032)
					(mid 308.113774 -215.778752)
					(end 308.117494 -215.787732)
				)
			)
		)
	)
	(zone
		(layer "In1.Cu")
		(hatch none 0.5)
		(connect_pads
			(clearance 0)
		)
		(min_thickness 0.25)
		(keepout
			(tracks not_allowed)
			(vias allowed)
			(pads allowed)
			(copperpour not_allowed)
			(footprints allowed)
		)
		(placement
			(enabled no)
			(sheetname "")
		)
		(fill
			(thermal_gap 0.5)
			(thermal_bridge_width 0.5)
			(island_removal_mode 0)
		)
		(polygon
			(pts
				(arc
					(start 37.545264 -212.88248)
					(mid 37.541544 -212.89146)
					(end 37.532564 -212.89518)
				)
				(arc
					(start 36.059364 -212.89518)
					(mid 36.050384 -212.89146)
					(end 36.046664 -212.88248)
				)
				(arc
					(start 36.046664 -212.387942)
					(mid 36.050384 -212.378962)
					(end 36.059364 -212.375242)
				)
				(arc
					(start 37.532564 -212.375242)
					(mid 37.541544 -212.378962)
					(end 37.545264 -212.387942)
				)
			)
		)
	)
	(zone
		(layer "In1.Cu")
		(hatch none 0.5)
		(connect_pads
			(clearance 0)
		)
		(min_thickness 0.25)
		(keepout
			(tracks not_allowed)
			(vias allowed)
			(pads allowed)
			(copperpour not_allowed)
			(footprints allowed)
		)
		(placement
			(enabled no)
			(sheetname "")
		)
		(fill
			(thermal_gap 0.5)
			(thermal_bridge_width 0.5)
			(island_removal_mode 0)
		)
		(polygon
			(pts
				(arc
					(start 428.205392 -265.582146)
					(mid 428.201672 -265.591126)
					(end 428.192692 -265.594846)
				)
				(arc
					(start 426.719492 -265.594846)
					(mid 426.710512 -265.591126)
					(end 426.706792 -265.582146)
				)
				(arc
					(start 426.706792 -265.087608)
					(mid 426.710512 -265.078628)
					(end 426.719492 -265.074908)
				)
				(arc
					(start 428.192692 -265.074908)
					(mid 428.201672 -265.078628)
					(end 428.205392 -265.087608)
				)
			)
		)
	)
	(zone
		(layer "In1.Cu")
		(hatch none 0.5)
		(connect_pads
			(clearance 0)
		)
		(min_thickness 0.25)
		(keepout
			(tracks not_allowed)
			(vias allowed)
			(pads allowed)
			(copperpour not_allowed)
			(footprints allowed)
		)
		(placement
			(enabled no)
			(sheetname "")
		)
		(fill
			(thermal_gap 0.5)
			(thermal_bridge_width 0.5)
			(island_removal_mode 0)
		)
		(polygon
			(pts
				(arc
					(start 33.445196 -209.482436)
					(mid 33.441476 -209.491416)
					(end 33.432496 -209.495136)
				)
				(arc
					(start 31.959296 -209.495136)
					(mid 31.950316 -209.491416)
					(end 31.946596 -209.482436)
				)
				(arc
					(start 31.946596 -208.987898)
					(mid 31.950316 -208.978918)
					(end 31.959296 -208.975198)
				)
				(arc
					(start 33.432496 -208.975198)
					(mid 33.441476 -208.978918)
					(end 33.445196 -208.987898)
				)
			)
		)
	)
	(zone
		(layer "In1.Cu")
		(hatch none 0.5)
		(connect_pads
			(clearance 0)
		)
		(min_thickness 0.25)
		(keepout
			(tracks not_allowed)
			(vias allowed)
			(pads allowed)
			(copperpour not_allowed)
			(footprints allowed)
		)
		(placement
			(enabled no)
			(sheetname "")
		)
		(fill
			(thermal_gap 0.5)
			(thermal_bridge_width 0.5)
			(island_removal_mode 0)
		)
		(polygon
			(pts
				(arc
					(start 413.418782 -391.822686)
					(mid 413.545782 -391.949686)
					(end 413.672782 -391.822686)
				)
				(arc
					(start 413.672782 -391.746486)
					(mid 413.545782 -391.619486)
					(end 413.418782 -391.746486)
				)
			)
		)
	)
	(zone
		(layer "In1.Cu")
		(hatch none 0.5)
		(connect_pads
			(clearance 0)
		)
		(min_thickness 0.25)
		(keepout
			(tracks not_allowed)
			(vias allowed)
			(pads allowed)
			(copperpour not_allowed)
			(footprints allowed)
		)
		(placement
			(enabled no)
			(sheetname "")
		)
		(fill
			(thermal_gap 0.5)
			(thermal_bridge_width 0.5)
			(island_removal_mode 0)
		)
		(polygon
			(pts
				(arc
					(start 406.218644 -399.701258)
					(mid 406.345644 -399.828258)
					(end 406.472644 -399.701258)
				)
				(arc
					(start 406.472644 -399.625058)
					(mid 406.345644 -399.498058)
					(end 406.218644 -399.625058)
				)
			)
		)
	)
	(zone
		(layer "In1.Cu")
		(hatch none 0.5)
		(connect_pads
			(clearance 0)
		)
		(min_thickness 0.25)
		(keepout
			(tracks not_allowed)
			(vias allowed)
			(pads allowed)
			(copperpour not_allowed)
			(footprints allowed)
		)
		(placement
			(enabled no)
			(sheetname "")
		)
		(fill
			(thermal_gap 0.5)
			(thermal_bridge_width 0.5)
			(island_removal_mode 0)
		)
		(polygon
			(pts
				(arc
					(start 389.81126 6.701028)
					(mid 389.833578 6.75491)
					(end 389.88746 6.777228)
				)
				(arc
					(start 390.4996 6.777228)
					(mid 390.553482 6.75491)
					(end 390.5758 6.701028)
				)
				(arc
					(start 390.5758 5.603748)
					(mid 390.553482 5.549866)
					(end 390.4996 5.527548)
				)
				(arc
					(start 389.88746 5.527548)
					(mid 389.833578 5.549866)
					(end 389.81126 5.603748)
				)
			)
		)
	)
	(zone
		(layer "In1.Cu")
		(hatch none 0.5)
		(connect_pads
			(clearance 0)
		)
		(min_thickness 0.25)
		(keepout
			(tracks not_allowed)
			(vias allowed)
			(pads allowed)
			(copperpour not_allowed)
			(footprints allowed)
		)
		(placement
			(enabled no)
			(sheetname "")
		)
		(fill
			(thermal_gap 0.5)
			(thermal_bridge_width 0.5)
			(island_removal_mode 0)
		)
		(polygon
			(pts
				(arc
					(start 443.2935 -254.53213)
					(mid 443.28978 -254.54111)
					(end 443.2808 -254.54483)
				)
				(arc
					(start 441.8076 -254.54483)
					(mid 441.79862 -254.54111)
					(end 441.7949 -254.53213)
				)
				(arc
					(start 441.7949 -254.037592)
					(mid 441.79862 -254.028612)
					(end 441.8076 -254.024892)
				)
				(arc
					(start 443.2808 -254.024892)
					(mid 443.28978 -254.028612)
					(end 443.2935 -254.037592)
				)
			)
		)
	)
	(zone
		(layer "In1.Cu")
		(hatch none 0.5)
		(connect_pads
			(clearance 0)
		)
		(min_thickness 0.25)
		(keepout
			(tracks not_allowed)
			(vias allowed)
			(pads allowed)
			(copperpour not_allowed)
			(footprints allowed)
		)
		(placement
			(enabled no)
			(sheetname "")
		)
		(fill
			(thermal_gap 0.5)
			(thermal_bridge_width 0.5)
			(island_removal_mode 0)
		)
		(polygon
			(pts
				(arc
					(start 176.821338 -306.38242)
					(mid 176.817618 -306.3914)
					(end 176.808638 -306.39512)
				)
				(arc
					(start 175.335438 -306.39512)
					(mid 175.326458 -306.3914)
					(end 175.322738 -306.38242)
				)
				(arc
					(start 175.322738 -305.887882)
					(mid 175.326458 -305.878902)
					(end 175.335438 -305.875182)
				)
				(arc
					(start 176.808638 -305.875182)
					(mid 176.817618 -305.878902)
					(end 176.821338 -305.887882)
				)
			)
		)
	)
	(zone
		(layer "In1.Cu")
		(hatch none 0.5)
		(connect_pads
			(clearance 0)
		)
		(min_thickness 0.25)
		(keepout
			(tracks not_allowed)
			(vias allowed)
			(pads allowed)
			(copperpour not_allowed)
			(footprints allowed)
		)
		(placement
			(enabled no)
			(sheetname "")
		)
		(fill
			(thermal_gap 0.5)
			(thermal_bridge_width 0.5)
			(island_removal_mode 0)
		)
		(polygon
			(pts
				(arc
					(start 273.841464 -267.282168)
					(mid 273.837744 -267.291148)
					(end 273.828764 -267.294868)
				)
				(arc
					(start 272.355564 -267.294868)
					(mid 272.346584 -267.291148)
					(end 272.342864 -267.282168)
				)
				(arc
					(start 272.342864 -266.78763)
					(mid 272.346584 -266.77865)
					(end 272.355564 -266.77493)
				)
				(arc
					(start 273.828764 -266.77493)
					(mid 273.837744 -266.77865)
					(end 273.841464 -266.78763)
				)
			)
		)
	)
	(zone
		(layer "In1.Cu")
		(hatch none 0.5)
		(connect_pads
			(clearance 0)
		)
		(min_thickness 0.25)
		(keepout
			(tracks not_allowed)
			(vias allowed)
			(pads allowed)
			(copperpour not_allowed)
			(footprints allowed)
		)
		(placement
			(enabled no)
			(sheetname "")
		)
		(fill
			(thermal_gap 0.5)
			(thermal_bridge_width 0.5)
			(island_removal_mode 0)
		)
		(polygon
			(pts
				(arc
					(start 424.761406 -300.432216)
					(mid 424.757686 -300.441196)
					(end 424.748706 -300.444916)
				)
				(arc
					(start 423.275506 -300.444916)
					(mid 423.266526 -300.441196)
					(end 423.262806 -300.432216)
				)
				(arc
					(start 423.262806 -299.937678)
					(mid 423.266526 -299.928698)
					(end 423.275506 -299.924978)
				)
				(arc
					(start 424.748706 -299.924978)
					(mid 424.757686 -299.928698)
					(end 424.761406 -299.937678)
				)
			)
		)
	)
	(zone
		(layer "In1.Cu")
		(hatch none 0.5)
		(connect_pads
			(clearance 0)
		)
		(min_thickness 0.25)
		(keepout
			(tracks not_allowed)
			(vias allowed)
			(pads allowed)
			(copperpour not_allowed)
			(footprints allowed)
		)
		(placement
			(enabled no)
			(sheetname "")
		)
		(fill
			(thermal_gap 0.5)
			(thermal_bridge_width 0.5)
			(island_removal_mode 0)
		)
		(polygon
			(pts
				(arc
					(start 293.029386 -222.23222)
					(mid 293.025666 -222.2412)
					(end 293.016686 -222.24492)
				)
				(arc
					(start 291.543486 -222.24492)
					(mid 291.534506 -222.2412)
					(end 291.530786 -222.23222)
				)
				(arc
					(start 291.530786 -221.737682)
					(mid 291.534506 -221.728702)
					(end 291.543486 -221.724982)
				)
				(arc
					(start 293.016686 -221.724982)
					(mid 293.025666 -221.728702)
					(end 293.029386 -221.737682)
				)
			)
		)
	)
	(zone
		(layer "In1.Cu")
		(hatch none 0.5)
		(connect_pads
			(clearance 0)
		)
		(min_thickness 0.25)
		(keepout
			(tracks not_allowed)
			(vias allowed)
			(pads allowed)
			(copperpour not_allowed)
			(footprints allowed)
		)
		(placement
			(enabled no)
			(sheetname "")
		)
		(fill
			(thermal_gap 0.5)
			(thermal_bridge_width 0.5)
			(island_removal_mode 0)
		)
		(polygon
			(pts
				(arc
					(start 288.929318 -228.18217)
					(mid 288.925598 -228.19115)
					(end 288.916618 -228.19487)
				)
				(arc
					(start 287.443418 -228.19487)
					(mid 287.434438 -228.19115)
					(end 287.430718 -228.18217)
				)
				(arc
					(start 287.430718 -227.687632)
					(mid 287.434438 -227.678652)
					(end 287.443418 -227.674932)
				)
				(arc
					(start 288.916618 -227.674932)
					(mid 288.925598 -227.678652)
					(end 288.929318 -227.687632)
				)
			)
		)
	)
	(zone
		(layer "In1.Cu")
		(hatch none 0.5)
		(connect_pads
			(clearance 0)
		)
		(min_thickness 0.25)
		(keepout
			(tracks not_allowed)
			(vias allowed)
			(pads allowed)
			(copperpour not_allowed)
			(footprints allowed)
		)
		(placement
			(enabled no)
			(sheetname "")
		)
		(fill
			(thermal_gap 0.5)
			(thermal_bridge_width 0.5)
			(island_removal_mode 0)
		)
		(polygon
			(pts
				(arc
					(start 417.217352 -311.482232)
					(mid 417.213632 -311.491212)
					(end 417.204652 -311.494932)
				)
				(arc
					(start 415.731452 -311.494932)
					(mid 415.722472 -311.491212)
					(end 415.718752 -311.482232)
				)
				(arc
					(start 415.718752 -310.987694)
					(mid 415.722472 -310.978714)
					(end 415.731452 -310.974994)
				)
				(arc
					(start 417.204652 -310.974994)
					(mid 417.213632 -310.978714)
					(end 417.217352 -310.987694)
				)
			)
		)
	)
	(zone
		(layer "In1.Cu")
		(hatch none 0.5)
		(connect_pads
			(clearance 0)
		)
		(min_thickness 0.25)
		(keepout
			(tracks not_allowed)
			(vias allowed)
			(pads allowed)
			(copperpour not_allowed)
			(footprints allowed)
		)
		(placement
			(enabled no)
			(sheetname "")
		)
		(fill
			(thermal_gap 0.5)
			(thermal_bridge_width 0.5)
			(island_removal_mode 0)
		)
		(polygon
			(pts
				(arc
					(start 413.117284 -254.53213)
					(mid 413.113564 -254.54111)
					(end 413.104584 -254.54483)
				)
				(arc
					(start 411.631384 -254.54483)
					(mid 411.622404 -254.54111)
					(end 411.618684 -254.53213)
				)
				(arc
					(start 411.618684 -254.037592)
					(mid 411.622404 -254.028612)
					(end 411.631384 -254.024892)
				)
				(arc
					(start 413.104584 -254.024892)
					(mid 413.113564 -254.028612)
					(end 413.117284 -254.037592)
				)
			)
		)
	)
	(zone
		(layer "In1.Cu")
		(hatch none 0.5)
		(connect_pads
			(clearance 0)
		)
		(min_thickness 0.25)
		(keepout
			(tracks not_allowed)
			(vias allowed)
			(pads allowed)
			(copperpour not_allowed)
			(footprints allowed)
		)
		(placement
			(enabled no)
			(sheetname "")
		)
		(fill
			(thermal_gap 0.5)
			(thermal_bridge_width 0.5)
			(island_removal_mode 0)
		)
		(polygon
			(pts
				(arc
					(start 165.177216 -243.482368)
					(mid 165.173496 -243.491348)
					(end 165.164516 -243.495068)
				)
				(arc
					(start 163.691316 -243.495068)
					(mid 163.682336 -243.491348)
					(end 163.678616 -243.482368)
				)
				(arc
					(start 163.678616 -242.98783)
					(mid 163.682336 -242.97885)
					(end 163.691316 -242.97513)
				)
				(arc
					(start 165.164516 -242.97513)
					(mid 165.173496 -242.97885)
					(end 165.177216 -242.98783)
				)
			)
		)
	)
	(zone
		(layer "In1.Cu")
		(hatch none 0.5)
		(connect_pads
			(clearance 0)
		)
		(min_thickness 0.25)
		(keepout
			(tracks not_allowed)
			(vias allowed)
			(pads allowed)
			(copperpour not_allowed)
			(footprints allowed)
		)
		(placement
			(enabled no)
			(sheetname "")
		)
		(fill
			(thermal_gap 0.5)
			(thermal_bridge_width 0.5)
			(island_removal_mode 0)
		)
		(polygon
			(pts
				(arc
					(start 169.277284 -211.182458)
					(mid 169.273564 -211.191438)
					(end 169.264584 -211.195158)
				)
				(arc
					(start 167.791384 -211.195158)
					(mid 167.782404 -211.191438)
					(end 167.778684 -211.182458)
				)
				(arc
					(start 167.778684 -210.68792)
					(mid 167.782404 -210.67894)
					(end 167.791384 -210.67522)
				)
				(arc
					(start 169.264584 -210.67522)
					(mid 169.273564 -210.67894)
					(end 169.277284 -210.68792)
				)
			)
		)
	)
	(zone
		(layer "In1.Cu")
		(hatch none 0.5)
		(connect_pads
			(clearance 0)
		)
		(min_thickness 0.25)
		(keepout
			(tracks not_allowed)
			(vias allowed)
			(pads allowed)
			(copperpour not_allowed)
			(footprints allowed)
		)
		(placement
			(enabled no)
			(sheetname "")
		)
		(fill
			(thermal_gap 0.5)
			(thermal_bridge_width 0.5)
			(island_removal_mode 0)
		)
		(polygon
			(pts
				(arc
					(start 447.393568 -201.83221)
					(mid 447.389848 -201.84119)
					(end 447.380868 -201.84491)
				)
				(arc
					(start 445.907668 -201.84491)
					(mid 445.898688 -201.84119)
					(end 445.894968 -201.83221)
				)
				(arc
					(start 445.894968 -201.337672)
					(mid 445.898688 -201.328692)
					(end 445.907668 -201.324972)
				)
				(arc
					(start 447.380868 -201.324972)
					(mid 447.389848 -201.328692)
					(end 447.393568 -201.337672)
				)
			)
		)
	)
	(zone
		(layer "In1.Cu")
		(hatch none 0.5)
		(connect_pads
			(clearance 0)
		)
		(min_thickness 0.25)
		(keepout
			(tracks not_allowed)
			(vias allowed)
			(pads allowed)
			(copperpour not_allowed)
			(footprints allowed)
		)
		(placement
			(enabled no)
			(sheetname "")
		)
		(fill
			(thermal_gap 0.5)
			(thermal_bridge_width 0.5)
			(island_removal_mode 0)
		)
		(polygon
			(pts
				(arc
					(start 424.761406 -247.732296)
					(mid 424.757686 -247.741276)
					(end 424.748706 -247.744996)
				)
				(arc
					(start 423.275506 -247.744996)
					(mid 423.266526 -247.741276)
					(end 423.262806 -247.732296)
				)
				(arc
					(start 423.262806 -247.237758)
					(mid 423.266526 -247.228778)
					(end 423.275506 -247.225058)
				)
				(arc
					(start 424.748706 -247.225058)
					(mid 424.757686 -247.228778)
					(end 424.761406 -247.237758)
				)
			)
		)
	)
	(zone
		(layer "In1.Cu")
		(hatch none 0.5)
		(connect_pads
			(clearance 0)
		)
		(min_thickness 0.25)
		(keepout
			(tracks not_allowed)
			(vias allowed)
			(pads allowed)
			(copperpour not_allowed)
			(footprints allowed)
		)
		(placement
			(enabled no)
			(sheetname "")
		)
		(fill
			(thermal_gap 0.5)
			(thermal_bridge_width 0.5)
			(island_removal_mode 0)
		)
		(polygon
			(pts
				(arc
					(start 293.029386 -219.682314)
					(mid 293.025666 -219.691294)
					(end 293.016686 -219.695014)
				)
				(arc
					(start 291.543486 -219.695014)
					(mid 291.534506 -219.691294)
					(end 291.530786 -219.682314)
				)
				(arc
					(start 291.530786 -219.187776)
					(mid 291.534506 -219.178796)
					(end 291.543486 -219.175076)
				)
				(arc
					(start 293.016686 -219.175076)
					(mid 293.025666 -219.178796)
					(end 293.029386 -219.187776)
				)
			)
		)
	)
	(zone
		(layer "In1.Cu")
		(hatch none 0.5)
		(connect_pads
			(clearance 0)
		)
		(min_thickness 0.25)
		(keepout
			(tracks not_allowed)
			(vias allowed)
			(pads allowed)
			(copperpour not_allowed)
			(footprints allowed)
		)
		(placement
			(enabled no)
			(sheetname "")
		)
		(fill
			(thermal_gap 0.5)
			(thermal_bridge_width 0.5)
			(island_removal_mode 0)
		)
		(polygon
			(pts
				(arc
					(start 420.661338 -253.682246)
					(mid 420.657618 -253.691226)
					(end 420.648638 -253.694946)
				)
				(arc
					(start 419.175438 -253.694946)
					(mid 419.166458 -253.691226)
					(end 419.162738 -253.682246)
				)
				(arc
					(start 419.162738 -253.187708)
					(mid 419.166458 -253.178728)
					(end 419.175438 -253.175008)
				)
				(arc
					(start 420.648638 -253.175008)
					(mid 420.657618 -253.178728)
					(end 420.661338 -253.187708)
				)
			)
		)
	)
	(zone
		(layer "In1.Cu")
		(hatch none 0.5)
		(connect_pads
			(clearance 0)
		)
		(min_thickness 0.25)
		(keepout
			(tracks not_allowed)
			(vias allowed)
			(pads allowed)
			(copperpour not_allowed)
			(footprints allowed)
		)
		(placement
			(enabled no)
			(sheetname "")
		)
		(fill
			(thermal_gap 0.5)
			(thermal_bridge_width 0.5)
			(island_removal_mode 0)
		)
		(polygon
			(pts
				(arc
					(start 277.941532 -292.782244)
					(mid 277.937812 -292.791224)
					(end 277.928832 -292.794944)
				)
				(arc
					(start 276.455632 -292.794944)
					(mid 276.446652 -292.791224)
					(end 276.442932 -292.782244)
				)
				(arc
					(start 276.442932 -292.287706)
					(mid 276.446652 -292.278726)
					(end 276.455632 -292.275006)
				)
				(arc
					(start 277.928832 -292.275006)
					(mid 277.937812 -292.278726)
					(end 277.941532 -292.287706)
				)
			)
		)
	)
	(zone
		(layer "In1.Cu")
		(hatch none 0.5)
		(connect_pads
			(clearance 0)
		)
		(min_thickness 0.25)
		(keepout
			(tracks not_allowed)
			(vias allowed)
			(pads allowed)
			(copperpour not_allowed)
			(footprints allowed)
		)
		(placement
			(enabled no)
			(sheetname "")
		)
		(fill
			(thermal_gap 0.5)
			(thermal_bridge_width 0.5)
			(island_removal_mode 0)
		)
		(polygon
			(pts
				(arc
					(start 432.30546 -254.53213)
					(mid 432.30174 -254.54111)
					(end 432.29276 -254.54483)
				)
				(arc
					(start 430.81956 -254.54483)
					(mid 430.81058 -254.54111)
					(end 430.80686 -254.53213)
				)
				(arc
					(start 430.80686 -254.037592)
					(mid 430.81058 -254.028612)
					(end 430.81956 -254.024892)
				)
				(arc
					(start 432.29276 -254.024892)
					(mid 432.30174 -254.028612)
					(end 432.30546 -254.037592)
				)
			)
		)
	)
	(zone
		(layer "In1.Cu")
		(hatch none 0.5)
		(connect_pads
			(clearance 0)
		)
		(min_thickness 0.25)
		(keepout
			(tracks not_allowed)
			(vias allowed)
			(pads allowed)
			(copperpour not_allowed)
			(footprints allowed)
		)
		(placement
			(enabled no)
			(sheetname "")
		)
		(fill
			(thermal_gap 0.5)
			(thermal_bridge_width 0.5)
			(island_removal_mode 0)
		)
		(polygon
			(pts
				(arc
					(start 115.290854 -391.319258)
					(mid 115.417854 -391.446258)
					(end 115.544854 -391.319258)
				)
				(arc
					(start 115.544854 -391.243058)
					(mid 115.417854 -391.116058)
					(end 115.290854 -391.243058)
				)
			)
		)
	)
	(zone
		(layer "In1.Cu")
		(hatch none 0.5)
		(connect_pads
			(clearance 0)
		)
		(min_thickness 0.25)
		(keepout
			(tracks not_allowed)
			(vias allowed)
			(pads allowed)
			(copperpour not_allowed)
			(footprints allowed)
		)
		(placement
			(enabled no)
			(sheetname "")
		)
		(fill
			(thermal_gap 0.5)
			(thermal_bridge_width 0.5)
			(island_removal_mode 0)
		)
		(polygon
			(pts
				(arc
					(start 45.089318 -249.432572)
					(mid 45.085598 -249.441552)
					(end 45.076618 -249.445272)
				)
				(arc
					(start 43.603418 -249.445272)
					(mid 43.594438 -249.441552)
					(end 43.590718 -249.432572)
				)
				(arc
					(start 43.590718 -248.938034)
					(mid 43.594438 -248.929054)
					(end 43.603418 -248.925334)
				)
				(arc
					(start 45.076618 -248.925334)
					(mid 45.085598 -248.929054)
					(end 45.089318 -248.938034)
				)
			)
		)
	)
	(zone
		(layer "In1.Cu")
		(hatch none 0.5)
		(connect_pads
			(clearance 0)
		)
		(min_thickness 0.25)
		(keepout
			(tracks not_allowed)
			(vias allowed)
			(pads allowed)
			(copperpour not_allowed)
			(footprints allowed)
		)
		(placement
			(enabled no)
			(sheetname "")
		)
		(fill
			(thermal_gap 0.5)
			(thermal_bridge_width 0.5)
			(island_removal_mode 0)
		)
		(polygon
			(pts
				(arc
					(start 33.445196 -215.432386)
					(mid 33.441476 -215.441366)
					(end 33.432496 -215.445086)
				)
				(arc
					(start 31.959296 -215.445086)
					(mid 31.950316 -215.441366)
					(end 31.946596 -215.432386)
				)
				(arc
					(start 31.946596 -214.937848)
					(mid 31.950316 -214.928868)
					(end 31.959296 -214.925148)
				)
				(arc
					(start 33.432496 -214.925148)
					(mid 33.441476 -214.928868)
					(end 33.445196 -214.937848)
				)
			)
		)
	)
	(zone
		(layer "In1.Cu")
		(hatch none 0.5)
		(connect_pads
			(clearance 0)
		)
		(min_thickness 0.25)
		(keepout
			(tracks not_allowed)
			(vias allowed)
			(pads allowed)
			(copperpour not_allowed)
			(footprints allowed)
		)
		(placement
			(enabled no)
			(sheetname "")
		)
		(fill
			(thermal_gap 0.5)
			(thermal_bridge_width 0.5)
			(island_removal_mode 0)
		)
		(polygon
			(pts
				(arc
					(start 339.988652 -397.849344)
					(mid 339.607652 -397.849344)
					(end 339.988652 -397.849344)
				)
			)
		)
	)
	(zone
		(layer "In1.Cu")
		(hatch none 0.5)
		(connect_pads
			(clearance 0)
		)
		(min_thickness 0.25)
		(keepout
			(tracks not_allowed)
			(vias allowed)
			(pads allowed)
			(copperpour not_allowed)
			(footprints allowed)
		)
		(placement
			(enabled no)
			(sheetname "")
		)
		(fill
			(thermal_gap 0.5)
			(thermal_bridge_width 0.5)
			(island_removal_mode 0)
		)
		(polygon
			(pts
				(arc
					(start 417.217352 -295.33215)
					(mid 417.213632 -295.34113)
					(end 417.204652 -295.34485)
				)
				(arc
					(start 415.731452 -295.34485)
					(mid 415.722472 -295.34113)
					(end 415.718752 -295.33215)
				)
				(arc
					(start 415.718752 -294.837612)
					(mid 415.722472 -294.828632)
					(end 415.731452 -294.824912)
				)
				(arc
					(start 417.204652 -294.824912)
					(mid 417.213632 -294.828632)
					(end 417.217352 -294.837612)
				)
			)
		)
	)
	(zone
		(layer "In1.Cu")
		(hatch none 0.5)
		(connect_pads
			(clearance 0)
		)
		(min_thickness 0.25)
		(keepout
			(tracks not_allowed)
			(vias allowed)
			(pads allowed)
			(copperpour not_allowed)
			(footprints allowed)
		)
		(placement
			(enabled no)
			(sheetname "")
		)
		(fill
			(thermal_gap 0.5)
			(thermal_bridge_width 0.5)
			(island_removal_mode 0)
		)
		(polygon
			(pts
				(arc
					(start 22.45741 -214.582502)
					(mid 22.45369 -214.591482)
					(end 22.44471 -214.595202)
				)
				(arc
					(start 20.97151 -214.595202)
					(mid 20.96253 -214.591482)
					(end 20.95881 -214.582502)
				)
				(arc
					(start 20.95881 -214.087964)
					(mid 20.96253 -214.078984)
					(end 20.97151 -214.075264)
				)
				(arc
					(start 22.44471 -214.075264)
					(mid 22.45369 -214.078984)
					(end 22.45741 -214.087964)
				)
			)
		)
	)
	(zone
		(layer "In1.Cu")
		(hatch none 0.5)
		(connect_pads
			(clearance 0)
		)
		(min_thickness 0.25)
		(keepout
			(tracks not_allowed)
			(vias allowed)
			(pads allowed)
			(copperpour not_allowed)
			(footprints allowed)
		)
		(placement
			(enabled no)
			(sheetname "")
		)
		(fill
			(thermal_gap 0.5)
			(thermal_bridge_width 0.5)
			(island_removal_mode 0)
		)
		(polygon
			(pts
				(arc
					(start 33.445196 -282.582366)
					(mid 33.441476 -282.591346)
					(end 33.432496 -282.595066)
				)
				(arc
					(start 31.959296 -282.595066)
					(mid 31.950316 -282.591346)
					(end 31.946596 -282.582366)
				)
				(arc
					(start 31.946596 -282.087828)
					(mid 31.950316 -282.078848)
					(end 31.959296 -282.075128)
				)
				(arc
					(start 33.432496 -282.075128)
					(mid 33.441476 -282.078848)
					(end 33.445196 -282.087828)
				)
			)
		)
	)
	(zone
		(layer "In1.Cu")
		(hatch none 0.5)
		(connect_pads
			(clearance 0)
		)
		(min_thickness 0.25)
		(keepout
			(tracks not_allowed)
			(vias allowed)
			(pads allowed)
			(copperpour not_allowed)
			(footprints allowed)
		)
		(placement
			(enabled no)
			(sheetname "")
		)
		(fill
			(thermal_gap 0.5)
			(thermal_bridge_width 0.5)
			(island_removal_mode 0)
		)
		(polygon
			(pts
				(arc
					(start 45.089318 -297.032426)
					(mid 45.085598 -297.041406)
					(end 45.076618 -297.045126)
				)
				(arc
					(start 43.603418 -297.045126)
					(mid 43.594438 -297.041406)
					(end 43.590718 -297.032426)
				)
				(arc
					(start 43.590718 -296.537888)
					(mid 43.594438 -296.528908)
					(end 43.603418 -296.525188)
				)
				(arc
					(start 45.076618 -296.525188)
					(mid 45.085598 -296.528908)
					(end 45.089318 -296.537888)
				)
			)
		)
	)
	(zone
		(layer "In1.Cu")
		(hatch none 0.5)
		(connect_pads
			(clearance 0)
		)
		(min_thickness 0.25)
		(keepout
			(tracks not_allowed)
			(vias allowed)
			(pads allowed)
			(copperpour not_allowed)
			(footprints allowed)
		)
		(placement
			(enabled no)
			(sheetname "")
		)
		(fill
			(thermal_gap 0.5)
			(thermal_bridge_width 0.5)
			(island_removal_mode 0)
		)
		(polygon
			(pts
				(arc
					(start 432.30546 -203.532232)
					(mid 432.30174 -203.541212)
					(end 432.29276 -203.544932)
				)
				(arc
					(start 430.81956 -203.544932)
					(mid 430.81058 -203.541212)
					(end 430.80686 -203.532232)
				)
				(arc
					(start 430.80686 -203.037694)
					(mid 430.81058 -203.028714)
					(end 430.81956 -203.024994)
				)
				(arc
					(start 432.29276 -203.024994)
					(mid 432.30174 -203.028714)
					(end 432.30546 -203.037694)
				)
			)
		)
	)
	(zone
		(layer "In1.Cu")
		(hatch none 0.5)
		(connect_pads
			(clearance 0)
		)
		(min_thickness 0.25)
		(keepout
			(tracks not_allowed)
			(vias allowed)
			(pads allowed)
			(copperpour not_allowed)
			(footprints allowed)
		)
		(placement
			(enabled no)
			(sheetname "")
		)
		(fill
			(thermal_gap 0.5)
			(thermal_bridge_width 0.5)
			(island_removal_mode 0)
		)
		(polygon
			(pts
				(arc
					(start 48.533304 -248.582434)
					(mid 48.529584 -248.591414)
					(end 48.520604 -248.595134)
				)
				(arc
					(start 47.047404 -248.595134)
					(mid 47.038424 -248.591414)
					(end 47.034704 -248.582434)
				)
				(arc
					(start 47.034704 -248.087896)
					(mid 47.038424 -248.078916)
					(end 47.047404 -248.075196)
				)
				(arc
					(start 48.520604 -248.075196)
					(mid 48.529584 -248.078916)
					(end 48.533304 -248.087896)
				)
			)
		)
	)
	(zone
		(layer "In1.Cu")
		(hatch none 0.5)
		(connect_pads
			(clearance 0)
		)
		(min_thickness 0.25)
		(keepout
			(tracks not_allowed)
			(vias allowed)
			(pads allowed)
			(copperpour not_allowed)
			(footprints allowed)
		)
		(placement
			(enabled no)
			(sheetname "")
		)
		(fill
			(thermal_gap 0.5)
			(thermal_bridge_width 0.5)
			(island_removal_mode 0)
		)
		(polygon
			(pts
				(arc
					(start 97.040954 -294.031416)
					(mid 96.736154 -294.336216)
					(end 97.040954 -294.641016)
				)
				(arc
					(start 97.981008 -294.641016)
					(mid 98.285808 -294.336216)
					(end 97.981008 -294.031416)
				)
			)
		)
	)
	(zone
		(layer "In1.Cu")
		(hatch none 0.5)
		(connect_pads
			(clearance 0)
		)
		(min_thickness 0.25)
		(keepout
			(tracks not_allowed)
			(vias allowed)
			(pads allowed)
			(copperpour not_allowed)
			(footprints allowed)
		)
		(placement
			(enabled no)
			(sheetname "")
		)
		(fill
			(thermal_gap 0.5)
			(thermal_bridge_width 0.5)
			(island_removal_mode 0)
		)
		(polygon
			(pts
				(arc
					(start 300.57344 -231.582214)
					(mid 300.56972 -231.591194)
					(end 300.56074 -231.594914)
				)
				(arc
					(start 299.08754 -231.594914)
					(mid 299.07856 -231.591194)
					(end 299.07484 -231.582214)
				)
				(arc
					(start 299.07484 -231.087676)
					(mid 299.07856 -231.078696)
					(end 299.08754 -231.074976)
				)
				(arc
					(start 300.56074 -231.074976)
					(mid 300.56972 -231.078696)
					(end 300.57344 -231.087676)
				)
			)
		)
	)
	(zone
		(layer "In1.Cu")
		(hatch none 0.5)
		(connect_pads
			(clearance 0)
		)
		(min_thickness 0.25)
		(keepout
			(tracks not_allowed)
			(vias allowed)
			(pads allowed)
			(copperpour not_allowed)
			(footprints allowed)
		)
		(placement
			(enabled no)
			(sheetname "")
		)
		(fill
			(thermal_gap 0.5)
			(thermal_bridge_width 0.5)
			(island_removal_mode 0)
		)
		(polygon
			(pts
				(arc
					(start 165.177216 -198.43242)
					(mid 165.173496 -198.4414)
					(end 165.164516 -198.44512)
				)
				(arc
					(start 163.691316 -198.44512)
					(mid 163.682336 -198.4414)
					(end 163.678616 -198.43242)
				)
				(arc
					(start 163.678616 -197.937882)
					(mid 163.682336 -197.928902)
					(end 163.691316 -197.925182)
				)
				(arc
					(start 165.164516 -197.925182)
					(mid 165.173496 -197.928902)
					(end 165.177216 -197.937882)
				)
			)
		)
	)
	(zone
		(layer "In1.Cu")
		(hatch none 0.5)
		(connect_pads
			(clearance 0)
		)
		(min_thickness 0.25)
		(keepout
			(tracks not_allowed)
			(vias allowed)
			(pads allowed)
			(copperpour not_allowed)
			(footprints allowed)
		)
		(placement
			(enabled no)
			(sheetname "")
		)
		(fill
			(thermal_gap 0.5)
			(thermal_bridge_width 0.5)
			(island_removal_mode 0)
		)
		(polygon
			(pts
				(arc
					(start 45.089318 -234.982512)
					(mid 45.085598 -234.991492)
					(end 45.076618 -234.995212)
				)
				(arc
					(start 43.603418 -234.995212)
					(mid 43.594438 -234.991492)
					(end 43.590718 -234.982512)
				)
				(arc
					(start 43.590718 -234.487974)
					(mid 43.594438 -234.478994)
					(end 43.603418 -234.475274)
				)
				(arc
					(start 45.076618 -234.475274)
					(mid 45.085598 -234.478994)
					(end 45.089318 -234.487974)
				)
			)
		)
	)
	(zone
		(layer "In1.Cu")
		(hatch none 0.5)
		(connect_pads
			(clearance 0)
		)
		(min_thickness 0.25)
		(keepout
			(tracks not_allowed)
			(vias allowed)
			(pads allowed)
			(copperpour not_allowed)
			(footprints allowed)
		)
		(placement
			(enabled no)
			(sheetname "")
		)
		(fill
			(thermal_gap 0.5)
			(thermal_bridge_width 0.5)
			(island_removal_mode 0)
		)
		(polygon
			(pts
				(arc
					(start 424.761406 -199.282304)
					(mid 424.757686 -199.291284)
					(end 424.748706 -199.295004)
				)
				(arc
					(start 423.275506 -199.295004)
					(mid 423.266526 -199.291284)
					(end 423.262806 -199.282304)
				)
				(arc
					(start 423.262806 -198.787766)
					(mid 423.266526 -198.778786)
					(end 423.275506 -198.775066)
				)
				(arc
					(start 424.748706 -198.775066)
					(mid 424.757686 -198.778786)
					(end 424.761406 -198.787766)
				)
			)
		)
	)
	(zone
		(layer "In1.Cu")
		(hatch none 0.5)
		(connect_pads
			(clearance 0)
		)
		(min_thickness 0.25)
		(keepout
			(tracks not_allowed)
			(vias allowed)
			(pads allowed)
			(copperpour not_allowed)
			(footprints allowed)
		)
		(placement
			(enabled no)
			(sheetname "")
		)
		(fill
			(thermal_gap 0.5)
			(thermal_bridge_width 0.5)
			(island_removal_mode 0)
		)
		(polygon
			(pts
				(arc
					(start 187.809378 -288.53257)
					(mid 187.805658 -288.54155)
					(end 187.796678 -288.54527)
				)
				(arc
					(start 186.323478 -288.54527)
					(mid 186.314498 -288.54155)
					(end 186.310778 -288.53257)
				)
				(arc
					(start 186.310778 -288.038032)
					(mid 186.314498 -288.029052)
					(end 186.323478 -288.025332)
				)
				(arc
					(start 187.796678 -288.025332)
					(mid 187.805658 -288.029052)
					(end 187.809378 -288.038032)
				)
			)
		)
	)
	(zone
		(layer "In1.Cu")
		(hatch none 0.5)
		(connect_pads
			(clearance 0)
		)
		(min_thickness 0.25)
		(keepout
			(tracks not_allowed)
			(vias allowed)
			(pads allowed)
			(copperpour not_allowed)
			(footprints allowed)
		)
		(placement
			(enabled no)
			(sheetname "")
		)
		(fill
			(thermal_gap 0.5)
			(thermal_bridge_width 0.5)
			(island_removal_mode 0)
		)
		(polygon
			(pts
				(arc
					(start 180.265324 -254.532384)
					(mid 180.261604 -254.541364)
					(end 180.252624 -254.545084)
				)
				(arc
					(start 178.779424 -254.545084)
					(mid 178.770444 -254.541364)
					(end 178.766724 -254.532384)
				)
				(arc
					(start 178.766724 -254.037846)
					(mid 178.770444 -254.028866)
					(end 178.779424 -254.025146)
				)
				(arc
					(start 180.252624 -254.025146)
					(mid 180.261604 -254.028866)
					(end 180.265324 -254.037846)
				)
			)
		)
	)
	(zone
		(layer "In1.Cu")
		(hatch none 0.5)
		(connect_pads
			(clearance 0)
		)
		(min_thickness 0.25)
		(keepout
			(tracks not_allowed)
			(vias allowed)
			(pads allowed)
			(copperpour not_allowed)
			(footprints allowed)
		)
		(placement
			(enabled no)
			(sheetname "")
		)
		(fill
			(thermal_gap 0.5)
			(thermal_bridge_width 0.5)
			(island_removal_mode 0)
		)
		(polygon
			(pts
				(arc
					(start 387.760972 -394.385292)
					(mid 387.379972 -394.385292)
					(end 387.760972 -394.385292)
				)
			)
		)
	)
	(zone
		(layer "In1.Cu")
		(hatch none 0.5)
		(connect_pads
			(clearance 0)
		)
		(min_thickness 0.25)
		(keepout
			(tracks not_allowed)
			(vias allowed)
			(pads allowed)
			(copperpour not_allowed)
			(footprints allowed)
		)
		(placement
			(enabled no)
			(sheetname "")
		)
		(fill
			(thermal_gap 0.5)
			(thermal_bridge_width 0.5)
			(island_removal_mode 0)
		)
		(polygon
			(pts
				(arc
					(start 184.365392 -287.682432)
					(mid 184.361672 -287.691412)
					(end 184.352692 -287.695132)
				)
				(arc
					(start 182.879492 -287.695132)
					(mid 182.870512 -287.691412)
					(end 182.866792 -287.682432)
				)
				(arc
					(start 182.866792 -287.187894)
					(mid 182.870512 -287.178914)
					(end 182.879492 -287.175194)
				)
				(arc
					(start 184.352692 -287.175194)
					(mid 184.361672 -287.178914)
					(end 184.365392 -287.187894)
				)
			)
		)
	)
	(zone
		(layer "In1.Cu")
		(hatch none 0.5)
		(connect_pads
			(clearance 0)
		)
		(min_thickness 0.25)
		(keepout
			(tracks not_allowed)
			(vias allowed)
			(pads allowed)
			(copperpour not_allowed)
			(footprints allowed)
		)
		(placement
			(enabled no)
			(sheetname "")
		)
		(fill
			(thermal_gap 0.5)
			(thermal_bridge_width 0.5)
			(island_removal_mode 0)
		)
		(polygon
			(pts
				(arc
					(start 417.217352 -302.132238)
					(mid 417.213632 -302.141218)
					(end 417.204652 -302.144938)
				)
				(arc
					(start 415.731452 -302.144938)
					(mid 415.722472 -302.141218)
					(end 415.718752 -302.132238)
				)
				(arc
					(start 415.718752 -301.6377)
					(mid 415.722472 -301.62872)
					(end 415.731452 -301.625)
				)
				(arc
					(start 417.204652 -301.625)
					(mid 417.213632 -301.62872)
					(end 417.217352 -301.6377)
				)
			)
		)
	)
	(zone
		(layer "In1.Cu")
		(hatch none 0.5)
		(connect_pads
			(clearance 0)
		)
		(min_thickness 0.25)
		(keepout
			(tracks not_allowed)
			(vias allowed)
			(pads allowed)
			(copperpour not_allowed)
			(footprints allowed)
		)
		(placement
			(enabled no)
			(sheetname "")
		)
		(fill
			(thermal_gap 0.5)
			(thermal_bridge_width 0.5)
			(island_removal_mode 0)
		)
		(polygon
			(pts
				(arc
					(start 454.937368 -240.932208)
					(mid 454.933648 -240.941188)
					(end 454.924668 -240.944908)
				)
				(arc
					(start 453.451468 -240.944908)
					(mid 453.442488 -240.941188)
					(end 453.438768 -240.932208)
				)
				(arc
					(start 453.438768 -240.43767)
					(mid 453.442488 -240.42869)
					(end 453.451468 -240.42497)
				)
				(arc
					(start 454.924668 -240.42497)
					(mid 454.933648 -240.42869)
					(end 454.937368 -240.43767)
				)
			)
		)
	)
	(zone
		(layer "In1.Cu")
		(hatch none 0.5)
		(connect_pads
			(clearance 0)
		)
		(min_thickness 0.25)
		(keepout
			(tracks not_allowed)
			(vias allowed)
			(pads allowed)
			(copperpour not_allowed)
			(footprints allowed)
		)
		(placement
			(enabled no)
			(sheetname "")
		)
		(fill
			(thermal_gap 0.5)
			(thermal_bridge_width 0.5)
			(island_removal_mode 0)
		)
		(polygon
			(pts
				(arc
					(start 180.265324 -200.132442)
					(mid 180.261604 -200.141422)
					(end 180.252624 -200.145142)
				)
				(arc
					(start 178.779424 -200.145142)
					(mid 178.770444 -200.141422)
					(end 178.766724 -200.132442)
				)
				(arc
					(start 178.766724 -199.637904)
					(mid 178.770444 -199.628924)
					(end 178.779424 -199.625204)
				)
				(arc
					(start 180.252624 -199.625204)
					(mid 180.261604 -199.628924)
					(end 180.265324 -199.637904)
				)
			)
		)
	)
	(zone
		(layer "In1.Cu")
		(hatch none 0.5)
		(connect_pads
			(clearance 0)
		)
		(min_thickness 0.25)
		(keepout
			(tracks not_allowed)
			(vias allowed)
			(pads allowed)
			(copperpour not_allowed)
			(footprints allowed)
		)
		(placement
			(enabled no)
			(sheetname "")
		)
		(fill
			(thermal_gap 0.5)
			(thermal_bridge_width 0.5)
			(island_removal_mode 0)
		)
		(polygon
			(pts
				(arc
					(start 339.118448 -391.822686)
					(mid 339.245448 -391.949686)
					(end 339.372448 -391.822686)
				)
				(arc
					(start 339.372448 -391.746486)
					(mid 339.245448 -391.619486)
					(end 339.118448 -391.746486)
				)
			)
		)
	)
	(zone
		(layer "In1.Cu")
		(hatch none 0.5)
		(connect_pads
			(clearance 0)
		)
		(min_thickness 0.25)
		(keepout
			(tracks not_allowed)
			(vias allowed)
			(pads allowed)
			(copperpour not_allowed)
			(footprints allowed)
		)
		(placement
			(enabled no)
			(sheetname "")
		)
		(fill
			(thermal_gap 0.5)
			(thermal_bridge_width 0.5)
			(island_removal_mode 0)
		)
		(polygon
			(pts
				(arc
					(start 52.633372 -261.332472)
					(mid 52.629652 -261.341452)
					(end 52.620672 -261.345172)
				)
				(arc
					(start 51.147472 -261.345172)
					(mid 51.138492 -261.341452)
					(end 51.134772 -261.332472)
				)
				(arc
					(start 51.134772 -260.837934)
					(mid 51.138492 -260.828954)
					(end 51.147472 -260.825234)
				)
				(arc
					(start 52.620672 -260.825234)
					(mid 52.629652 -260.828954)
					(end 52.633372 -260.837934)
				)
			)
		)
	)
	(zone
		(layer "In1.Cu")
		(hatch none 0.5)
		(connect_pads
			(clearance 0)
		)
		(min_thickness 0.25)
		(keepout
			(tracks not_allowed)
			(vias allowed)
			(pads allowed)
			(copperpour not_allowed)
			(footprints allowed)
		)
		(placement
			(enabled no)
			(sheetname "")
		)
		(fill
			(thermal_gap 0.5)
			(thermal_bridge_width 0.5)
			(island_removal_mode 0)
		)
		(polygon
			(pts
				(arc
					(start 94.38894 -385.31038)
					(mid 94.00794 -385.31038)
					(end 94.38894 -385.31038)
				)
			)
		)
	)
	(zone
		(layer "In1.Cu")
		(hatch none 0.5)
		(connect_pads
			(clearance 0)
		)
		(min_thickness 0.25)
		(keepout
			(tracks not_allowed)
			(vias allowed)
			(pads allowed)
			(copperpour not_allowed)
			(footprints allowed)
		)
		(placement
			(enabled no)
			(sheetname "")
		)
		(fill
			(thermal_gap 0.5)
			(thermal_bridge_width 0.5)
			(island_removal_mode 0)
		)
		(polygon
			(pts
				(arc
					(start 187.809378 -284.282388)
					(mid 187.805658 -284.291368)
					(end 187.796678 -284.295088)
				)
				(arc
					(start 186.323478 -284.295088)
					(mid 186.314498 -284.291368)
					(end 186.310778 -284.282388)
				)
				(arc
					(start 186.310778 -283.78785)
					(mid 186.314498 -283.77887)
					(end 186.323478 -283.77515)
				)
				(arc
					(start 187.796678 -283.77515)
					(mid 187.805658 -283.77887)
					(end 187.809378 -283.78785)
				)
			)
		)
	)
	(zone
		(layer "In1.Cu")
		(hatch none 0.5)
		(connect_pads
			(clearance 0)
		)
		(min_thickness 0.25)
		(keepout
			(tracks not_allowed)
			(vias allowed)
			(pads allowed)
			(copperpour not_allowed)
			(footprints allowed)
		)
		(placement
			(enabled no)
			(sheetname "")
		)
		(fill
			(thermal_gap 0.5)
			(thermal_bridge_width 0.5)
			(island_removal_mode 0)
		)
		(polygon
			(pts
				(arc
					(start 56.077358 -229.882446)
					(mid 56.073638 -229.891426)
					(end 56.064658 -229.895146)
				)
				(arc
					(start 54.591458 -229.895146)
					(mid 54.582478 -229.891426)
					(end 54.578758 -229.882446)
				)
				(arc
					(start 54.578758 -229.387908)
					(mid 54.582478 -229.378928)
					(end 54.591458 -229.375208)
				)
				(arc
					(start 56.064658 -229.375208)
					(mid 56.073638 -229.378928)
					(end 56.077358 -229.387908)
				)
			)
		)
	)
	(zone
		(layer "In1.Cu")
		(hatch none 0.5)
		(connect_pads
			(clearance 0)
		)
		(min_thickness 0.25)
		(keepout
			(tracks not_allowed)
			(vias allowed)
			(pads allowed)
			(copperpour not_allowed)
			(footprints allowed)
		)
		(placement
			(enabled no)
			(sheetname "")
		)
		(fill
			(thermal_gap 0.5)
			(thermal_bridge_width 0.5)
			(island_removal_mode 0)
		)
		(polygon
			(pts
				(arc
					(start 18.357342 -254.532384)
					(mid 18.353622 -254.541364)
					(end 18.344642 -254.545084)
				)
				(arc
					(start 16.871442 -254.545084)
					(mid 16.862462 -254.541364)
					(end 16.858742 -254.532384)
				)
				(arc
					(start 16.858742 -254.037846)
					(mid 16.862462 -254.028866)
					(end 16.871442 -254.025146)
				)
				(arc
					(start 18.344642 -254.025146)
					(mid 18.353622 -254.028866)
					(end 18.357342 -254.037846)
				)
			)
		)
	)
	(zone
		(layer "In1.Cu")
		(hatch none 0.5)
		(connect_pads
			(clearance 0)
		)
		(min_thickness 0.25)
		(keepout
			(tracks not_allowed)
			(vias allowed)
			(pads allowed)
			(copperpour not_allowed)
			(footprints allowed)
		)
		(placement
			(enabled no)
			(sheetname "")
		)
		(fill
			(thermal_gap 0.5)
			(thermal_bridge_width 0.5)
			(island_removal_mode 0)
		)
		(polygon
			(pts
				(arc
					(start 60.177426 -295.332404)
					(mid 60.173706 -295.341384)
					(end 60.164726 -295.345104)
				)
				(arc
					(start 58.691526 -295.345104)
					(mid 58.682546 -295.341384)
					(end 58.678826 -295.332404)
				)
				(arc
					(start 58.678826 -294.837866)
					(mid 58.682546 -294.828886)
					(end 58.691526 -294.825166)
				)
				(arc
					(start 60.164726 -294.825166)
					(mid 60.173706 -294.828886)
					(end 60.177426 -294.837866)
				)
			)
		)
	)
	(zone
		(layer "In1.Cu")
		(hatch none 0.5)
		(connect_pads
			(clearance 0)
		)
		(min_thickness 0.25)
		(keepout
			(tracks not_allowed)
			(vias allowed)
			(pads allowed)
			(copperpour not_allowed)
			(footprints allowed)
		)
		(placement
			(enabled no)
			(sheetname "")
		)
		(fill
			(thermal_gap 0.5)
			(thermal_bridge_width 0.5)
			(island_removal_mode 0)
		)
		(polygon
			(pts
				(arc
					(start 420.661338 -200.132188)
					(mid 420.657618 -200.141168)
					(end 420.648638 -200.144888)
				)
				(arc
					(start 419.175438 -200.144888)
					(mid 419.166458 -200.141168)
					(end 419.162738 -200.132188)
				)
				(arc
					(start 419.162738 -199.63765)
					(mid 419.166458 -199.62867)
					(end 419.175438 -199.62495)
				)
				(arc
					(start 420.648638 -199.62495)
					(mid 420.657618 -199.62867)
					(end 420.661338 -199.63765)
				)
			)
		)
	)
	(zone
		(layer "In1.Cu")
		(hatch none 0.5)
		(connect_pads
			(clearance 0)
		)
		(min_thickness 0.25)
		(keepout
			(tracks not_allowed)
			(vias allowed)
			(pads allowed)
			(copperpour not_allowed)
			(footprints allowed)
		)
		(placement
			(enabled no)
			(sheetname "")
		)
		(fill
			(thermal_gap 0.5)
			(thermal_bridge_width 0.5)
			(island_removal_mode 0)
		)
		(polygon
			(pts
				(arc
					(start 296.473372 -226.482148)
					(mid 296.469652 -226.491128)
					(end 296.460672 -226.494848)
				)
				(arc
					(start 294.987472 -226.494848)
					(mid 294.978492 -226.491128)
					(end 294.974772 -226.482148)
				)
				(arc
					(start 294.974772 -225.98761)
					(mid 294.978492 -225.97863)
					(end 294.987472 -225.97491)
				)
				(arc
					(start 296.460672 -225.97491)
					(mid 296.469652 -225.97863)
					(end 296.473372 -225.98761)
				)
			)
		)
	)
	(zone
		(layer "In1.Cu")
		(hatch none 0.5)
		(connect_pads
			(clearance 0)
		)
		(min_thickness 0.25)
		(keepout
			(tracks not_allowed)
			(vias allowed)
			(pads allowed)
			(copperpour not_allowed)
			(footprints allowed)
		)
		(placement
			(enabled no)
			(sheetname "")
		)
		(fill
			(thermal_gap 0.5)
			(thermal_bridge_width 0.5)
			(island_removal_mode 0)
		)
		(polygon
			(pts
				(arc
					(start 86.098126 -390.761474)
					(mid 85.793326 -390.761474)
					(end 86.098126 -390.761474)
				)
			)
		)
	)
	(zone
		(layer "In1.Cu")
		(hatch none 0.5)
		(connect_pads
			(clearance 0)
		)
		(min_thickness 0.25)
		(keepout
			(tracks not_allowed)
			(vias allowed)
			(pads allowed)
			(copperpour not_allowed)
			(footprints allowed)
		)
		(placement
			(enabled no)
			(sheetname "")
		)
		(fill
			(thermal_gap 0.5)
			(thermal_bridge_width 0.5)
			(island_removal_mode 0)
		)
		(polygon
			(pts
				(arc
					(start 413.117284 -206.082138)
					(mid 413.113564 -206.091118)
					(end 413.104584 -206.094838)
				)
				(arc
					(start 411.631384 -206.094838)
					(mid 411.622404 -206.091118)
					(end 411.618684 -206.082138)
				)
				(arc
					(start 411.618684 -205.5876)
					(mid 411.622404 -205.57862)
					(end 411.631384 -205.5749)
				)
				(arc
					(start 413.104584 -205.5749)
					(mid 413.113564 -205.57862)
					(end 413.117284 -205.5876)
				)
			)
		)
	)
	(zone
		(layer "In1.Cu")
		(hatch none 0.5)
		(connect_pads
			(clearance 0)
		)
		(min_thickness 0.25)
		(keepout
			(tracks not_allowed)
			(vias allowed)
			(pads allowed)
			(copperpour not_allowed)
			(footprints allowed)
		)
		(placement
			(enabled no)
			(sheetname "")
		)
		(fill
			(thermal_gap 0.5)
			(thermal_bridge_width 0.5)
			(island_removal_mode 0)
		)
		(polygon
			(pts
				(arc
					(start 281.385264 -305.532282)
					(mid 281.381544 -305.541262)
					(end 281.372564 -305.544982)
				)
				(arc
					(start 279.899364 -305.544982)
					(mid 279.890384 -305.541262)
					(end 279.886664 -305.532282)
				)
				(arc
					(start 279.886664 -305.037744)
					(mid 279.890384 -305.028764)
					(end 279.899364 -305.025044)
				)
				(arc
					(start 281.372564 -305.025044)
					(mid 281.381544 -305.028764)
					(end 281.385264 -305.037744)
				)
			)
		)
	)
	(zone
		(layer "In1.Cu")
		(hatch none 0.5)
		(connect_pads
			(clearance 0)
		)
		(min_thickness 0.25)
		(keepout
			(tracks not_allowed)
			(vias allowed)
			(pads allowed)
			(copperpour not_allowed)
			(footprints allowed)
		)
		(placement
			(enabled no)
			(sheetname "")
		)
		(fill
			(thermal_gap 0.5)
			(thermal_bridge_width 0.5)
			(island_removal_mode 0)
		)
		(polygon
			(pts
				(arc
					(start 206.5782 -216.035382)
					(mid 205.9178 -216.035382)
					(end 206.5782 -216.035382)
				)
			)
		)
	)
	(zone
		(layer "In1.Cu")
		(hatch none 0.5)
		(connect_pads
			(clearance 0)
		)
		(min_thickness 0.25)
		(keepout
			(tracks not_allowed)
			(vias allowed)
			(pads allowed)
			(copperpour not_allowed)
			(footprints allowed)
		)
		(placement
			(enabled no)
			(sheetname "")
		)
		(fill
			(thermal_gap 0.5)
			(thermal_bridge_width 0.5)
			(island_removal_mode 0)
		)
		(polygon
			(pts
				(arc
					(start 277.941532 -238.382302)
					(mid 277.937812 -238.391282)
					(end 277.928832 -238.395002)
				)
				(arc
					(start 276.455632 -238.395002)
					(mid 276.446652 -238.391282)
					(end 276.442932 -238.382302)
				)
				(arc
					(start 276.442932 -237.887764)
					(mid 276.446652 -237.878784)
					(end 276.455632 -237.875064)
				)
				(arc
					(start 277.928832 -237.875064)
					(mid 277.937812 -237.878784)
					(end 277.941532 -237.887764)
				)
			)
		)
	)
	(zone
		(layer "In1.Cu")
		(hatch none 0.5)
		(connect_pads
			(clearance 0)
		)
		(min_thickness 0.25)
		(keepout
			(tracks not_allowed)
			(vias allowed)
			(pads allowed)
			(copperpour not_allowed)
			(footprints allowed)
		)
		(placement
			(enabled no)
			(sheetname "")
		)
		(fill
			(thermal_gap 0.5)
			(thermal_bridge_width 0.5)
			(island_removal_mode 0)
		)
		(polygon
			(pts
				(arc
					(start 60.177426 -214.582502)
					(mid 60.173706 -214.591482)
					(end 60.164726 -214.595202)
				)
				(arc
					(start 58.691526 -214.595202)
					(mid 58.682546 -214.591482)
					(end 58.678826 -214.582502)
				)
				(arc
					(start 58.678826 -214.087964)
					(mid 58.682546 -214.078984)
					(end 58.691526 -214.075264)
				)
				(arc
					(start 60.164726 -214.075264)
					(mid 60.173706 -214.078984)
					(end 60.177426 -214.087964)
				)
			)
		)
	)
	(zone
		(layer "In1.Cu")
		(hatch none 0.5)
		(connect_pads
			(clearance 0)
		)
		(min_thickness 0.25)
		(keepout
			(tracks not_allowed)
			(vias allowed)
			(pads allowed)
			(copperpour not_allowed)
			(footprints allowed)
		)
		(placement
			(enabled no)
			(sheetname "")
		)
		(fill
			(thermal_gap 0.5)
			(thermal_bridge_width 0.5)
			(island_removal_mode 0)
		)
		(polygon
			(pts
				(arc
					(start 30.001464 -234.982512)
					(mid 29.997744 -234.991492)
					(end 29.988764 -234.995212)
				)
				(arc
					(start 28.515564 -234.995212)
					(mid 28.506584 -234.991492)
					(end 28.502864 -234.982512)
				)
				(arc
					(start 28.502864 -234.487974)
					(mid 28.506584 -234.478994)
					(end 28.515564 -234.475274)
				)
				(arc
					(start 29.988764 -234.475274)
					(mid 29.997744 -234.478994)
					(end 30.001464 -234.487974)
				)
			)
		)
	)
	(zone
		(layer "In1.Cu")
		(hatch none 0.5)
		(connect_pads
			(clearance 0)
		)
		(min_thickness 0.25)
		(keepout
			(tracks not_allowed)
			(vias allowed)
			(pads allowed)
			(copperpour not_allowed)
			(footprints allowed)
		)
		(placement
			(enabled no)
			(sheetname "")
		)
		(fill
			(thermal_gap 0.5)
			(thermal_bridge_width 0.5)
			(island_removal_mode 0)
		)
		(polygon
			(pts
				(arc
					(start 386.891022 -391.822686)
					(mid 387.018022 -391.949686)
					(end 387.145022 -391.822686)
				)
				(arc
					(start 387.145022 -391.746486)
					(mid 387.018022 -391.619486)
					(end 386.891022 -391.746486)
				)
			)
		)
	)
	(zone
		(layer "In1.Cu")
		(hatch none 0.5)
		(connect_pads
			(clearance 0)
		)
		(min_thickness 0.25)
		(keepout
			(tracks not_allowed)
			(vias allowed)
			(pads allowed)
			(copperpour not_allowed)
			(footprints allowed)
		)
		(placement
			(enabled no)
			(sheetname "")
		)
		(fill
			(thermal_gap 0.5)
			(thermal_bridge_width 0.5)
			(island_removal_mode 0)
		)
		(polygon
			(pts
				(arc
					(start 304.017426 -274.93214)
					(mid 304.013706 -274.94112)
					(end 304.004726 -274.94484)
				)
				(arc
					(start 302.531526 -274.94484)
					(mid 302.522546 -274.94112)
					(end 302.518826 -274.93214)
				)
				(arc
					(start 302.518826 -274.437602)
					(mid 302.522546 -274.428622)
					(end 302.531526 -274.424902)
				)
				(arc
					(start 304.004726 -274.424902)
					(mid 304.013706 -274.428622)
					(end 304.017426 -274.437602)
				)
			)
		)
	)
	(zone
		(layer "In1.Cu")
		(hatch none 0.5)
		(connect_pads
			(clearance 0)
		)
		(min_thickness 0.25)
		(keepout
			(tracks not_allowed)
			(vias allowed)
			(pads allowed)
			(copperpour not_allowed)
			(footprints allowed)
		)
		(placement
			(enabled no)
			(sheetname "")
		)
		(fill
			(thermal_gap 0.5)
			(thermal_bridge_width 0.5)
			(island_removal_mode 0)
		)
		(polygon
			(pts
				(arc
					(start 285.485332 -214.582248)
					(mid 285.481612 -214.591228)
					(end 285.472632 -214.594948)
				)
				(arc
					(start 283.999432 -214.594948)
					(mid 283.990452 -214.591228)
					(end 283.986732 -214.582248)
				)
				(arc
					(start 283.986732 -214.08771)
					(mid 283.990452 -214.07873)
					(end 283.999432 -214.07501)
				)
				(arc
					(start 285.472632 -214.07501)
					(mid 285.481612 -214.07873)
					(end 285.485332 -214.08771)
				)
			)
		)
	)
	(zone
		(layer "In1.Cu")
		(hatch none 0.5)
		(connect_pads
			(clearance 0)
		)
		(min_thickness 0.25)
		(keepout
			(tracks not_allowed)
			(vias allowed)
			(pads allowed)
			(copperpour not_allowed)
			(footprints allowed)
		)
		(placement
			(enabled no)
			(sheetname "")
		)
		(fill
			(thermal_gap 0.5)
			(thermal_bridge_width 0.5)
			(island_removal_mode 0)
		)
		(polygon
			(pts
				(arc
					(start 300.57344 -254.53213)
					(mid 300.56972 -254.54111)
					(end 300.56074 -254.54483)
				)
				(arc
					(start 299.08754 -254.54483)
					(mid 299.07856 -254.54111)
					(end 299.07484 -254.53213)
				)
				(arc
					(start 299.07484 -254.037592)
					(mid 299.07856 -254.028612)
					(end 299.08754 -254.024892)
				)
				(arc
					(start 300.56074 -254.024892)
					(mid 300.56972 -254.028612)
					(end 300.57344 -254.037592)
				)
			)
		)
	)
	(zone
		(layer "In1.Cu")
		(hatch none 0.5)
		(connect_pads
			(clearance 0)
		)
		(min_thickness 0.25)
		(keepout
			(tracks not_allowed)
			(vias allowed)
			(pads allowed)
			(copperpour not_allowed)
			(footprints allowed)
		)
		(placement
			(enabled no)
			(sheetname "")
		)
		(fill
			(thermal_gap 0.5)
			(thermal_bridge_width 0.5)
			(island_removal_mode 0)
		)
		(polygon
			(pts
				(arc
					(start 439.849514 -308.082188)
					(mid 439.845794 -308.091168)
					(end 439.836814 -308.094888)
				)
				(arc
					(start 438.363614 -308.094888)
					(mid 438.354634 -308.091168)
					(end 438.350914 -308.082188)
				)
				(arc
					(start 438.350914 -307.58765)
					(mid 438.354634 -307.57867)
					(end 438.363614 -307.57495)
				)
				(arc
					(start 439.836814 -307.57495)
					(mid 439.845794 -307.57867)
					(end 439.849514 -307.58765)
				)
			)
		)
	)
	(zone
		(layer "In1.Cu")
		(hatch none 0.5)
		(connect_pads
			(clearance 0)
		)
		(min_thickness 0.25)
		(keepout
			(tracks not_allowed)
			(vias allowed)
			(pads allowed)
			(copperpour not_allowed)
			(footprints allowed)
		)
		(placement
			(enabled no)
			(sheetname "")
		)
		(fill
			(thermal_gap 0.5)
			(thermal_bridge_width 0.5)
			(island_removal_mode 0)
		)
		(polygon
			(pts
				(arc
					(start 52.633372 -223.932496)
					(mid 52.629652 -223.941476)
					(end 52.620672 -223.945196)
				)
				(arc
					(start 51.147472 -223.945196)
					(mid 51.138492 -223.941476)
					(end 51.134772 -223.932496)
				)
				(arc
					(start 51.134772 -223.437958)
					(mid 51.138492 -223.428978)
					(end 51.147472 -223.425258)
				)
				(arc
					(start 52.620672 -223.425258)
					(mid 52.629652 -223.428978)
					(end 52.633372 -223.437958)
				)
			)
		)
	)
	(zone
		(layer "In1.Cu")
		(hatch none 0.5)
		(connect_pads
			(clearance 0)
		)
		(min_thickness 0.25)
		(keepout
			(tracks not_allowed)
			(vias allowed)
			(pads allowed)
			(copperpour not_allowed)
			(footprints allowed)
		)
		(placement
			(enabled no)
			(sheetname "")
		)
		(fill
			(thermal_gap 0.5)
			(thermal_bridge_width 0.5)
			(island_removal_mode 0)
		)
		(polygon
			(pts
				(arc
					(start 387.361176 -397.156432)
					(mid 386.980176 -397.156432)
					(end 387.361176 -397.156432)
				)
			)
		)
	)
	(zone
		(layer "In1.Cu")
		(hatch none 0.5)
		(connect_pads
			(clearance 0)
		)
		(min_thickness 0.25)
		(keepout
			(tracks not_allowed)
			(vias allowed)
			(pads allowed)
			(copperpour not_allowed)
			(footprints allowed)
		)
		(placement
			(enabled no)
			(sheetname "")
		)
		(fill
			(thermal_gap 0.5)
			(thermal_bridge_width 0.5)
			(island_removal_mode 0)
		)
		(polygon
			(pts
				(arc
					(start 152.288748 -389.467344)
					(mid 151.907748 -389.467344)
					(end 152.288748 -389.467344)
				)
			)
		)
	)
	(zone
		(layer "In1.Cu")
		(hatch none 0.5)
		(connect_pads
			(clearance 0)
		)
		(min_thickness 0.25)
		(keepout
			(tracks not_allowed)
			(vias allowed)
			(pads allowed)
			(copperpour not_allowed)
			(footprints allowed)
		)
		(placement
			(enabled no)
			(sheetname "")
		)
		(fill
			(thermal_gap 0.5)
			(thermal_bridge_width 0.5)
			(island_removal_mode 0)
		)
		(polygon
			(pts
				(arc
					(start 420.661338 -228.18217)
					(mid 420.657618 -228.19115)
					(end 420.648638 -228.19487)
				)
				(arc
					(start 419.175438 -228.19487)
					(mid 419.166458 -228.19115)
					(end 419.162738 -228.18217)
				)
				(arc
					(start 419.162738 -227.687632)
					(mid 419.166458 -227.678652)
					(end 419.175438 -227.674932)
				)
				(arc
					(start 420.648638 -227.674932)
					(mid 420.657618 -227.678652)
					(end 420.661338 -227.687632)
				)
			)
		)
	)
	(zone
		(layer "In1.Cu")
		(hatch none 0.5)
		(connect_pads
			(clearance 0)
		)
		(min_thickness 0.25)
		(keepout
			(tracks not_allowed)
			(vias allowed)
			(pads allowed)
			(copperpour not_allowed)
			(footprints allowed)
		)
		(placement
			(enabled no)
			(sheetname "")
		)
		(fill
			(thermal_gap 0.5)
			(thermal_bridge_width 0.5)
			(island_removal_mode 0)
		)
		(polygon
			(pts
				(arc
					(start 417.018724 -399.701258)
					(mid 417.145724 -399.828258)
					(end 417.272724 -399.701258)
				)
				(arc
					(start 417.272724 -399.625058)
					(mid 417.145724 -399.498058)
					(end 417.018724 -399.625058)
				)
			)
		)
	)
	(zone
		(layer "In1.Cu")
		(hatch none 0.5)
		(connect_pads
			(clearance 0)
		)
		(min_thickness 0.25)
		(keepout
			(tracks not_allowed)
			(vias allowed)
			(pads allowed)
			(copperpour not_allowed)
			(footprints allowed)
		)
		(placement
			(enabled no)
			(sheetname "")
		)
		(fill
			(thermal_gap 0.5)
			(thermal_bridge_width 0.5)
			(island_removal_mode 0)
		)
		(polygon
			(pts
				(arc
					(start 114.961162 -386.003292)
					(mid 114.580162 -386.003292)
					(end 114.961162 -386.003292)
				)
			)
		)
	)
	(zone
		(layer "In1.Cu")
		(hatch none 0.5)
		(connect_pads
			(clearance 0)
		)
		(min_thickness 0.25)
		(keepout
			(tracks not_allowed)
			(vias allowed)
			(pads allowed)
			(copperpour not_allowed)
			(footprints allowed)
		)
		(placement
			(enabled no)
			(sheetname "")
		)
		(fill
			(thermal_gap 0.5)
			(thermal_bridge_width 0.5)
			(island_removal_mode 0)
		)
		(polygon
			(pts
				(arc
					(start 409.81884 -399.701258)
					(mid 409.94584 -399.828258)
					(end 410.07284 -399.701258)
				)
				(arc
					(start 410.07284 -399.625058)
					(mid 409.94584 -399.498058)
					(end 409.81884 -399.625058)
				)
			)
		)
	)
	(zone
		(layer "In1.Cu")
		(hatch none 0.5)
		(connect_pads
			(clearance 0)
		)
		(min_thickness 0.25)
		(keepout
			(tracks not_allowed)
			(vias allowed)
			(pads allowed)
			(copperpour not_allowed)
			(footprints allowed)
		)
		(placement
			(enabled no)
			(sheetname "")
		)
		(fill
			(thermal_gap 0.5)
			(thermal_bridge_width 0.5)
			(island_removal_mode 0)
		)
		(polygon
			(pts
				(arc
					(start 273.841464 -250.282202)
					(mid 273.837744 -250.291182)
					(end 273.828764 -250.294902)
				)
				(arc
					(start 272.355564 -250.294902)
					(mid 272.346584 -250.291182)
					(end 272.342864 -250.282202)
				)
				(arc
					(start 272.342864 -249.787664)
					(mid 272.346584 -249.778684)
					(end 272.355564 -249.774964)
				)
				(arc
					(start 273.828764 -249.774964)
					(mid 273.837744 -249.778684)
					(end 273.841464 -249.787664)
				)
			)
		)
	)
	(zone
		(layer "In1.Cu")
		(hatch none 0.5)
		(connect_pads
			(clearance 0)
		)
		(min_thickness 0.25)
		(keepout
			(tracks not_allowed)
			(vias allowed)
			(pads allowed)
			(copperpour not_allowed)
			(footprints allowed)
		)
		(placement
			(enabled no)
			(sheetname "")
		)
		(fill
			(thermal_gap 0.5)
			(thermal_bridge_width 0.5)
			(island_removal_mode 0)
		)
		(polygon
			(pts
				(arc
					(start 304.017426 -290.232338)
					(mid 304.013706 -290.241318)
					(end 304.004726 -290.245038)
				)
				(arc
					(start 302.531526 -290.245038)
					(mid 302.522546 -290.241318)
					(end 302.518826 -290.232338)
				)
				(arc
					(start 302.518826 -289.7378)
					(mid 302.522546 -289.72882)
					(end 302.531526 -289.7251)
				)
				(arc
					(start 304.004726 -289.7251)
					(mid 304.013706 -289.72882)
					(end 304.017426 -289.7378)
				)
			)
		)
	)
	(zone
		(layer "In1.Cu")
		(hatch none 0.5)
		(connect_pads
			(clearance 0)
		)
		(min_thickness 0.25)
		(keepout
			(tracks not_allowed)
			(vias allowed)
			(pads allowed)
			(copperpour not_allowed)
			(footprints allowed)
		)
		(placement
			(enabled no)
			(sheetname "")
		)
		(fill
			(thermal_gap 0.5)
			(thermal_bridge_width 0.5)
			(island_removal_mode 0)
		)
		(polygon
			(pts
				(arc
					(start 206.5782 -272.135346)
					(mid 205.9178 -272.135346)
					(end 206.5782 -272.135346)
				)
			)
		)
	)
	(zone
		(layer "In1.Cu")
		(hatch none 0.5)
		(connect_pads
			(clearance 0)
		)
		(min_thickness 0.25)
		(keepout
			(tracks not_allowed)
			(vias allowed)
			(pads allowed)
			(copperpour not_allowed)
			(footprints allowed)
		)
		(placement
			(enabled no)
			(sheetname "")
		)
		(fill
			(thermal_gap 0.5)
			(thermal_bridge_width 0.5)
			(island_removal_mode 0)
		)
		(polygon
			(pts
				(arc
					(start 338.497926 -399.143474)
					(mid 338.193126 -399.143474)
					(end 338.497926 -399.143474)
				)
			)
		)
	)
	(zone
		(layer "In1.Cu")
		(hatch none 0.5)
		(connect_pads
			(clearance 0)
		)
		(min_thickness 0.25)
		(keepout
			(tracks not_allowed)
			(vias allowed)
			(pads allowed)
			(copperpour not_allowed)
			(footprints allowed)
		)
		(placement
			(enabled no)
			(sheetname "")
		)
		(fill
			(thermal_gap 0.5)
			(thermal_bridge_width 0.5)
			(island_removal_mode 0)
		)
		(polygon
			(pts
				(arc
					(start 447.393568 -291.082222)
					(mid 447.389848 -291.091202)
					(end 447.380868 -291.094922)
				)
				(arc
					(start 445.907668 -291.094922)
					(mid 445.898688 -291.091202)
					(end 445.894968 -291.082222)
				)
				(arc
					(start 445.894968 -290.587684)
					(mid 445.898688 -290.578704)
					(end 445.907668 -290.574984)
				)
				(arc
					(start 447.380868 -290.574984)
					(mid 447.389848 -290.578704)
					(end 447.393568 -290.587684)
				)
			)
		)
	)
	(zone
		(layer "In1.Cu")
		(hatch none 0.5)
		(connect_pads
			(clearance 0)
		)
		(min_thickness 0.25)
		(keepout
			(tracks not_allowed)
			(vias allowed)
			(pads allowed)
			(copperpour not_allowed)
			(footprints allowed)
		)
		(placement
			(enabled no)
			(sheetname "")
		)
		(fill
			(thermal_gap 0.5)
			(thermal_bridge_width 0.5)
			(island_removal_mode 0)
		)
		(polygon
			(pts
				(arc
					(start 285.485332 -275.782278)
					(mid 285.481612 -275.791258)
					(end 285.472632 -275.794978)
				)
				(arc
					(start 283.999432 -275.794978)
					(mid 283.990452 -275.791258)
					(end 283.986732 -275.782278)
				)
				(arc
					(start 283.986732 -275.28774)
					(mid 283.990452 -275.27876)
					(end 283.999432 -275.27504)
				)
				(arc
					(start 285.472632 -275.27504)
					(mid 285.481612 -275.27876)
					(end 285.485332 -275.28774)
				)
			)
		)
	)
	(zone
		(layer "In1.Cu")
		(hatch none 0.5)
		(connect_pads
			(clearance 0)
		)
		(min_thickness 0.25)
		(keepout
			(tracks not_allowed)
			(vias allowed)
			(pads allowed)
			(copperpour not_allowed)
			(footprints allowed)
		)
		(placement
			(enabled no)
			(sheetname "")
		)
		(fill
			(thermal_gap 0.5)
			(thermal_bridge_width 0.5)
			(island_removal_mode 0)
		)
		(polygon
			(pts
				(arc
					(start 48.533304 -293.632382)
					(mid 48.529584 -293.641362)
					(end 48.520604 -293.645082)
				)
				(arc
					(start 47.047404 -293.645082)
					(mid 47.038424 -293.641362)
					(end 47.034704 -293.632382)
				)
				(arc
					(start 47.034704 -293.137844)
					(mid 47.038424 -293.128864)
					(end 47.047404 -293.125144)
				)
				(arc
					(start 48.520604 -293.125144)
					(mid 48.529584 -293.128864)
					(end 48.533304 -293.137844)
				)
			)
		)
	)
	(zone
		(layer "In1.Cu")
		(hatch none 0.5)
		(connect_pads
			(clearance 0)
		)
		(min_thickness 0.25)
		(keepout
			(tracks not_allowed)
			(vias allowed)
			(pads allowed)
			(copperpour not_allowed)
			(footprints allowed)
		)
		(placement
			(enabled no)
			(sheetname "")
		)
		(fill
			(thermal_gap 0.5)
			(thermal_bridge_width 0.5)
			(island_removal_mode 0)
		)
		(polygon
			(pts
				(arc
					(start 281.385264 -285.982156)
					(mid 281.381544 -285.991136)
					(end 281.372564 -285.994856)
				)
				(arc
					(start 279.899364 -285.994856)
					(mid 279.890384 -285.991136)
					(end 279.886664 -285.982156)
				)
				(arc
					(start 279.886664 -285.487618)
					(mid 279.890384 -285.478638)
					(end 279.899364 -285.474918)
				)
				(arc
					(start 281.372564 -285.474918)
					(mid 281.381544 -285.478638)
					(end 281.385264 -285.487618)
				)
			)
		)
	)
	(zone
		(layer "In1.Cu")
		(hatch none 0.5)
		(connect_pads
			(clearance 0)
		)
		(min_thickness 0.25)
		(keepout
			(tracks not_allowed)
			(vias allowed)
			(pads allowed)
			(copperpour not_allowed)
			(footprints allowed)
		)
		(placement
			(enabled no)
			(sheetname "")
		)
		(fill
			(thermal_gap 0.5)
			(thermal_bridge_width 0.5)
			(island_removal_mode 0)
		)
		(polygon
			(pts
				(arc
					(start 300.57344 -287.682178)
					(mid 300.56972 -287.691158)
					(end 300.56074 -287.694878)
				)
				(arc
					(start 299.08754 -287.694878)
					(mid 299.07856 -287.691158)
					(end 299.07484 -287.682178)
				)
				(arc
					(start 299.07484 -287.18764)
					(mid 299.07856 -287.17866)
					(end 299.08754 -287.17494)
				)
				(arc
					(start 300.56074 -287.17494)
					(mid 300.56972 -287.17866)
					(end 300.57344 -287.18764)
				)
			)
		)
	)
	(zone
		(layer "In1.Cu")
		(hatch none 0.5)
		(connect_pads
			(clearance 0)
		)
		(min_thickness 0.25)
		(keepout
			(tracks not_allowed)
			(vias allowed)
			(pads allowed)
			(copperpour not_allowed)
			(footprints allowed)
		)
		(placement
			(enabled no)
			(sheetname "")
		)
		(fill
			(thermal_gap 0.5)
			(thermal_bridge_width 0.5)
			(island_removal_mode 0)
		)
		(polygon
			(pts
				(arc
					(start 180.265324 -228.182424)
					(mid 180.261604 -228.191404)
					(end 180.252624 -228.195124)
				)
				(arc
					(start 178.779424 -228.195124)
					(mid 178.770444 -228.191404)
					(end 178.766724 -228.182424)
				)
				(arc
					(start 178.766724 -227.687886)
					(mid 178.770444 -227.678906)
					(end 178.779424 -227.675186)
				)
				(arc
					(start 180.252624 -227.675186)
					(mid 180.261604 -227.678906)
					(end 180.265324 -227.687886)
				)
			)
		)
	)
	(zone
		(layer "In1.Cu")
		(hatch none 0.5)
		(connect_pads
			(clearance 0)
		)
		(min_thickness 0.25)
		(keepout
			(tracks not_allowed)
			(vias allowed)
			(pads allowed)
			(copperpour not_allowed)
			(footprints allowed)
		)
		(placement
			(enabled no)
			(sheetname "")
		)
		(fill
			(thermal_gap 0.5)
			(thermal_bridge_width 0.5)
			(island_removal_mode 0)
		)
		(polygon
			(pts
				(arc
					(start 296.473372 -291.932106)
					(mid 296.469652 -291.941086)
					(end 296.460672 -291.944806)
				)
				(arc
					(start 294.987472 -291.944806)
					(mid 294.978492 -291.941086)
					(end 294.974772 -291.932106)
				)
				(arc
					(start 294.974772 -291.437568)
					(mid 294.978492 -291.428588)
					(end 294.987472 -291.424868)
				)
				(arc
					(start 296.460672 -291.424868)
					(mid 296.469652 -291.428588)
					(end 296.473372 -291.437568)
				)
			)
		)
	)
	(zone
		(layer "In1.Cu")
		(hatch none 0.5)
		(connect_pads
			(clearance 0)
		)
		(min_thickness 0.25)
		(keepout
			(tracks not_allowed)
			(vias allowed)
			(pads allowed)
			(copperpour not_allowed)
			(footprints allowed)
		)
		(placement
			(enabled no)
			(sheetname "")
		)
		(fill
			(thermal_gap 0.5)
			(thermal_bridge_width 0.5)
			(island_removal_mode 0)
		)
		(polygon
			(pts
				(arc
					(start 18.357342 -290.232592)
					(mid 18.353622 -290.241572)
					(end 18.344642 -290.245292)
				)
				(arc
					(start 16.871442 -290.245292)
					(mid 16.862462 -290.241572)
					(end 16.858742 -290.232592)
				)
				(arc
					(start 16.858742 -289.738054)
					(mid 16.862462 -289.729074)
					(end 16.871442 -289.725354)
				)
				(arc
					(start 18.344642 -289.725354)
					(mid 18.353622 -289.729074)
					(end 18.357342 -289.738054)
				)
			)
		)
	)
	(zone
		(layer "In1.Cu")
		(hatch none 0.5)
		(connect_pads
			(clearance 0)
		)
		(min_thickness 0.25)
		(keepout
			(tracks not_allowed)
			(vias allowed)
			(pads allowed)
			(copperpour not_allowed)
			(footprints allowed)
		)
		(placement
			(enabled no)
			(sheetname "")
		)
		(fill
			(thermal_gap 0.5)
			(thermal_bridge_width 0.5)
			(island_removal_mode 0)
		)
		(polygon
			(pts
				(arc
					(start 25.901396 -198.43242)
					(mid 25.897676 -198.4414)
					(end 25.888696 -198.44512)
				)
				(arc
					(start 24.415496 -198.44512)
					(mid 24.406516 -198.4414)
					(end 24.402796 -198.43242)
				)
				(arc
					(start 24.402796 -197.937882)
					(mid 24.406516 -197.928902)
					(end 24.415496 -197.925182)
				)
				(arc
					(start 25.888696 -197.925182)
					(mid 25.897676 -197.928902)
					(end 25.901396 -197.937882)
				)
			)
		)
	)
	(zone
		(layer "In1.Cu")
		(hatch none 0.5)
		(connect_pads
			(clearance 0)
		)
		(min_thickness 0.25)
		(keepout
			(tracks not_allowed)
			(vias allowed)
			(pads allowed)
			(copperpour not_allowed)
			(footprints allowed)
		)
		(placement
			(enabled no)
			(sheetname "")
		)
		(fill
			(thermal_gap 0.5)
			(thermal_bridge_width 0.5)
			(island_removal_mode 0)
		)
		(polygon
			(pts
				(arc
					(start 443.2935 -212.032088)
					(mid 443.28978 -212.041068)
					(end 443.2808 -212.044788)
				)
				(arc
					(start 441.8076 -212.044788)
					(mid 441.79862 -212.041068)
					(end 441.7949 -212.032088)
				)
				(arc
					(start 441.7949 -211.53755)
					(mid 441.79862 -211.52857)
					(end 441.8076 -211.52485)
				)
				(arc
					(start 443.2808 -211.52485)
					(mid 443.28978 -211.52857)
					(end 443.2935 -211.53755)
				)
			)
		)
	)
	(zone
		(layer "In1.Cu")
		(hatch none 0.5)
		(connect_pads
			(clearance 0)
		)
		(min_thickness 0.25)
		(keepout
			(tracks not_allowed)
			(vias allowed)
			(pads allowed)
			(copperpour not_allowed)
			(footprints allowed)
		)
		(placement
			(enabled no)
			(sheetname "")
		)
		(fill
			(thermal_gap 0.5)
			(thermal_bridge_width 0.5)
			(island_removal_mode 0)
		)
		(polygon
			(pts
				(arc
					(start 389.241792 -23.50389)
					(mid 389.18791 -23.481572)
					(end 389.165592 -23.42769)
				)
				(arc
					(start 389.165592 -22.153372)
					(mid 389.18791 -22.09949)
					(end 389.241792 -22.077172)
				)
				(arc
					(start 389.750046 -22.077172)
					(mid 389.803928 -22.09949)
					(end 389.826246 -22.153372)
				)
				(arc
					(start 389.826246 -23.42769)
					(mid 389.803928 -23.481572)
					(end 389.750046 -23.50389)
				)
			)
		)
	)
	(zone
		(layer "In1.Cu")
		(hatch none 0.5)
		(connect_pads
			(clearance 0)
		)
		(min_thickness 0.25)
		(keepout
			(tracks not_allowed)
			(vias allowed)
			(pads allowed)
			(copperpour not_allowed)
			(footprints allowed)
		)
		(placement
			(enabled no)
			(sheetname "")
		)
		(fill
			(thermal_gap 0.5)
			(thermal_bridge_width 0.5)
			(island_removal_mode 0)
		)
		(polygon
			(pts
				(arc
					(start 165.177216 -305.532536)
					(mid 165.173496 -305.541516)
					(end 165.164516 -305.545236)
				)
				(arc
					(start 163.691316 -305.545236)
					(mid 163.682336 -305.541516)
					(end 163.678616 -305.532536)
				)
				(arc
					(start 163.678616 -305.037998)
					(mid 163.682336 -305.029018)
					(end 163.691316 -305.025298)
				)
				(arc
					(start 165.164516 -305.025298)
					(mid 165.173496 -305.029018)
					(end 165.177216 -305.037998)
				)
			)
		)
	)
	(zone
		(layer "In1.Cu")
		(hatch none 0.5)
		(connect_pads
			(clearance 0)
		)
		(min_thickness 0.25)
		(keepout
			(tracks not_allowed)
			(vias allowed)
			(pads allowed)
			(copperpour not_allowed)
			(footprints allowed)
		)
		(placement
			(enabled no)
			(sheetname "")
		)
		(fill
			(thermal_gap 0.5)
			(thermal_bridge_width 0.5)
			(island_removal_mode 0)
		)
		(polygon
			(pts
				(arc
					(start 52.261262 -388.774432)
					(mid 51.880262 -388.774432)
					(end 52.261262 -388.774432)
				)
			)
		)
	)
	(zone
		(layer "In1.Cu")
		(hatch none 0.5)
		(connect_pads
			(clearance 0)
		)
		(min_thickness 0.25)
		(keepout
			(tracks not_allowed)
			(vias allowed)
			(pads allowed)
			(copperpour not_allowed)
			(footprints allowed)
		)
		(placement
			(enabled no)
			(sheetname "")
		)
		(fill
			(thermal_gap 0.5)
			(thermal_bridge_width 0.5)
			(island_removal_mode 0)
		)
		(polygon
			(pts
				(arc
					(start 206.9973 -233.28249)
					(mid 206.99358 -233.29147)
					(end 206.9846 -233.29519)
				)
				(arc
					(start 205.5114 -233.29519)
					(mid 205.50242 -233.29147)
					(end 205.4987 -233.28249)
				)
				(arc
					(start 205.4987 -232.787952)
					(mid 205.50242 -232.778972)
					(end 205.5114 -232.775252)
				)
				(arc
					(start 206.9846 -232.775252)
					(mid 206.99358 -232.778972)
					(end 206.9973 -232.787952)
				)
			)
		)
	)
	(zone
		(layer "In1.Cu")
		(hatch none 0.5)
		(connect_pads
			(clearance 0)
		)
		(min_thickness 0.25)
		(keepout
			(tracks not_allowed)
			(vias allowed)
			(pads allowed)
			(copperpour not_allowed)
			(footprints allowed)
		)
		(placement
			(enabled no)
			(sheetname "")
		)
		(fill
			(thermal_gap 0.5)
			(thermal_bridge_width 0.5)
			(island_removal_mode 0)
		)
		(polygon
			(pts
				(arc
					(start 420.661338 -286.832294)
					(mid 420.657618 -286.841274)
					(end 420.648638 -286.844994)
				)
				(arc
					(start 419.175438 -286.844994)
					(mid 419.166458 -286.841274)
					(end 419.162738 -286.832294)
				)
				(arc
					(start 419.162738 -286.337756)
					(mid 419.166458 -286.328776)
					(end 419.175438 -286.325056)
				)
				(arc
					(start 420.648638 -286.325056)
					(mid 420.657618 -286.328776)
					(end 420.661338 -286.337756)
				)
			)
		)
	)
	(zone
		(layer "In1.Cu")
		(hatch none 0.5)
		(connect_pads
			(clearance 0)
		)
		(min_thickness 0.25)
		(keepout
			(tracks not_allowed)
			(vias allowed)
			(pads allowed)
			(copperpour not_allowed)
			(footprints allowed)
		)
		(placement
			(enabled no)
			(sheetname "")
		)
		(fill
			(thermal_gap 0.5)
			(thermal_bridge_width 0.5)
			(island_removal_mode 0)
		)
		(polygon
			(pts
				(arc
					(start 309.86095 -397.849344)
					(mid 309.47995 -397.849344)
					(end 309.86095 -397.849344)
				)
			)
		)
	)
	(zone
		(layer "In1.Cu")
		(hatch none 0.5)
		(connect_pads
			(clearance 0)
		)
		(min_thickness 0.25)
		(keepout
			(tracks not_allowed)
			(vias allowed)
			(pads allowed)
			(copperpour not_allowed)
			(footprints allowed)
		)
		(placement
			(enabled no)
			(sheetname "")
		)
		(fill
			(thermal_gap 0.5)
			(thermal_bridge_width 0.5)
			(island_removal_mode 0)
		)
		(polygon
			(pts
				(arc
					(start 417.888674 -394.385292)
					(mid 417.507674 -394.385292)
					(end 417.888674 -394.385292)
				)
			)
		)
	)
	(zone
		(layer "In1.Cu")
		(hatch none 0.5)
		(connect_pads
			(clearance 0)
		)
		(min_thickness 0.25)
		(keepout
			(tracks not_allowed)
			(vias allowed)
			(pads allowed)
			(copperpour not_allowed)
			(footprints allowed)
		)
		(placement
			(enabled no)
			(sheetname "")
		)
		(fill
			(thermal_gap 0.5)
			(thermal_bridge_width 0.5)
			(island_removal_mode 0)
		)
		(polygon
			(pts
				(arc
					(start 60.177426 -205.232508)
					(mid 60.173706 -205.241488)
					(end 60.164726 -205.245208)
				)
				(arc
					(start 58.691526 -205.245208)
					(mid 58.682546 -205.241488)
					(end 58.678826 -205.232508)
				)
				(arc
					(start 58.678826 -204.73797)
					(mid 58.682546 -204.72899)
					(end 58.691526 -204.72527)
				)
				(arc
					(start 60.164726 -204.72527)
					(mid 60.173706 -204.72899)
					(end 60.177426 -204.73797)
				)
			)
		)
	)
	(zone
		(layer "In1.Cu")
		(hatch none 0.5)
		(connect_pads
			(clearance 0)
		)
		(min_thickness 0.25)
		(keepout
			(tracks not_allowed)
			(vias allowed)
			(pads allowed)
			(copperpour not_allowed)
			(footprints allowed)
		)
		(placement
			(enabled no)
			(sheetname "")
		)
		(fill
			(thermal_gap 0.5)
			(thermal_bridge_width 0.5)
			(island_removal_mode 0)
		)
		(polygon
			(pts
				(arc
					(start 206.9973 -220.532452)
					(mid 206.99358 -220.541432)
					(end 206.9846 -220.545152)
				)
				(arc
					(start 205.5114 -220.545152)
					(mid 205.50242 -220.541432)
					(end 205.4987 -220.532452)
				)
				(arc
					(start 205.4987 -220.037914)
					(mid 205.50242 -220.028934)
					(end 205.5114 -220.025214)
				)
				(arc
					(start 206.9846 -220.025214)
					(mid 206.99358 -220.028934)
					(end 206.9973 -220.037914)
				)
			)
		)
	)
	(zone
		(layer "In1.Cu")
		(hatch none 0.5)
		(connect_pads
			(clearance 0)
		)
		(min_thickness 0.25)
		(keepout
			(tracks not_allowed)
			(vias allowed)
			(pads allowed)
			(copperpour not_allowed)
			(footprints allowed)
		)
		(placement
			(enabled no)
			(sheetname "")
		)
		(fill
			(thermal_gap 0.5)
			(thermal_bridge_width 0.5)
			(island_removal_mode 0)
		)
		(polygon
			(pts
				(arc
					(start 199.4535 -223.932496)
					(mid 199.44978 -223.941476)
					(end 199.4408 -223.945196)
				)
				(arc
					(start 197.9676 -223.945196)
					(mid 197.95862 -223.941476)
					(end 197.9549 -223.932496)
				)
				(arc
					(start 197.9549 -223.437958)
					(mid 197.95862 -223.428978)
					(end 197.9676 -223.425258)
				)
				(arc
					(start 199.4408 -223.425258)
					(mid 199.44978 -223.428978)
					(end 199.4535 -223.437958)
				)
			)
		)
	)
	(zone
		(layer "In1.Cu")
		(hatch none 0.5)
		(connect_pads
			(clearance 0)
		)
		(min_thickness 0.25)
		(keepout
			(tracks not_allowed)
			(vias allowed)
			(pads allowed)
			(copperpour not_allowed)
			(footprints allowed)
		)
		(placement
			(enabled no)
			(sheetname "")
		)
		(fill
			(thermal_gap 0.5)
			(thermal_bridge_width 0.5)
			(island_removal_mode 0)
		)
		(polygon
			(pts
				(arc
					(start 176.821338 -309.782464)
					(mid 176.817618 -309.791444)
					(end 176.808638 -309.795164)
				)
				(arc
					(start 175.335438 -309.795164)
					(mid 175.326458 -309.791444)
					(end 175.322738 -309.782464)
				)
				(arc
					(start 175.322738 -309.287926)
					(mid 175.326458 -309.278946)
					(end 175.335438 -309.275226)
				)
				(arc
					(start 176.808638 -309.275226)
					(mid 176.817618 -309.278946)
					(end 176.821338 -309.287926)
				)
			)
		)
	)
	(zone
		(layer "In1.Cu")
		(hatch none 0.5)
		(connect_pads
			(clearance 0)
		)
		(min_thickness 0.25)
		(keepout
			(tracks not_allowed)
			(vias allowed)
			(pads allowed)
			(copperpour not_allowed)
			(footprints allowed)
		)
		(placement
			(enabled no)
			(sheetname "")
		)
		(fill
			(thermal_gap 0.5)
			(thermal_bridge_width 0.5)
			(island_removal_mode 0)
		)
		(polygon
			(pts
				(arc
					(start 159.488886 -389.467344)
					(mid 159.107886 -389.467344)
					(end 159.488886 -389.467344)
				)
			)
		)
	)
	(zone
		(layer "In1.Cu")
		(hatch none 0.5)
		(connect_pads
			(clearance 0)
		)
		(min_thickness 0.25)
		(keepout
			(tracks not_allowed)
			(vias allowed)
			(pads allowed)
			(copperpour not_allowed)
			(footprints allowed)
		)
		(placement
			(enabled no)
			(sheetname "")
		)
		(fill
			(thermal_gap 0.5)
			(thermal_bridge_width 0.5)
			(island_removal_mode 0)
		)
		(polygon
			(pts
				(arc
					(start 413.117284 -230.73233)
					(mid 413.113564 -230.74131)
					(end 413.104584 -230.74503)
				)
				(arc
					(start 411.631384 -230.74503)
					(mid 411.622404 -230.74131)
					(end 411.618684 -230.73233)
				)
				(arc
					(start 411.618684 -230.237792)
					(mid 411.622404 -230.228812)
					(end 411.631384 -230.225092)
				)
				(arc
					(start 413.104584 -230.225092)
					(mid 413.113564 -230.228812)
					(end 413.117284 -230.237792)
				)
			)
		)
	)
	(zone
		(layer "In1.Cu")
		(hatch none 0.5)
		(connect_pads
			(clearance 0)
		)
		(min_thickness 0.25)
		(keepout
			(tracks not_allowed)
			(vias allowed)
			(pads allowed)
			(copperpour not_allowed)
			(footprints allowed)
		)
		(placement
			(enabled no)
			(sheetname "")
		)
		(fill
			(thermal_gap 0.5)
			(thermal_bridge_width 0.5)
			(island_removal_mode 0)
		)
		(polygon
			(pts
				(arc
					(start 60.177426 -251.13234)
					(mid 60.173706 -251.14132)
					(end 60.164726 -251.14504)
				)
				(arc
					(start 58.691526 -251.14504)
					(mid 58.682546 -251.14132)
					(end 58.678826 -251.13234)
				)
				(arc
					(start 58.678826 -250.637802)
					(mid 58.682546 -250.628822)
					(end 58.691526 -250.625102)
				)
				(arc
					(start 60.164726 -250.625102)
					(mid 60.173706 -250.628822)
					(end 60.177426 -250.637802)
				)
			)
		)
	)
	(zone
		(layer "In1.Cu")
		(hatch none 0.5)
		(connect_pads
			(clearance 0)
		)
		(min_thickness 0.25)
		(keepout
			(tracks not_allowed)
			(vias allowed)
			(pads allowed)
			(copperpour not_allowed)
			(footprints allowed)
		)
		(placement
			(enabled no)
			(sheetname "")
		)
		(fill
			(thermal_gap 0.5)
			(thermal_bridge_width 0.5)
			(island_removal_mode 0)
		)
		(polygon
			(pts
				(arc
					(start 454.937368 -252.832108)
					(mid 454.933648 -252.841088)
					(end 454.924668 -252.844808)
				)
				(arc
					(start 453.451468 -252.844808)
					(mid 453.442488 -252.841088)
					(end 453.438768 -252.832108)
				)
				(arc
					(start 453.438768 -252.33757)
					(mid 453.442488 -252.32859)
					(end 453.451468 -252.32487)
				)
				(arc
					(start 454.924668 -252.32487)
					(mid 454.933648 -252.32859)
					(end 454.937368 -252.33757)
				)
			)
		)
	)
	(zone
		(layer "In1.Cu")
		(hatch none 0.5)
		(connect_pads
			(clearance 0)
		)
		(min_thickness 0.25)
		(keepout
			(tracks not_allowed)
			(vias allowed)
			(pads allowed)
			(copperpour not_allowed)
			(footprints allowed)
		)
		(placement
			(enabled no)
			(sheetname "")
		)
		(fill
			(thermal_gap 0.5)
			(thermal_bridge_width 0.5)
			(island_removal_mode 0)
		)
		(polygon
			(pts
				(arc
					(start 30.001464 -278.332438)
					(mid 29.997744 -278.341418)
					(end 29.988764 -278.345138)
				)
				(arc
					(start 28.515564 -278.345138)
					(mid 28.506584 -278.341418)
					(end 28.502864 -278.332438)
				)
				(arc
					(start 28.502864 -277.8379)
					(mid 28.506584 -277.82892)
					(end 28.515564 -277.8252)
				)
				(arc
					(start 29.988764 -277.8252)
					(mid 29.997744 -277.82892)
					(end 30.001464 -277.8379)
				)
			)
		)
	)
	(zone
		(layer "In1.Cu")
		(hatch none 0.5)
		(connect_pads
			(clearance 0)
		)
		(min_thickness 0.25)
		(keepout
			(tracks not_allowed)
			(vias allowed)
			(pads allowed)
			(copperpour not_allowed)
			(footprints allowed)
		)
		(placement
			(enabled no)
			(sheetname "")
		)
		(fill
			(thermal_gap 0.5)
			(thermal_bridge_width 0.5)
			(island_removal_mode 0)
		)
		(polygon
			(pts
				(arc
					(start 300.57344 -216.28227)
					(mid 300.56972 -216.29125)
					(end 300.56074 -216.29497)
				)
				(arc
					(start 299.08754 -216.29497)
					(mid 299.07856 -216.29125)
					(end 299.07484 -216.28227)
				)
				(arc
					(start 299.07484 -215.787732)
					(mid 299.07856 -215.778752)
					(end 299.08754 -215.775032)
				)
				(arc
					(start 300.56074 -215.775032)
					(mid 300.56972 -215.778752)
					(end 300.57344 -215.787732)
				)
			)
		)
	)
	(zone
		(layer "In1.Cu")
		(hatch none 0.5)
		(connect_pads
			(clearance 0)
		)
		(min_thickness 0.25)
		(keepout
			(tracks not_allowed)
			(vias allowed)
			(pads allowed)
			(copperpour not_allowed)
			(footprints allowed)
		)
		(placement
			(enabled no)
			(sheetname "")
		)
		(fill
			(thermal_gap 0.5)
			(thermal_bridge_width 0.5)
			(island_removal_mode 0)
		)
		(polygon
			(pts
				(arc
					(start 428.205392 -248.58218)
					(mid 428.201672 -248.59116)
					(end 428.192692 -248.59488)
				)
				(arc
					(start 426.719492 -248.59488)
					(mid 426.710512 -248.59116)
					(end 426.706792 -248.58218)
				)
				(arc
					(start 426.706792 -248.087642)
					(mid 426.710512 -248.078662)
					(end 426.719492 -248.074942)
				)
				(arc
					(start 428.192692 -248.074942)
					(mid 428.201672 -248.078662)
					(end 428.205392 -248.087642)
				)
			)
		)
	)
	(zone
		(layer "In1.Cu")
		(hatch none 0.5)
		(connect_pads
			(clearance 0)
		)
		(min_thickness 0.25)
		(keepout
			(tracks not_allowed)
			(vias allowed)
			(pads allowed)
			(copperpour not_allowed)
			(footprints allowed)
		)
		(placement
			(enabled no)
			(sheetname "")
		)
		(fill
			(thermal_gap 0.5)
			(thermal_bridge_width 0.5)
			(island_removal_mode 0)
		)
		(polygon
			(pts
				(arc
					(start 165.177216 -221.382336)
					(mid 165.173496 -221.391316)
					(end 165.164516 -221.395036)
				)
				(arc
					(start 163.691316 -221.395036)
					(mid 163.682336 -221.391316)
					(end 163.678616 -221.382336)
				)
				(arc
					(start 163.678616 -220.887798)
					(mid 163.682336 -220.878818)
					(end 163.691316 -220.875098)
				)
				(arc
					(start 165.164516 -220.875098)
					(mid 165.173496 -220.878818)
					(end 165.177216 -220.887798)
				)
			)
		)
	)
	(zone
		(layer "In1.Cu")
		(hatch none 0.5)
		(connect_pads
			(clearance 0)
		)
		(min_thickness 0.25)
		(keepout
			(tracks not_allowed)
			(vias allowed)
			(pads allowed)
			(copperpour not_allowed)
			(footprints allowed)
		)
		(placement
			(enabled no)
			(sheetname "")
		)
		(fill
			(thermal_gap 0.5)
			(thermal_bridge_width 0.5)
			(island_removal_mode 0)
		)
		(polygon
			(pts
				(arc
					(start 156.79801 -390.761474)
					(mid 156.49321 -390.761474)
					(end 156.79801 -390.761474)
				)
			)
		)
	)
	(zone
		(layer "In1.Cu")
		(hatch none 0.5)
		(connect_pads
			(clearance 0)
		)
		(min_thickness 0.25)
		(keepout
			(tracks not_allowed)
			(vias allowed)
			(pads allowed)
			(copperpour not_allowed)
			(footprints allowed)
		)
		(placement
			(enabled no)
			(sheetname "")
		)
		(fill
			(thermal_gap 0.5)
			(thermal_bridge_width 0.5)
			(island_removal_mode 0)
		)
		(polygon
			(pts
				(arc
					(start 288.929318 -296.182288)
					(mid 288.925598 -296.191268)
					(end 288.916618 -296.194988)
				)
				(arc
					(start 287.443418 -296.194988)
					(mid 287.434438 -296.191268)
					(end 287.430718 -296.182288)
				)
				(arc
					(start 287.430718 -295.68775)
					(mid 287.434438 -295.67877)
					(end 287.443418 -295.67505)
				)
				(arc
					(start 288.916618 -295.67505)
					(mid 288.925598 -295.67877)
					(end 288.929318 -295.68775)
				)
			)
		)
	)
	(zone
		(layer "In1.Cu")
		(hatch none 0.5)
		(connect_pads
			(clearance 0)
		)
		(min_thickness 0.25)
		(keepout
			(tracks not_allowed)
			(vias allowed)
			(pads allowed)
			(copperpour not_allowed)
			(footprints allowed)
		)
		(placement
			(enabled no)
			(sheetname "")
		)
		(fill
			(thermal_gap 0.5)
			(thermal_bridge_width 0.5)
			(island_removal_mode 0)
		)
		(polygon
			(pts
				(arc
					(start 147.48891 -389.467344)
					(mid 147.10791 -389.467344)
					(end 147.48891 -389.467344)
				)
			)
		)
	)
	(zone
		(layer "In1.Cu")
		(hatch none 0.5)
		(connect_pads
			(clearance 0)
		)
		(min_thickness 0.25)
		(keepout
			(tracks not_allowed)
			(vias allowed)
			(pads allowed)
			(copperpour not_allowed)
			(footprints allowed)
		)
		(placement
			(enabled no)
			(sheetname "")
		)
		(fill
			(thermal_gap 0.5)
			(thermal_bridge_width 0.5)
			(island_removal_mode 0)
		)
		(polygon
			(pts
				(arc
					(start 308.117494 -234.982258)
					(mid 308.113774 -234.991238)
					(end 308.104794 -234.994958)
				)
				(arc
					(start 306.631594 -234.994958)
					(mid 306.622614 -234.991238)
					(end 306.618894 -234.982258)
				)
				(arc
					(start 306.618894 -234.48772)
					(mid 306.622614 -234.47874)
					(end 306.631594 -234.47502)
				)
				(arc
					(start 308.104794 -234.47502)
					(mid 308.113774 -234.47874)
					(end 308.117494 -234.48772)
				)
			)
		)
	)
	(zone
		(layer "In1.Cu")
		(hatch none 0.5)
		(connect_pads
			(clearance 0)
		)
		(min_thickness 0.25)
		(keepout
			(tracks not_allowed)
			(vias allowed)
			(pads allowed)
			(copperpour not_allowed)
			(footprints allowed)
		)
		(placement
			(enabled no)
			(sheetname "")
		)
		(fill
			(thermal_gap 0.5)
			(thermal_bridge_width 0.5)
			(island_removal_mode 0)
		)
		(polygon
			(pts
				(arc
					(start 293.029386 -251.132086)
					(mid 293.025666 -251.141066)
					(end 293.016686 -251.144786)
				)
				(arc
					(start 291.543486 -251.144786)
					(mid 291.534506 -251.141066)
					(end 291.530786 -251.132086)
				)
				(arc
					(start 291.530786 -250.637548)
					(mid 291.534506 -250.628568)
					(end 291.543486 -250.624848)
				)
				(arc
					(start 293.016686 -250.624848)
					(mid 293.025666 -250.628568)
					(end 293.029386 -250.637548)
				)
			)
		)
	)
	(zone
		(layer "In1.Cu")
		(hatch none 0.5)
		(connect_pads
			(clearance 0)
		)
		(min_thickness 0.25)
		(keepout
			(tracks not_allowed)
			(vias allowed)
			(pads allowed)
			(copperpour not_allowed)
			(footprints allowed)
		)
		(placement
			(enabled no)
			(sheetname "")
		)
		(fill
			(thermal_gap 0.5)
			(thermal_bridge_width 0.5)
			(island_removal_mode 0)
		)
		(polygon
			(pts
				(arc
					(start 318.26073 -397.849344)
					(mid 317.87973 -397.849344)
					(end 318.26073 -397.849344)
				)
			)
		)
	)
	(zone
		(layer "In1.Cu")
		(hatch none 0.5)
		(connect_pads
			(clearance 0)
		)
		(min_thickness 0.25)
		(keepout
			(tracks not_allowed)
			(vias allowed)
			(pads allowed)
			(copperpour not_allowed)
			(footprints allowed)
		)
		(placement
			(enabled no)
			(sheetname "")
		)
		(fill
			(thermal_gap 0.5)
			(thermal_bridge_width 0.5)
			(island_removal_mode 0)
		)
		(polygon
			(pts
				(arc
					(start 33.445196 -230.732584)
					(mid 33.441476 -230.741564)
					(end 33.432496 -230.745284)
				)
				(arc
					(start 31.959296 -230.745284)
					(mid 31.950316 -230.741564)
					(end 31.946596 -230.732584)
				)
				(arc
					(start 31.946596 -230.238046)
					(mid 31.950316 -230.229066)
					(end 31.959296 -230.225346)
				)
				(arc
					(start 33.432496 -230.225346)
					(mid 33.441476 -230.229066)
					(end 33.445196 -230.238046)
				)
			)
		)
	)
	(zone
		(layer "In1.Cu")
		(hatch none 0.5)
		(connect_pads
			(clearance 0)
		)
		(min_thickness 0.25)
		(keepout
			(tracks not_allowed)
			(vias allowed)
			(pads allowed)
			(copperpour not_allowed)
			(footprints allowed)
		)
		(placement
			(enabled no)
			(sheetname "")
		)
		(fill
			(thermal_gap 0.5)
			(thermal_bridge_width 0.5)
			(island_removal_mode 0)
		)
		(polygon
			(pts
				(arc
					(start 58.990992 -383.440686)
					(mid 59.117992 -383.567686)
					(end 59.244992 -383.440686)
				)
				(arc
					(start 59.244992 -383.364486)
					(mid 59.117992 -383.237486)
					(end 58.990992 -383.364486)
				)
			)
		)
	)
	(zone
		(layer "In1.Cu")
		(hatch none 0.5)
		(connect_pads
			(clearance 0)
		)
		(min_thickness 0.25)
		(keepout
			(tracks not_allowed)
			(vias allowed)
			(pads allowed)
			(copperpour not_allowed)
			(footprints allowed)
		)
		(placement
			(enabled no)
			(sheetname "")
		)
		(fill
			(thermal_gap 0.5)
			(thermal_bridge_width 0.5)
			(island_removal_mode 0)
		)
		(polygon
			(pts
				(arc
					(start 63.791084 -391.319258)
					(mid 63.918084 -391.446258)
					(end 64.045084 -391.319258)
				)
				(arc
					(start 64.045084 -391.243058)
					(mid 63.918084 -391.116058)
					(end 63.791084 -391.243058)
				)
			)
		)
	)
	(zone
		(layer "In1.Cu")
		(hatch none 0.5)
		(connect_pads
			(clearance 0)
		)
		(min_thickness 0.25)
		(keepout
			(tracks not_allowed)
			(vias allowed)
			(pads allowed)
			(copperpour not_allowed)
			(footprints allowed)
		)
		(placement
			(enabled no)
			(sheetname "")
		)
		(fill
			(thermal_gap 0.5)
			(thermal_bridge_width 0.5)
			(island_removal_mode 0)
		)
		(polygon
			(pts
				(arc
					(start 428.205392 -301.2821)
					(mid 428.201672 -301.29108)
					(end 428.192692 -301.2948)
				)
				(arc
					(start 426.719492 -301.2948)
					(mid 426.710512 -301.29108)
					(end 426.706792 -301.2821)
				)
				(arc
					(start 426.706792 -300.787562)
					(mid 426.710512 -300.778582)
					(end 426.719492 -300.774862)
				)
				(arc
					(start 428.192692 -300.774862)
					(mid 428.201672 -300.778582)
					(end 428.205392 -300.787562)
				)
			)
		)
	)
	(zone
		(layer "In1.Cu")
		(hatch none 0.5)
		(connect_pads
			(clearance 0)
		)
		(min_thickness 0.25)
		(keepout
			(tracks not_allowed)
			(vias allowed)
			(pads allowed)
			(copperpour not_allowed)
			(footprints allowed)
		)
		(placement
			(enabled no)
			(sheetname "")
		)
		(fill
			(thermal_gap 0.5)
			(thermal_bridge_width 0.5)
			(island_removal_mode 0)
		)
		(polygon
			(pts
				(arc
					(start 266.29741 -280.88209)
					(mid 266.29369 -280.89107)
					(end 266.28471 -280.89479)
				)
				(arc
					(start 264.81151 -280.89479)
					(mid 264.80253 -280.89107)
					(end 264.79881 -280.88209)
				)
				(arc
					(start 264.79881 -280.387552)
					(mid 264.80253 -280.378572)
					(end 264.81151 -280.374852)
				)
				(arc
					(start 266.28471 -280.374852)
					(mid 266.29369 -280.378572)
					(end 266.29741 -280.387552)
				)
			)
		)
	)
	(zone
		(layer "In1.Cu")
		(hatch none 0.5)
		(connect_pads
			(clearance 0)
		)
		(min_thickness 0.25)
		(keepout
			(tracks not_allowed)
			(vias allowed)
			(pads allowed)
			(copperpour not_allowed)
			(footprints allowed)
		)
		(placement
			(enabled no)
			(sheetname "")
		)
		(fill
			(thermal_gap 0.5)
			(thermal_bridge_width 0.5)
			(island_removal_mode 0)
		)
		(polygon
			(pts
				(arc
					(start 293.029386 -278.332184)
					(mid 293.025666 -278.341164)
					(end 293.016686 -278.344884)
				)
				(arc
					(start 291.543486 -278.344884)
					(mid 291.534506 -278.341164)
					(end 291.530786 -278.332184)
				)
				(arc
					(start 291.530786 -277.837646)
					(mid 291.534506 -277.828666)
					(end 291.543486 -277.824946)
				)
				(arc
					(start 293.016686 -277.824946)
					(mid 293.025666 -277.828666)
					(end 293.029386 -277.837646)
				)
			)
		)
	)
	(zone
		(layer "In1.Cu")
		(hatch none 0.5)
		(connect_pads
			(clearance 0)
		)
		(min_thickness 0.25)
		(keepout
			(tracks not_allowed)
			(vias allowed)
			(pads allowed)
			(copperpour not_allowed)
			(footprints allowed)
		)
		(placement
			(enabled no)
			(sheetname "")
		)
		(fill
			(thermal_gap 0.5)
			(thermal_bridge_width 0.5)
			(island_removal_mode 0)
		)
		(polygon
			(pts
				(arc
					(start 151.418798 -383.440686)
					(mid 151.545798 -383.567686)
					(end 151.672798 -383.440686)
				)
				(arc
					(start 151.672798 -383.364486)
					(mid 151.545798 -383.237486)
					(end 151.418798 -383.364486)
				)
			)
		)
	)
	(zone
		(layer "In1.Cu")
		(hatch none 0.5)
		(connect_pads
			(clearance 0)
		)
		(min_thickness 0.25)
		(keepout
			(tracks not_allowed)
			(vias allowed)
			(pads allowed)
			(copperpour not_allowed)
			(footprints allowed)
		)
		(placement
			(enabled no)
			(sheetname "")
		)
		(fill
			(thermal_gap 0.5)
			(thermal_bridge_width 0.5)
			(island_removal_mode 0)
		)
		(polygon
			(pts
				(arc
					(start 37.545264 -223.932496)
					(mid 37.541544 -223.941476)
					(end 37.532564 -223.945196)
				)
				(arc
					(start 36.059364 -223.945196)
					(mid 36.050384 -223.941476)
					(end 36.046664 -223.932496)
				)
				(arc
					(start 36.046664 -223.437958)
					(mid 36.050384 -223.428978)
					(end 36.059364 -223.425258)
				)
				(arc
					(start 37.532564 -223.425258)
					(mid 37.541544 -223.428978)
					(end 37.545264 -223.437958)
				)
			)
		)
	)
	(zone
		(layer "In1.Cu")
		(hatch none 0.5)
		(connect_pads
			(clearance 0)
		)
		(min_thickness 0.25)
		(keepout
			(tracks not_allowed)
			(vias allowed)
			(pads allowed)
			(copperpour not_allowed)
			(footprints allowed)
		)
		(placement
			(enabled no)
			(sheetname "")
		)
		(fill
			(thermal_gap 0.5)
			(thermal_bridge_width 0.5)
			(island_removal_mode 0)
		)
		(polygon
			(pts
				(arc
					(start 130.27025 -390.761474)
					(mid 129.96545 -390.761474)
					(end 130.27025 -390.761474)
				)
			)
		)
	)
	(zone
		(layer "In1.Cu")
		(hatch none 0.5)
		(connect_pads
			(clearance 0)
		)
		(min_thickness 0.25)
		(keepout
			(tracks not_allowed)
			(vias allowed)
			(pads allowed)
			(copperpour not_allowed)
			(footprints allowed)
		)
		(placement
			(enabled no)
			(sheetname "")
		)
		(fill
			(thermal_gap 0.5)
			(thermal_bridge_width 0.5)
			(island_removal_mode 0)
		)
		(polygon
			(pts
				(arc
					(start 25.901396 -314.032392)
					(mid 25.897676 -314.041372)
					(end 25.888696 -314.045092)
				)
				(arc
					(start 24.415496 -314.045092)
					(mid 24.406516 -314.041372)
					(end 24.402796 -314.032392)
				)
				(arc
					(start 24.402796 -313.537854)
					(mid 24.406516 -313.528874)
					(end 24.415496 -313.525154)
				)
				(arc
					(start 25.888696 -313.525154)
					(mid 25.897676 -313.528874)
					(end 25.901396 -313.537854)
				)
			)
		)
	)
	(zone
		(layer "In1.Cu")
		(hatch none 0.5)
		(connect_pads
			(clearance 0)
		)
		(min_thickness 0.25)
		(keepout
			(tracks not_allowed)
			(vias allowed)
			(pads allowed)
			(copperpour not_allowed)
			(footprints allowed)
		)
		(placement
			(enabled no)
			(sheetname "")
		)
		(fill
			(thermal_gap 0.5)
			(thermal_bridge_width 0.5)
			(island_removal_mode 0)
		)
		(polygon
			(pts
				(arc
					(start 58.37047 -390.761474)
					(mid 58.06567 -390.761474)
					(end 58.37047 -390.761474)
				)
			)
		)
	)
	(zone
		(layer "In1.Cu")
		(hatch none 0.5)
		(connect_pads
			(clearance 0)
		)
		(min_thickness 0.25)
		(keepout
			(tracks not_allowed)
			(vias allowed)
			(pads allowed)
			(copperpour not_allowed)
			(footprints allowed)
		)
		(placement
			(enabled no)
			(sheetname "")
		)
		(fill
			(thermal_gap 0.5)
			(thermal_bridge_width 0.5)
			(island_removal_mode 0)
		)
		(polygon
			(pts
				(arc
					(start 293.029386 -214.582248)
					(mid 293.025666 -214.591228)
					(end 293.016686 -214.594948)
				)
				(arc
					(start 291.543486 -214.594948)
					(mid 291.534506 -214.591228)
					(end 291.530786 -214.582248)
				)
				(arc
					(start 291.530786 -214.08771)
					(mid 291.534506 -214.07873)
					(end 291.543486 -214.07501)
				)
				(arc
					(start 293.016686 -214.07501)
					(mid 293.025666 -214.07873)
					(end 293.029386 -214.08771)
				)
			)
		)
	)
	(zone
		(layer "In1.Cu")
		(hatch none 0.5)
		(connect_pads
			(clearance 0)
		)
		(min_thickness 0.25)
		(keepout
			(tracks not_allowed)
			(vias allowed)
			(pads allowed)
			(copperpour not_allowed)
			(footprints allowed)
		)
		(placement
			(enabled no)
			(sheetname "")
		)
		(fill
			(thermal_gap 0.5)
			(thermal_bridge_width 0.5)
			(island_removal_mode 0)
		)
		(polygon
			(pts
				(arc
					(start 352.318574 -399.701258)
					(mid 352.445574 -399.828258)
					(end 352.572574 -399.701258)
				)
				(arc
					(start 352.572574 -399.625058)
					(mid 352.445574 -399.498058)
					(end 352.318574 -399.625058)
				)
			)
		)
	)
	(zone
		(layer "In1.Cu")
		(hatch none 0.5)
		(connect_pads
			(clearance 0)
		)
		(min_thickness 0.25)
		(keepout
			(tracks not_allowed)
			(vias allowed)
			(pads allowed)
			(copperpour not_allowed)
			(footprints allowed)
		)
		(placement
			(enabled no)
			(sheetname "")
		)
		(fill
			(thermal_gap 0.5)
			(thermal_bridge_width 0.5)
			(island_removal_mode 0)
		)
		(polygon
			(pts
				(arc
					(start 270.397478 -238.382302)
					(mid 270.393758 -238.391282)
					(end 270.384778 -238.395002)
				)
				(arc
					(start 268.911578 -238.395002)
					(mid 268.902598 -238.391282)
					(end 268.898878 -238.382302)
				)
				(arc
					(start 268.898878 -237.887764)
					(mid 268.902598 -237.878784)
					(end 268.911578 -237.875064)
				)
				(arc
					(start 270.384778 -237.875064)
					(mid 270.393758 -237.878784)
					(end 270.397478 -237.887764)
				)
			)
		)
	)
	(zone
		(layer "In1.Cu")
		(hatch none 0.5)
		(connect_pads
			(clearance 0)
		)
		(min_thickness 0.25)
		(keepout
			(tracks not_allowed)
			(vias allowed)
			(pads allowed)
			(copperpour not_allowed)
			(footprints allowed)
		)
		(placement
			(enabled no)
			(sheetname "")
		)
		(fill
			(thermal_gap 0.5)
			(thermal_bridge_width 0.5)
			(island_removal_mode 0)
		)
		(polygon
			(pts
				(arc
					(start 407.088848 -394.385292)
					(mid 406.707848 -394.385292)
					(end 407.088848 -394.385292)
				)
			)
		)
	)
	(zone
		(layer "In1.Cu")
		(hatch none 0.5)
		(connect_pads
			(clearance 0)
		)
		(min_thickness 0.25)
		(keepout
			(tracks not_allowed)
			(vias allowed)
			(pads allowed)
			(copperpour not_allowed)
			(footprints allowed)
		)
		(placement
			(enabled no)
			(sheetname "")
		)
		(fill
			(thermal_gap 0.5)
			(thermal_bridge_width 0.5)
			(island_removal_mode 0)
		)
		(polygon
			(pts
				(arc
					(start 344.78849 -394.385292)
					(mid 344.40749 -394.385292)
					(end 344.78849 -394.385292)
				)
			)
		)
	)
	(zone
		(layer "In1.Cu")
		(hatch none 0.5)
		(connect_pads
			(clearance 0)
		)
		(min_thickness 0.25)
		(keepout
			(tracks not_allowed)
			(vias allowed)
			(pads allowed)
			(copperpour not_allowed)
			(footprints allowed)
		)
		(placement
			(enabled no)
			(sheetname "")
		)
		(fill
			(thermal_gap 0.5)
			(thermal_bridge_width 0.5)
			(island_removal_mode 0)
		)
		(polygon
			(pts
				(arc
					(start 315.860938 -397.849344)
					(mid 315.479938 -397.849344)
					(end 315.860938 -397.849344)
				)
			)
		)
	)
	(zone
		(layer "In1.Cu")
		(hatch none 0.5)
		(connect_pads
			(clearance 0)
		)
		(min_thickness 0.25)
		(keepout
			(tracks not_allowed)
			(vias allowed)
			(pads allowed)
			(copperpour not_allowed)
			(footprints allowed)
		)
		(placement
			(enabled no)
			(sheetname "")
		)
		(fill
			(thermal_gap 0.5)
			(thermal_bridge_width 0.5)
			(island_removal_mode 0)
		)
		(polygon
			(pts
				(arc
					(start 373.070374 -392.30427)
					(mid 372.765574 -392.30427)
					(end 373.070374 -392.30427)
				)
			)
		)
	)
	(zone
		(layer "In1.Cu")
		(hatch none 0.5)
		(connect_pads
			(clearance 0)
		)
		(min_thickness 0.25)
		(keepout
			(tracks not_allowed)
			(vias allowed)
			(pads allowed)
			(copperpour not_allowed)
			(footprints allowed)
		)
		(placement
			(enabled no)
			(sheetname "")
		)
		(fill
			(thermal_gap 0.5)
			(thermal_bridge_width 0.5)
			(island_removal_mode 0)
		)
		(polygon
			(pts
				(arc
					(start 172.72127 -237.532418)
					(mid 172.71755 -237.541398)
					(end 172.70857 -237.545118)
				)
				(arc
					(start 171.23537 -237.545118)
					(mid 171.22639 -237.541398)
					(end 171.22267 -237.532418)
				)
				(arc
					(start 171.22267 -237.03788)
					(mid 171.22639 -237.0289)
					(end 171.23537 -237.02518)
				)
				(arc
					(start 172.70857 -237.02518)
					(mid 172.71755 -237.0289)
					(end 172.72127 -237.03788)
				)
			)
		)
	)
	(zone
		(layer "In1.Cu")
		(hatch none 0.5)
		(connect_pads
			(clearance 0)
		)
		(min_thickness 0.25)
		(keepout
			(tracks not_allowed)
			(vias allowed)
			(pads allowed)
			(copperpour not_allowed)
			(footprints allowed)
		)
		(placement
			(enabled no)
			(sheetname "")
		)
		(fill
			(thermal_gap 0.5)
			(thermal_bridge_width 0.5)
			(island_removal_mode 0)
		)
		(polygon
			(pts
				(arc
					(start 417.888674 -397.849344)
					(mid 417.507674 -397.849344)
					(end 417.888674 -397.849344)
				)
			)
		)
	)
	(zone
		(layer "In1.Cu")
		(hatch none 0.5)
		(connect_pads
			(clearance 0)
		)
		(min_thickness 0.25)
		(keepout
			(tracks not_allowed)
			(vias allowed)
			(pads allowed)
			(copperpour not_allowed)
			(footprints allowed)
		)
		(placement
			(enabled no)
			(sheetname "")
		)
		(fill
			(thermal_gap 0.5)
			(thermal_bridge_width 0.5)
			(island_removal_mode 0)
		)
		(polygon
			(pts
				(arc
					(start 447.393568 -263.03224)
					(mid 447.389848 -263.04122)
					(end 447.380868 -263.04494)
				)
				(arc
					(start 445.907668 -263.04494)
					(mid 445.898688 -263.04122)
					(end 445.894968 -263.03224)
				)
				(arc
					(start 445.894968 -262.537702)
					(mid 445.898688 -262.528722)
					(end 445.907668 -262.525002)
				)
				(arc
					(start 447.380868 -262.525002)
					(mid 447.389848 -262.528722)
					(end 447.393568 -262.537702)
				)
			)
		)
	)
	(zone
		(layer "In1.Cu")
		(hatch none 0.5)
		(connect_pads
			(clearance 0)
		)
		(min_thickness 0.25)
		(keepout
			(tracks not_allowed)
			(vias allowed)
			(pads allowed)
			(copperpour not_allowed)
			(footprints allowed)
		)
		(placement
			(enabled no)
			(sheetname "")
		)
		(fill
			(thermal_gap 0.5)
			(thermal_bridge_width 0.5)
			(island_removal_mode 0)
		)
		(polygon
			(pts
				(arc
					(start 60.177426 -216.282524)
					(mid 60.173706 -216.291504)
					(end 60.164726 -216.295224)
				)
				(arc
					(start 58.691526 -216.295224)
					(mid 58.682546 -216.291504)
					(end 58.678826 -216.282524)
				)
				(arc
					(start 58.678826 -215.787986)
					(mid 58.682546 -215.779006)
					(end 58.691526 -215.775286)
				)
				(arc
					(start 60.164726 -215.775286)
					(mid 60.173706 -215.779006)
					(end 60.177426 -215.787986)
				)
			)
		)
	)
	(zone
		(layer "In1.Cu")
		(hatch none 0.5)
		(connect_pads
			(clearance 0)
		)
		(min_thickness 0.25)
		(keepout
			(tracks not_allowed)
			(vias allowed)
			(pads allowed)
			(copperpour not_allowed)
			(footprints allowed)
		)
		(placement
			(enabled no)
			(sheetname "")
		)
		(fill
			(thermal_gap 0.5)
			(thermal_bridge_width 0.5)
			(island_removal_mode 0)
		)
		(polygon
			(pts
				(arc
					(start 40.98925 -280.882344)
					(mid 40.98553 -280.891324)
					(end 40.97655 -280.895044)
				)
				(arc
					(start 39.50335 -280.895044)
					(mid 39.49437 -280.891324)
					(end 39.49065 -280.882344)
				)
				(arc
					(start 39.49065 -280.387806)
					(mid 39.49437 -280.378826)
					(end 39.50335 -280.375106)
				)
				(arc
					(start 40.97655 -280.375106)
					(mid 40.98553 -280.378826)
					(end 40.98925 -280.387806)
				)
			)
		)
	)
	(zone
		(layer "In1.Cu")
		(hatch none 0.5)
		(connect_pads
			(clearance 0)
		)
		(min_thickness 0.25)
		(keepout
			(tracks not_allowed)
			(vias allowed)
			(pads allowed)
			(copperpour not_allowed)
			(footprints allowed)
		)
		(placement
			(enabled no)
			(sheetname "")
		)
		(fill
			(thermal_gap 0.5)
			(thermal_bridge_width 0.5)
			(island_removal_mode 0)
		)
		(polygon
			(pts
				(arc
					(start 277.941532 -281.732228)
					(mid 277.937812 -281.741208)
					(end 277.928832 -281.744928)
				)
				(arc
					(start 276.455632 -281.744928)
					(mid 276.446652 -281.741208)
					(end 276.442932 -281.732228)
				)
				(arc
					(start 276.442932 -281.23769)
					(mid 276.446652 -281.22871)
					(end 276.455632 -281.22499)
				)
				(arc
					(start 277.928832 -281.22499)
					(mid 277.937812 -281.22871)
					(end 277.941532 -281.23769)
				)
			)
		)
	)
	(zone
		(layer "In1.Cu")
		(hatch none 0.5)
		(connect_pads
			(clearance 0)
		)
		(min_thickness 0.25)
		(keepout
			(tracks not_allowed)
			(vias allowed)
			(pads allowed)
			(copperpour not_allowed)
			(footprints allowed)
		)
		(placement
			(enabled no)
			(sheetname "")
		)
		(fill
			(thermal_gap 0.5)
			(thermal_bridge_width 0.5)
			(island_removal_mode 0)
		)
		(polygon
			(pts
				(arc
					(start 381.760984 -394.385292)
					(mid 381.379984 -394.385292)
					(end 381.760984 -394.385292)
				)
			)
		)
	)
	(zone
		(layer "In1.Cu")
		(hatch none 0.5)
		(connect_pads
			(clearance 0)
		)
		(min_thickness 0.25)
		(keepout
			(tracks not_allowed)
			(vias allowed)
			(pads allowed)
			(copperpour not_allowed)
			(footprints allowed)
		)
		(placement
			(enabled no)
			(sheetname "")
		)
		(fill
			(thermal_gap 0.5)
			(thermal_bridge_width 0.5)
			(island_removal_mode 0)
		)
		(polygon
			(pts
				(arc
					(start 420.661338 -293.632128)
					(mid 420.657618 -293.641108)
					(end 420.648638 -293.644828)
				)
				(arc
					(start 419.175438 -293.644828)
					(mid 419.166458 -293.641108)
					(end 419.162738 -293.632128)
				)
				(arc
					(start 419.162738 -293.13759)
					(mid 419.166458 -293.12861)
					(end 419.175438 -293.12489)
				)
				(arc
					(start 420.648638 -293.12489)
					(mid 420.657618 -293.12861)
					(end 420.661338 -293.13759)
				)
			)
		)
	)
	(zone
		(layer "In1.Cu")
		(hatch none 0.5)
		(connect_pads
			(clearance 0)
		)
		(min_thickness 0.25)
		(keepout
			(tracks not_allowed)
			(vias allowed)
			(pads allowed)
			(copperpour not_allowed)
			(footprints allowed)
		)
		(placement
			(enabled no)
			(sheetname "")
		)
		(fill
			(thermal_gap 0.5)
			(thermal_bridge_width 0.5)
			(island_removal_mode 0)
		)
		(polygon
			(pts
				(arc
					(start 407.418794 -399.701258)
					(mid 407.545794 -399.828258)
					(end 407.672794 -399.701258)
				)
				(arc
					(start 407.672794 -399.625058)
					(mid 407.545794 -399.498058)
					(end 407.418794 -399.625058)
				)
			)
		)
	)
	(zone
		(layer "In1.Cu")
		(hatch none 0.5)
		(connect_pads
			(clearance 0)
		)
		(min_thickness 0.25)
		(keepout
			(tracks not_allowed)
			(vias allowed)
			(pads allowed)
			(copperpour not_allowed)
			(footprints allowed)
		)
		(placement
			(enabled no)
			(sheetname "")
		)
		(fill
			(thermal_gap 0.5)
			(thermal_bridge_width 0.5)
			(island_removal_mode 0)
		)
		(polygon
			(pts
				(arc
					(start 265.87831 -198.185024)
					(mid 265.21791 -198.185024)
					(end 265.87831 -198.185024)
				)
			)
		)
	)
	(zone
		(layer "In1.Cu")
		(hatch none 0.5)
		(connect_pads
			(clearance 0)
		)
		(min_thickness 0.25)
		(keepout
			(tracks not_allowed)
			(vias allowed)
			(pads allowed)
			(copperpour not_allowed)
			(footprints allowed)
		)
		(placement
			(enabled no)
			(sheetname "")
		)
		(fill
			(thermal_gap 0.5)
			(thermal_bridge_width 0.5)
			(island_removal_mode 0)
		)
		(polygon
			(pts
				(arc
					(start 424.761406 -313.182254)
					(mid 424.757686 -313.191234)
					(end 424.748706 -313.194954)
				)
				(arc
					(start 423.275506 -313.194954)
					(mid 423.266526 -313.191234)
					(end 423.262806 -313.182254)
				)
				(arc
					(start 423.262806 -312.687716)
					(mid 423.266526 -312.678736)
					(end 423.275506 -312.675016)
				)
				(arc
					(start 424.748706 -312.675016)
					(mid 424.757686 -312.678736)
					(end 424.761406 -312.687716)
				)
			)
		)
	)
	(zone
		(layer "In1.Cu")
		(hatch none 0.5)
		(connect_pads
			(clearance 0)
		)
		(min_thickness 0.25)
		(keepout
			(tracks not_allowed)
			(vias allowed)
			(pads allowed)
			(copperpour not_allowed)
			(footprints allowed)
		)
		(placement
			(enabled no)
			(sheetname "")
		)
		(fill
			(thermal_gap 0.5)
			(thermal_bridge_width 0.5)
			(island_removal_mode 0)
		)
		(polygon
			(pts
				(arc
					(start 53.570378 -390.761474)
					(mid 53.265578 -390.761474)
					(end 53.570378 -390.761474)
				)
			)
		)
	)
	(zone
		(layer "In1.Cu")
		(hatch none 0.5)
		(connect_pads
			(clearance 0)
		)
		(min_thickness 0.25)
		(keepout
			(tracks not_allowed)
			(vias allowed)
			(pads allowed)
			(copperpour not_allowed)
			(footprints allowed)
		)
		(placement
			(enabled no)
			(sheetname "")
		)
		(fill
			(thermal_gap 0.5)
			(thermal_bridge_width 0.5)
			(island_removal_mode 0)
		)
		(polygon
			(pts
				(arc
					(start 435.749446 -277.4823)
					(mid 435.745726 -277.49128)
					(end 435.736746 -277.495)
				)
				(arc
					(start 434.263546 -277.495)
					(mid 434.254566 -277.49128)
					(end 434.250846 -277.4823)
				)
				(arc
					(start 434.250846 -276.987762)
					(mid 434.254566 -276.978782)
					(end 434.263546 -276.975062)
				)
				(arc
					(start 435.736746 -276.975062)
					(mid 435.745726 -276.978782)
					(end 435.749446 -276.987762)
				)
			)
		)
	)
	(zone
		(layer "In1.Cu")
		(hatch none 0.5)
		(connect_pads
			(clearance 0)
		)
		(min_thickness 0.25)
		(keepout
			(tracks not_allowed)
			(vias allowed)
			(pads allowed)
			(copperpour not_allowed)
			(footprints allowed)
		)
		(placement
			(enabled no)
			(sheetname "")
		)
		(fill
			(thermal_gap 0.5)
			(thermal_bridge_width 0.5)
			(island_removal_mode 0)
		)
		(polygon
			(pts
				(arc
					(start 293.029386 -246.032274)
					(mid 293.025666 -246.041254)
					(end 293.016686 -246.044974)
				)
				(arc
					(start 291.543486 -246.044974)
					(mid 291.534506 -246.041254)
					(end 291.530786 -246.032274)
				)
				(arc
					(start 291.530786 -245.537736)
					(mid 291.534506 -245.528756)
					(end 291.543486 -245.525036)
				)
				(arc
					(start 293.016686 -245.525036)
					(mid 293.025666 -245.528756)
					(end 293.029386 -245.537736)
				)
			)
		)
	)
	(zone
		(layer "In1.Cu")
		(hatch none 0.5)
		(connect_pads
			(clearance 0)
		)
		(min_thickness 0.25)
		(keepout
			(tracks not_allowed)
			(vias allowed)
			(pads allowed)
			(copperpour not_allowed)
			(footprints allowed)
		)
		(placement
			(enabled no)
			(sheetname "")
		)
		(fill
			(thermal_gap 0.5)
			(thermal_bridge_width 0.5)
			(island_removal_mode 0)
		)
		(polygon
			(pts
				(arc
					(start 318.590676 -391.822686)
					(mid 318.717676 -391.949686)
					(end 318.844676 -391.822686)
				)
				(arc
					(start 318.844676 -391.746486)
					(mid 318.717676 -391.619486)
					(end 318.590676 -391.746486)
				)
			)
		)
	)
	(zone
		(layer "In1.Cu")
		(hatch none 0.5)
		(connect_pads
			(clearance 0)
		)
		(min_thickness 0.25)
		(keepout
			(tracks not_allowed)
			(vias allowed)
			(pads allowed)
			(copperpour not_allowed)
			(footprints allowed)
		)
		(placement
			(enabled no)
			(sheetname "")
		)
		(fill
			(thermal_gap 0.5)
			(thermal_bridge_width 0.5)
			(island_removal_mode 0)
		)
		(polygon
			(pts
				(arc
					(start 307.460904 -397.849344)
					(mid 307.079904 -397.849344)
					(end 307.460904 -397.849344)
				)
			)
		)
	)
	(zone
		(layer "In1.Cu")
		(hatch none 0.5)
		(connect_pads
			(clearance 0)
		)
		(min_thickness 0.25)
		(keepout
			(tracks not_allowed)
			(vias allowed)
			(pads allowed)
			(copperpour not_allowed)
			(footprints allowed)
		)
		(placement
			(enabled no)
			(sheetname "")
		)
		(fill
			(thermal_gap 0.5)
			(thermal_bridge_width 0.5)
			(island_removal_mode 0)
		)
		(polygon
			(pts
				(arc
					(start 123.690888 -391.319258)
					(mid 123.817888 -391.446258)
					(end 123.944888 -391.319258)
				)
				(arc
					(start 123.944888 -391.243058)
					(mid 123.817888 -391.116058)
					(end 123.690888 -391.243058)
				)
			)
		)
	)
	(zone
		(layer "In1.Cu")
		(hatch none 0.5)
		(connect_pads
			(clearance 0)
		)
		(min_thickness 0.25)
		(keepout
			(tracks not_allowed)
			(vias allowed)
			(pads allowed)
			(copperpour not_allowed)
			(footprints allowed)
		)
		(placement
			(enabled no)
			(sheetname "")
		)
		(fill
			(thermal_gap 0.5)
			(thermal_bridge_width 0.5)
			(island_removal_mode 0)
		)
		(polygon
			(pts
				(arc
					(start 321.860926 -397.849344)
					(mid 321.479926 -397.849344)
					(end 321.860926 -397.849344)
				)
			)
		)
	)
	(zone
		(layer "In1.Cu")
		(hatch none 0.5)
		(connect_pads
			(clearance 0)
		)
		(min_thickness 0.25)
		(keepout
			(tracks not_allowed)
			(vias allowed)
			(pads allowed)
			(copperpour not_allowed)
			(footprints allowed)
		)
		(placement
			(enabled no)
			(sheetname "")
		)
		(fill
			(thermal_gap 0.5)
			(thermal_bridge_width 0.5)
			(island_removal_mode 0)
		)
		(polygon
			(pts
				(arc
					(start 56.261 -389.467344)
					(mid 55.88 -389.467344)
					(end 56.261 -389.467344)
				)
			)
		)
	)
	(zone
		(layer "In1.Cu")
		(hatch none 0.5)
		(connect_pads
			(clearance 0)
		)
		(min_thickness 0.25)
		(keepout
			(tracks not_allowed)
			(vias allowed)
			(pads allowed)
			(copperpour not_allowed)
			(footprints allowed)
		)
		(placement
			(enabled no)
			(sheetname "")
		)
		(fill
			(thermal_gap 0.5)
			(thermal_bridge_width 0.5)
			(island_removal_mode 0)
		)
		(polygon
			(pts
				(arc
					(start 57.791096 -391.319258)
					(mid 57.918096 -391.446258)
					(end 58.045096 -391.319258)
				)
				(arc
					(start 58.045096 -391.243058)
					(mid 57.918096 -391.116058)
					(end 57.791096 -391.243058)
				)
			)
		)
	)
	(zone
		(layer "In1.Cu")
		(hatch none 0.5)
		(connect_pads
			(clearance 0)
		)
		(min_thickness 0.25)
		(keepout
			(tracks not_allowed)
			(vias allowed)
			(pads allowed)
			(copperpour not_allowed)
			(footprints allowed)
		)
		(placement
			(enabled no)
			(sheetname "")
		)
		(fill
			(thermal_gap 0.5)
			(thermal_bridge_width 0.5)
			(island_removal_mode 0)
		)
		(polygon
			(pts
				(arc
					(start 187.809378 -251.982478)
					(mid 187.805658 -251.991458)
					(end 187.796678 -251.995178)
				)
				(arc
					(start 186.323478 -251.995178)
					(mid 186.314498 -251.991458)
					(end 186.310778 -251.982478)
				)
				(arc
					(start 186.310778 -251.48794)
					(mid 186.314498 -251.47896)
					(end 186.323478 -251.47524)
				)
				(arc
					(start 187.796678 -251.47524)
					(mid 187.805658 -251.47896)
					(end 187.809378 -251.48794)
				)
			)
		)
	)
	(zone
		(layer "In1.Cu")
		(hatch none 0.5)
		(connect_pads
			(clearance 0)
		)
		(min_thickness 0.25)
		(keepout
			(tracks not_allowed)
			(vias allowed)
			(pads allowed)
			(copperpour not_allowed)
			(footprints allowed)
		)
		(placement
			(enabled no)
			(sheetname "")
		)
		(fill
			(thermal_gap 0.5)
			(thermal_bridge_width 0.5)
			(island_removal_mode 0)
		)
		(polygon
			(pts
				(arc
					(start 386.16128 -397.156432)
					(mid 385.78028 -397.156432)
					(end 386.16128 -397.156432)
				)
			)
		)
	)
	(zone
		(layer "In1.Cu")
		(hatch none 0.5)
		(connect_pads
			(clearance 0)
		)
		(min_thickness 0.25)
		(keepout
			(tracks not_allowed)
			(vias allowed)
			(pads allowed)
			(copperpour not_allowed)
			(footprints allowed)
		)
		(placement
			(enabled no)
			(sheetname "")
		)
		(fill
			(thermal_gap 0.5)
			(thermal_bridge_width 0.5)
			(island_removal_mode 0)
		)
		(polygon
			(pts
				(arc
					(start 129.36093 -386.003292)
					(mid 128.97993 -386.003292)
					(end 129.36093 -386.003292)
				)
			)
		)
	)
	(zone
		(layer "In1.Cu")
		(hatch none 0.5)
		(connect_pads
			(clearance 0)
		)
		(min_thickness 0.25)
		(keepout
			(tracks not_allowed)
			(vias allowed)
			(pads allowed)
			(copperpour not_allowed)
			(footprints allowed)
		)
		(placement
			(enabled no)
			(sheetname "")
		)
		(fill
			(thermal_gap 0.5)
			(thermal_bridge_width 0.5)
			(island_removal_mode 0)
		)
		(polygon
			(pts
				(arc
					(start 176.821338 -231.582468)
					(mid 176.817618 -231.591448)
					(end 176.808638 -231.595168)
				)
				(arc
					(start 175.335438 -231.595168)
					(mid 175.326458 -231.591448)
					(end 175.322738 -231.582468)
				)
				(arc
					(start 175.322738 -231.08793)
					(mid 175.326458 -231.07895)
					(end 175.335438 -231.07523)
				)
				(arc
					(start 176.808638 -231.07523)
					(mid 176.817618 -231.07895)
					(end 176.821338 -231.08793)
				)
			)
		)
	)
	(zone
		(layer "In1.Cu")
		(hatch none 0.5)
		(connect_pads
			(clearance 0)
		)
		(min_thickness 0.25)
		(keepout
			(tracks not_allowed)
			(vias allowed)
			(pads allowed)
			(copperpour not_allowed)
			(footprints allowed)
		)
		(placement
			(enabled no)
			(sheetname "")
		)
		(fill
			(thermal_gap 0.5)
			(thermal_bridge_width 0.5)
			(island_removal_mode 0)
		)
		(polygon
			(pts
				(arc
					(start 184.365392 -208.632552)
					(mid 184.361672 -208.641532)
					(end 184.352692 -208.645252)
				)
				(arc
					(start 182.879492 -208.645252)
					(mid 182.870512 -208.641532)
					(end 182.866792 -208.632552)
				)
				(arc
					(start 182.866792 -208.138014)
					(mid 182.870512 -208.129034)
					(end 182.879492 -208.125314)
				)
				(arc
					(start 184.352692 -208.125314)
					(mid 184.361672 -208.129034)
					(end 184.365392 -208.138014)
				)
			)
		)
	)
	(zone
		(layer "In1.Cu")
		(hatch none 0.5)
		(connect_pads
			(clearance 0)
		)
		(min_thickness 0.25)
		(keepout
			(tracks not_allowed)
			(vias allowed)
			(pads allowed)
			(copperpour not_allowed)
			(footprints allowed)
		)
		(placement
			(enabled no)
			(sheetname "")
		)
		(fill
			(thermal_gap 0.5)
			(thermal_bridge_width 0.5)
			(island_removal_mode 0)
		)
		(polygon
			(pts
				(arc
					(start 288.929318 -200.132188)
					(mid 288.925598 -200.141168)
					(end 288.916618 -200.144888)
				)
				(arc
					(start 287.443418 -200.144888)
					(mid 287.434438 -200.141168)
					(end 287.430718 -200.132188)
				)
				(arc
					(start 287.430718 -199.63765)
					(mid 287.434438 -199.62867)
					(end 287.443418 -199.62495)
				)
				(arc
					(start 288.916618 -199.62495)
					(mid 288.925598 -199.62867)
					(end 288.929318 -199.63765)
				)
			)
		)
	)
	(zone
		(layer "In1.Cu")
		(hatch none 0.5)
		(connect_pads
			(clearance 0)
		)
		(min_thickness 0.25)
		(keepout
			(tracks not_allowed)
			(vias allowed)
			(pads allowed)
			(copperpour not_allowed)
			(footprints allowed)
		)
		(placement
			(enabled no)
			(sheetname "")
		)
		(fill
			(thermal_gap 0.5)
			(thermal_bridge_width 0.5)
			(island_removal_mode 0)
		)
		(polygon
			(pts
				(arc
					(start 293.029386 -266.432284)
					(mid 293.025666 -266.441264)
					(end 293.016686 -266.444984)
				)
				(arc
					(start 291.543486 -266.444984)
					(mid 291.534506 -266.441264)
					(end 291.530786 -266.432284)
				)
				(arc
					(start 291.530786 -265.937746)
					(mid 291.534506 -265.928766)
					(end 291.543486 -265.925046)
				)
				(arc
					(start 293.016686 -265.925046)
					(mid 293.025666 -265.928766)
					(end 293.029386 -265.937746)
				)
			)
		)
	)
	(zone
		(layer "In1.Cu")
		(hatch none 0.5)
		(connect_pads
			(clearance 0)
		)
		(min_thickness 0.25)
		(keepout
			(tracks not_allowed)
			(vias allowed)
			(pads allowed)
			(copperpour not_allowed)
			(footprints allowed)
		)
		(placement
			(enabled no)
			(sheetname "")
		)
		(fill
			(thermal_gap 0.5)
			(thermal_bridge_width 0.5)
			(island_removal_mode 0)
		)
		(polygon
			(pts
				(arc
					(start 304.190654 -391.822686)
					(mid 304.317654 -391.949686)
					(end 304.444654 -391.822686)
				)
				(arc
					(start 304.444654 -391.746486)
					(mid 304.317654 -391.619486)
					(end 304.190654 -391.746486)
				)
			)
		)
	)
	(zone
		(layer "In1.Cu")
		(hatch none 0.5)
		(connect_pads
			(clearance 0)
		)
		(min_thickness 0.25)
		(keepout
			(tracks not_allowed)
			(vias allowed)
			(pads allowed)
			(copperpour not_allowed)
			(footprints allowed)
		)
		(placement
			(enabled no)
			(sheetname "")
		)
		(fill
			(thermal_gap 0.5)
			(thermal_bridge_width 0.5)
			(island_removal_mode 0)
		)
		(polygon
			(pts
				(arc
					(start 80.71866 -383.440686)
					(mid 80.84566 -383.567686)
					(end 80.97266 -383.440686)
				)
				(arc
					(start 80.97266 -383.364486)
					(mid 80.84566 -383.237486)
					(end 80.71866 -383.364486)
				)
			)
		)
	)
	(zone
		(layer "In1.Cu")
		(hatch none 0.5)
		(connect_pads
			(clearance 0)
		)
		(min_thickness 0.25)
		(keepout
			(tracks not_allowed)
			(vias allowed)
			(pads allowed)
			(copperpour not_allowed)
			(footprints allowed)
		)
		(placement
			(enabled no)
			(sheetname "")
		)
		(fill
			(thermal_gap 0.5)
			(thermal_bridge_width 0.5)
			(island_removal_mode 0)
		)
		(polygon
			(pts
				(arc
					(start 296.473372 -241.782092)
					(mid 296.469652 -241.791072)
					(end 296.460672 -241.794792)
				)
				(arc
					(start 294.987472 -241.794792)
					(mid 294.978492 -241.791072)
					(end 294.974772 -241.782092)
				)
				(arc
					(start 294.974772 -241.287554)
					(mid 294.978492 -241.278574)
					(end 294.987472 -241.274854)
				)
				(arc
					(start 296.460672 -241.274854)
					(mid 296.469652 -241.278574)
					(end 296.473372 -241.287554)
				)
			)
		)
	)
	(zone
		(layer "In1.Cu")
		(hatch none 0.5)
		(connect_pads
			(clearance 0)
		)
		(min_thickness 0.25)
		(keepout
			(tracks not_allowed)
			(vias allowed)
			(pads allowed)
			(copperpour not_allowed)
			(footprints allowed)
		)
		(placement
			(enabled no)
			(sheetname "")
		)
		(fill
			(thermal_gap 0.5)
			(thermal_bridge_width 0.5)
			(island_removal_mode 0)
		)
		(polygon
			(pts
				(arc
					(start 180.265324 -226.482402)
					(mid 180.261604 -226.491382)
					(end 180.252624 -226.495102)
				)
				(arc
					(start 178.779424 -226.495102)
					(mid 178.770444 -226.491382)
					(end 178.766724 -226.482402)
				)
				(arc
					(start 178.766724 -225.987864)
					(mid 178.770444 -225.978884)
					(end 178.779424 -225.975164)
				)
				(arc
					(start 180.252624 -225.975164)
					(mid 180.261604 -225.978884)
					(end 180.265324 -225.987864)
				)
			)
		)
	)
	(zone
		(layer "In1.Cu")
		(hatch none 0.5)
		(connect_pads
			(clearance 0)
		)
		(min_thickness 0.25)
		(keepout
			(tracks not_allowed)
			(vias allowed)
			(pads allowed)
			(copperpour not_allowed)
			(footprints allowed)
		)
		(placement
			(enabled no)
			(sheetname "")
		)
		(fill
			(thermal_gap 0.5)
			(thermal_bridge_width 0.5)
			(island_removal_mode 0)
		)
		(polygon
			(pts
				(arc
					(start 51.461162 -389.467344)
					(mid 51.080162 -389.467344)
					(end 51.461162 -389.467344)
				)
			)
		)
	)
	(zone
		(layer "In1.Cu")
		(hatch none 0.5)
		(connect_pads
			(clearance 0)
		)
		(min_thickness 0.25)
		(keepout
			(tracks not_allowed)
			(vias allowed)
			(pads allowed)
			(copperpour not_allowed)
			(footprints allowed)
		)
		(placement
			(enabled no)
			(sheetname "")
		)
		(fill
			(thermal_gap 0.5)
			(thermal_bridge_width 0.5)
			(island_removal_mode 0)
		)
		(polygon
			(pts
				(arc
					(start 285.485332 -278.332184)
					(mid 285.481612 -278.341164)
					(end 285.472632 -278.344884)
				)
				(arc
					(start 283.999432 -278.344884)
					(mid 283.990452 -278.341164)
					(end 283.986732 -278.332184)
				)
				(arc
					(start 283.986732 -277.837646)
					(mid 283.990452 -277.828666)
					(end 283.999432 -277.824946)
				)
				(arc
					(start 285.472632 -277.824946)
					(mid 285.481612 -277.828666)
					(end 285.485332 -277.837646)
				)
			)
		)
	)
	(zone
		(layer "In1.Cu")
		(hatch none 0.5)
		(connect_pads
			(clearance 0)
		)
		(min_thickness 0.25)
		(keepout
			(tracks not_allowed)
			(vias allowed)
			(pads allowed)
			(copperpour not_allowed)
			(footprints allowed)
		)
		(placement
			(enabled no)
			(sheetname "")
		)
		(fill
			(thermal_gap 0.5)
			(thermal_bridge_width 0.5)
			(island_removal_mode 0)
		)
		(polygon
			(pts
				(arc
					(start 417.217352 -261.332218)
					(mid 417.213632 -261.341198)
					(end 417.204652 -261.344918)
				)
				(arc
					(start 415.731452 -261.344918)
					(mid 415.722472 -261.341198)
					(end 415.718752 -261.332218)
				)
				(arc
					(start 415.718752 -260.83768)
					(mid 415.722472 -260.8287)
					(end 415.731452 -260.82498)
				)
				(arc
					(start 417.204652 -260.82498)
					(mid 417.213632 -260.8287)
					(end 417.217352 -260.83768)
				)
			)
		)
	)
	(zone
		(layer "In1.Cu")
		(hatch none 0.5)
		(connect_pads
			(clearance 0)
		)
		(min_thickness 0.25)
		(keepout
			(tracks not_allowed)
			(vias allowed)
			(pads allowed)
			(copperpour not_allowed)
			(footprints allowed)
		)
		(placement
			(enabled no)
			(sheetname "")
		)
		(fill
			(thermal_gap 0.5)
			(thermal_bridge_width 0.5)
			(island_removal_mode 0)
		)
		(polygon
			(pts
				(arc
					(start 432.30546 -219.682314)
					(mid 432.30174 -219.691294)
					(end 432.29276 -219.695014)
				)
				(arc
					(start 430.81956 -219.695014)
					(mid 430.81058 -219.691294)
					(end 430.80686 -219.682314)
				)
				(arc
					(start 430.80686 -219.187776)
					(mid 430.81058 -219.178796)
					(end 430.81956 -219.175076)
				)
				(arc
					(start 432.29276 -219.175076)
					(mid 432.30174 -219.178796)
					(end 432.30546 -219.187776)
				)
			)
		)
	)
	(zone
		(layer "In1.Cu")
		(hatch none 0.5)
		(connect_pads
			(clearance 0)
		)
		(min_thickness 0.25)
		(keepout
			(tracks not_allowed)
			(vias allowed)
			(pads allowed)
			(copperpour not_allowed)
			(footprints allowed)
		)
		(placement
			(enabled no)
			(sheetname "")
		)
		(fill
			(thermal_gap 0.5)
			(thermal_bridge_width 0.5)
			(island_removal_mode 0)
		)
		(polygon
			(pts
				(arc
					(start 60.177426 -234.982512)
					(mid 60.173706 -234.991492)
					(end 60.164726 -234.995212)
				)
				(arc
					(start 58.691526 -234.995212)
					(mid 58.682546 -234.991492)
					(end 58.678826 -234.982512)
				)
				(arc
					(start 58.678826 -234.487974)
					(mid 58.682546 -234.478994)
					(end 58.691526 -234.475274)
				)
				(arc
					(start 60.164726 -234.475274)
					(mid 60.173706 -234.478994)
					(end 60.177426 -234.487974)
				)
			)
		)
	)
	(zone
		(layer "In1.Cu")
		(hatch none 0.5)
		(connect_pads
			(clearance 0)
		)
		(min_thickness 0.25)
		(keepout
			(tracks not_allowed)
			(vias allowed)
			(pads allowed)
			(copperpour not_allowed)
			(footprints allowed)
		)
		(placement
			(enabled no)
			(sheetname "")
		)
		(fill
			(thermal_gap 0.5)
			(thermal_bridge_width 0.5)
			(island_removal_mode 0)
		)
		(polygon
			(pts
				(arc
					(start 148.28901 -388.774432)
					(mid 147.90801 -388.774432)
					(end 148.28901 -388.774432)
				)
			)
		)
	)
	(zone
		(layer "In1.Cu")
		(hatch none 0.5)
		(connect_pads
			(clearance 0)
		)
		(min_thickness 0.25)
		(keepout
			(tracks not_allowed)
			(vias allowed)
			(pads allowed)
			(copperpour not_allowed)
			(footprints allowed)
		)
		(placement
			(enabled no)
			(sheetname "")
		)
		(fill
			(thermal_gap 0.5)
			(thermal_bridge_width 0.5)
			(island_removal_mode 0)
		)
		(polygon
			(pts
				(arc
					(start 63.461138 -389.467344)
					(mid 63.080138 -389.467344)
					(end 63.461138 -389.467344)
				)
			)
		)
	)
	(zone
		(layer "In1.Cu")
		(hatch none 0.5)
		(connect_pads
			(clearance 0)
		)
		(min_thickness 0.25)
		(keepout
			(tracks not_allowed)
			(vias allowed)
			(pads allowed)
			(copperpour not_allowed)
			(footprints allowed)
		)
		(placement
			(enabled no)
			(sheetname "")
		)
		(fill
			(thermal_gap 0.5)
			(thermal_bridge_width 0.5)
			(island_removal_mode 0)
		)
		(polygon
			(pts
				(arc
					(start 304.017426 -291.932106)
					(mid 304.013706 -291.941086)
					(end 304.004726 -291.944806)
				)
				(arc
					(start 302.531526 -291.944806)
					(mid 302.522546 -291.941086)
					(end 302.518826 -291.932106)
				)
				(arc
					(start 302.518826 -291.437568)
					(mid 302.522546 -291.428588)
					(end 302.531526 -291.424868)
				)
				(arc
					(start 304.004726 -291.424868)
					(mid 304.013706 -291.428588)
					(end 304.017426 -291.437568)
				)
			)
		)
	)
	(zone
		(layer "In1.Cu")
		(hatch none 0.5)
		(connect_pads
			(clearance 0)
		)
		(min_thickness 0.25)
		(keepout
			(tracks not_allowed)
			(vias allowed)
			(pads allowed)
			(copperpour not_allowed)
			(footprints allowed)
		)
		(placement
			(enabled no)
			(sheetname "")
		)
		(fill
			(thermal_gap 0.5)
			(thermal_bridge_width 0.5)
			(island_removal_mode 0)
		)
		(polygon
			(pts
				(arc
					(start 420.661338 -304.682144)
					(mid 420.657618 -304.691124)
					(end 420.648638 -304.694844)
				)
				(arc
					(start 419.175438 -304.694844)
					(mid 419.166458 -304.691124)
					(end 419.162738 -304.682144)
				)
				(arc
					(start 419.162738 -304.187606)
					(mid 419.166458 -304.178626)
					(end 419.175438 -304.174906)
				)
				(arc
					(start 420.648638 -304.174906)
					(mid 420.657618 -304.178626)
					(end 420.661338 -304.187606)
				)
			)
		)
	)
	(zone
		(layer "In1.Cu")
		(hatch none 0.5)
		(connect_pads
			(clearance 0)
		)
		(min_thickness 0.25)
		(keepout
			(tracks not_allowed)
			(vias allowed)
			(pads allowed)
			(copperpour not_allowed)
			(footprints allowed)
		)
		(placement
			(enabled no)
			(sheetname "")
		)
		(fill
			(thermal_gap 0.5)
			(thermal_bridge_width 0.5)
			(island_removal_mode 0)
		)
		(polygon
			(pts
				(arc
					(start 304.017426 -308.932326)
					(mid 304.013706 -308.941306)
					(end 304.004726 -308.945026)
				)
				(arc
					(start 302.531526 -308.945026)
					(mid 302.522546 -308.941306)
					(end 302.518826 -308.932326)
				)
				(arc
					(start 302.518826 -308.437788)
					(mid 302.522546 -308.428808)
					(end 302.531526 -308.425088)
				)
				(arc
					(start 304.004726 -308.425088)
					(mid 304.013706 -308.428808)
					(end 304.017426 -308.437788)
				)
			)
		)
	)
	(zone
		(layer "In1.Cu")
		(hatch none 0.5)
		(connect_pads
			(clearance 0)
		)
		(min_thickness 0.25)
		(keepout
			(tracks not_allowed)
			(vias allowed)
			(pads allowed)
			(copperpour not_allowed)
			(footprints allowed)
		)
		(placement
			(enabled no)
			(sheetname "")
		)
		(fill
			(thermal_gap 0.5)
			(thermal_bridge_width 0.5)
			(island_removal_mode 0)
		)
		(polygon
			(pts
				(arc
					(start 206.9973 -298.732448)
					(mid 206.99358 -298.741428)
					(end 206.9846 -298.745148)
				)
				(arc
					(start 205.5114 -298.745148)
					(mid 205.50242 -298.741428)
					(end 205.4987 -298.732448)
				)
				(arc
					(start 205.4987 -298.23791)
					(mid 205.50242 -298.22893)
					(end 205.5114 -298.22521)
				)
				(arc
					(start 206.9846 -298.22521)
					(mid 206.99358 -298.22893)
					(end 206.9973 -298.23791)
				)
			)
		)
	)
	(zone
		(layer "In1.Cu")
		(hatch none 0.5)
		(connect_pads
			(clearance 0)
		)
		(min_thickness 0.25)
		(keepout
			(tracks not_allowed)
			(vias allowed)
			(pads allowed)
			(copperpour not_allowed)
			(footprints allowed)
		)
		(placement
			(enabled no)
			(sheetname "")
		)
		(fill
			(thermal_gap 0.5)
			(thermal_bridge_width 0.5)
			(island_removal_mode 0)
		)
		(polygon
			(pts
				(arc
					(start 56.077358 -198.43242)
					(mid 56.073638 -198.4414)
					(end 56.064658 -198.44512)
				)
				(arc
					(start 54.591458 -198.44512)
					(mid 54.582478 -198.4414)
					(end 54.578758 -198.43242)
				)
				(arc
					(start 54.578758 -197.937882)
					(mid 54.582478 -197.928902)
					(end 54.591458 -197.925182)
				)
				(arc
					(start 56.064658 -197.925182)
					(mid 56.073638 -197.928902)
					(end 56.077358 -197.937882)
				)
			)
		)
	)
	(zone
		(layer "In1.Cu")
		(hatch none 0.5)
		(connect_pads
			(clearance 0)
		)
		(min_thickness 0.25)
		(keepout
			(tracks not_allowed)
			(vias allowed)
			(pads allowed)
			(copperpour not_allowed)
			(footprints allowed)
		)
		(placement
			(enabled no)
			(sheetname "")
		)
		(fill
			(thermal_gap 0.5)
			(thermal_bridge_width 0.5)
			(island_removal_mode 0)
		)
		(polygon
			(pts
				(arc
					(start 195.353432 -268.982444)
					(mid 195.349712 -268.991424)
					(end 195.340732 -268.995144)
				)
				(arc
					(start 193.867532 -268.995144)
					(mid 193.858552 -268.991424)
					(end 193.854832 -268.982444)
				)
				(arc
					(start 193.854832 -268.487906)
					(mid 193.858552 -268.478926)
					(end 193.867532 -268.475206)
				)
				(arc
					(start 195.340732 -268.475206)
					(mid 195.349712 -268.478926)
					(end 195.353432 -268.487906)
				)
			)
		)
	)
	(zone
		(layer "In1.Cu")
		(hatch none 0.5)
		(connect_pads
			(clearance 0)
		)
		(min_thickness 0.25)
		(keepout
			(tracks not_allowed)
			(vias allowed)
			(pads allowed)
			(copperpour not_allowed)
			(footprints allowed)
		)
		(placement
			(enabled no)
			(sheetname "")
		)
		(fill
			(thermal_gap 0.5)
			(thermal_bridge_width 0.5)
			(island_removal_mode 0)
		)
		(polygon
			(pts
				(arc
					(start 420.661338 -251.982224)
					(mid 420.657618 -251.991204)
					(end 420.648638 -251.994924)
				)
				(arc
					(start 419.175438 -251.994924)
					(mid 419.166458 -251.991204)
					(end 419.162738 -251.982224)
				)
				(arc
					(start 419.162738 -251.487686)
					(mid 419.166458 -251.478706)
					(end 419.175438 -251.474986)
				)
				(arc
					(start 420.648638 -251.474986)
					(mid 420.657618 -251.478706)
					(end 420.661338 -251.487686)
				)
			)
		)
	)
	(zone
		(layer "In1.Cu")
		(hatch none 0.5)
		(connect_pads
			(clearance 0)
		)
		(min_thickness 0.25)
		(keepout
			(tracks not_allowed)
			(vias allowed)
			(pads allowed)
			(copperpour not_allowed)
			(footprints allowed)
		)
		(placement
			(enabled no)
			(sheetname "")
		)
		(fill
			(thermal_gap 0.5)
			(thermal_bridge_width 0.5)
			(island_removal_mode 0)
		)
		(polygon
			(pts
				(arc
					(start 180.265324 -314.032392)
					(mid 180.261604 -314.041372)
					(end 180.252624 -314.045092)
				)
				(arc
					(start 178.779424 -314.045092)
					(mid 178.770444 -314.041372)
					(end 178.766724 -314.032392)
				)
				(arc
					(start 178.766724 -313.537854)
					(mid 178.770444 -313.528874)
					(end 178.779424 -313.525154)
				)
				(arc
					(start 180.252624 -313.525154)
					(mid 180.261604 -313.528874)
					(end 180.265324 -313.537854)
				)
			)
		)
	)
	(zone
		(layer "In1.Cu")
		(hatch none 0.5)
		(connect_pads
			(clearance 0)
		)
		(min_thickness 0.25)
		(keepout
			(tracks not_allowed)
			(vias allowed)
			(pads allowed)
			(copperpour not_allowed)
			(footprints allowed)
		)
		(placement
			(enabled no)
			(sheetname "")
		)
		(fill
			(thermal_gap 0.5)
			(thermal_bridge_width 0.5)
			(island_removal_mode 0)
		)
		(polygon
			(pts
				(arc
					(start 199.4535 -313.182508)
					(mid 199.44978 -313.191488)
					(end 199.4408 -313.195208)
				)
				(arc
					(start 197.9676 -313.195208)
					(mid 197.95862 -313.191488)
					(end 197.9549 -313.182508)
				)
				(arc
					(start 197.9549 -312.68797)
					(mid 197.95862 -312.67899)
					(end 197.9676 -312.67527)
				)
				(arc
					(start 199.4408 -312.67527)
					(mid 199.44978 -312.67899)
					(end 199.4535 -312.68797)
				)
			)
		)
	)
	(zone
		(layer "In1.Cu")
		(hatch none 0.5)
		(connect_pads
			(clearance 0)
		)
		(min_thickness 0.25)
		(keepout
			(tracks not_allowed)
			(vias allowed)
			(pads allowed)
			(copperpour not_allowed)
			(footprints allowed)
		)
		(placement
			(enabled no)
			(sheetname "")
		)
		(fill
			(thermal_gap 0.5)
			(thermal_bridge_width 0.5)
			(island_removal_mode 0)
		)
		(polygon
			(pts
				(arc
					(start 288.929318 -224.782126)
					(mid 288.925598 -224.791106)
					(end 288.916618 -224.794826)
				)
				(arc
					(start 287.443418 -224.794826)
					(mid 287.434438 -224.791106)
					(end 287.430718 -224.782126)
				)
				(arc
					(start 287.430718 -224.287588)
					(mid 287.434438 -224.278608)
					(end 287.443418 -224.274888)
				)
				(arc
					(start 288.916618 -224.274888)
					(mid 288.925598 -224.278608)
					(end 288.929318 -224.287588)
				)
			)
		)
	)
	(zone
		(layer "In1.Cu")
		(hatch none 0.5)
		(connect_pads
			(clearance 0)
		)
		(min_thickness 0.25)
		(keepout
			(tracks not_allowed)
			(vias allowed)
			(pads allowed)
			(copperpour not_allowed)
			(footprints allowed)
		)
		(placement
			(enabled no)
			(sheetname "")
		)
		(fill
			(thermal_gap 0.5)
			(thermal_bridge_width 0.5)
			(island_removal_mode 0)
		)
		(polygon
			(pts
				(arc
					(start 180.265324 -295.332404)
					(mid 180.261604 -295.341384)
					(end 180.252624 -295.345104)
				)
				(arc
					(start 178.779424 -295.345104)
					(mid 178.770444 -295.341384)
					(end 178.766724 -295.332404)
				)
				(arc
					(start 178.766724 -294.837866)
					(mid 178.770444 -294.828886)
					(end 178.779424 -294.825166)
				)
				(arc
					(start 180.252624 -294.825166)
					(mid 180.261604 -294.828886)
					(end 180.265324 -294.837866)
				)
			)
		)
	)
	(zone
		(layer "In1.Cu")
		(hatch none 0.5)
		(connect_pads
			(clearance 0)
		)
		(min_thickness 0.25)
		(keepout
			(tracks not_allowed)
			(vias allowed)
			(pads allowed)
			(copperpour not_allowed)
			(footprints allowed)
		)
		(placement
			(enabled no)
			(sheetname "")
		)
		(fill
			(thermal_gap 0.5)
			(thermal_bridge_width 0.5)
			(island_removal_mode 0)
		)
		(polygon
			(pts
				(arc
					(start 165.177216 -314.88253)
					(mid 165.173496 -314.89151)
					(end 165.164516 -314.89523)
				)
				(arc
					(start 163.691316 -314.89523)
					(mid 163.682336 -314.89151)
					(end 163.678616 -314.88253)
				)
				(arc
					(start 163.678616 -314.387992)
					(mid 163.682336 -314.379012)
					(end 163.691316 -314.375292)
				)
				(arc
					(start 165.164516 -314.375292)
					(mid 165.173496 -314.379012)
					(end 165.177216 -314.387992)
				)
			)
		)
	)
	(zone
		(layer "In1.Cu")
		(hatch none 0.5)
		(connect_pads
			(clearance 0)
		)
		(min_thickness 0.25)
		(keepout
			(tracks not_allowed)
			(vias allowed)
			(pads allowed)
			(copperpour not_allowed)
			(footprints allowed)
		)
		(placement
			(enabled no)
			(sheetname "")
		)
		(fill
			(thermal_gap 0.5)
			(thermal_bridge_width 0.5)
			(island_removal_mode 0)
		)
		(polygon
			(pts
				(arc
					(start 187.809378 -198.43242)
					(mid 187.805658 -198.4414)
					(end 187.796678 -198.44512)
				)
				(arc
					(start 186.323478 -198.44512)
					(mid 186.314498 -198.4414)
					(end 186.310778 -198.43242)
				)
				(arc
					(start 186.310778 -197.937882)
					(mid 186.314498 -197.928902)
					(end 186.323478 -197.925182)
				)
				(arc
					(start 187.796678 -197.925182)
					(mid 187.805658 -197.928902)
					(end 187.809378 -197.937882)
				)
			)
		)
	)
	(zone
		(layer "In1.Cu")
		(hatch none 0.5)
		(connect_pads
			(clearance 0)
		)
		(min_thickness 0.25)
		(keepout
			(tracks not_allowed)
			(vias allowed)
			(pads allowed)
			(copperpour not_allowed)
			(footprints allowed)
		)
		(placement
			(enabled no)
			(sheetname "")
		)
		(fill
			(thermal_gap 0.5)
			(thermal_bridge_width 0.5)
			(island_removal_mode 0)
		)
		(polygon
			(pts
				(arc
					(start 61.861192 -385.31038)
					(mid 61.480192 -385.31038)
					(end 61.861192 -385.31038)
				)
			)
		)
	)
	(zone
		(layer "In1.Cu")
		(hatch none 0.5)
		(connect_pads
			(clearance 0)
		)
		(min_thickness 0.25)
		(keepout
			(tracks not_allowed)
			(vias allowed)
			(pads allowed)
			(copperpour not_allowed)
			(footprints allowed)
		)
		(placement
			(enabled no)
			(sheetname "")
		)
		(fill
			(thermal_gap 0.5)
			(thermal_bridge_width 0.5)
			(island_removal_mode 0)
		)
		(polygon
			(pts
				(arc
					(start 270.397478 -304.682144)
					(mid 270.393758 -304.691124)
					(end 270.384778 -304.694844)
				)
				(arc
					(start 268.911578 -304.694844)
					(mid 268.902598 -304.691124)
					(end 268.898878 -304.682144)
				)
				(arc
					(start 268.898878 -304.187606)
					(mid 268.902598 -304.178626)
					(end 268.911578 -304.174906)
				)
				(arc
					(start 270.384778 -304.174906)
					(mid 270.393758 -304.178626)
					(end 270.397478 -304.187606)
				)
			)
		)
	)
	(zone
		(layer "In1.Cu")
		(hatch none 0.5)
		(connect_pads
			(clearance 0)
		)
		(min_thickness 0.25)
		(keepout
			(tracks not_allowed)
			(vias allowed)
			(pads allowed)
			(copperpour not_allowed)
			(footprints allowed)
		)
		(placement
			(enabled no)
			(sheetname "")
		)
		(fill
			(thermal_gap 0.5)
			(thermal_bridge_width 0.5)
			(island_removal_mode 0)
		)
		(polygon
			(pts
				(arc
					(start 413.117284 -310.632094)
					(mid 413.113564 -310.641074)
					(end 413.104584 -310.644794)
				)
				(arc
					(start 411.631384 -310.644794)
					(mid 411.622404 -310.641074)
					(end 411.618684 -310.632094)
				)
				(arc
					(start 411.618684 -310.137556)
					(mid 411.622404 -310.128576)
					(end 411.631384 -310.124856)
				)
				(arc
					(start 413.104584 -310.124856)
					(mid 413.113564 -310.128576)
					(end 413.117284 -310.137556)
				)
			)
		)
	)
	(zone
		(layer "In1.Cu")
		(hatch none 0.5)
		(connect_pads
			(clearance 0)
		)
		(min_thickness 0.25)
		(keepout
			(tracks not_allowed)
			(vias allowed)
			(pads allowed)
			(copperpour not_allowed)
			(footprints allowed)
		)
		(placement
			(enabled no)
			(sheetname "")
		)
		(fill
			(thermal_gap 0.5)
			(thermal_bridge_width 0.5)
			(island_removal_mode 0)
		)
		(polygon
			(pts
				(arc
					(start 450.8373 -262.182102)
					(mid 450.83358 -262.191082)
					(end 450.8246 -262.194802)
				)
				(arc
					(start 449.3514 -262.194802)
					(mid 449.34242 -262.191082)
					(end 449.3387 -262.182102)
				)
				(arc
					(start 449.3387 -261.687564)
					(mid 449.34242 -261.678584)
					(end 449.3514 -261.674864)
				)
				(arc
					(start 450.8246 -261.674864)
					(mid 450.83358 -261.678584)
					(end 450.8373 -261.687564)
				)
			)
		)
	)
	(zone
		(layer "In1.Cu")
		(hatch none 0.5)
		(connect_pads
			(clearance 0)
		)
		(min_thickness 0.25)
		(keepout
			(tracks not_allowed)
			(vias allowed)
			(pads allowed)
			(copperpour not_allowed)
			(footprints allowed)
		)
		(placement
			(enabled no)
			(sheetname "")
		)
		(fill
			(thermal_gap 0.5)
			(thermal_bridge_width 0.5)
			(island_removal_mode 0)
		)
		(polygon
			(pts
				(arc
					(start 435.749446 -314.032138)
					(mid 435.745726 -314.041118)
					(end 435.736746 -314.044838)
				)
				(arc
					(start 434.263546 -314.044838)
					(mid 434.254566 -314.041118)
					(end 434.250846 -314.032138)
				)
				(arc
					(start 434.250846 -313.5376)
					(mid 434.254566 -313.52862)
					(end 434.263546 -313.5249)
				)
				(arc
					(start 435.736746 -313.5249)
					(mid 435.745726 -313.52862)
					(end 435.749446 -313.5376)
				)
			)
		)
	)
	(zone
		(layer "In1.Cu")
		(hatch none 0.5)
		(connect_pads
			(clearance 0)
		)
		(min_thickness 0.25)
		(keepout
			(tracks not_allowed)
			(vias allowed)
			(pads allowed)
			(copperpour not_allowed)
			(footprints allowed)
		)
		(placement
			(enabled no)
			(sheetname "")
		)
		(fill
			(thermal_gap 0.5)
			(thermal_bridge_width 0.5)
			(island_removal_mode 0)
		)
		(polygon
			(pts
				(arc
					(start 187.809378 -204.38237)
					(mid 187.805658 -204.39135)
					(end 187.796678 -204.39507)
				)
				(arc
					(start 186.323478 -204.39507)
					(mid 186.314498 -204.39135)
					(end 186.310778 -204.38237)
				)
				(arc
					(start 186.310778 -203.887832)
					(mid 186.314498 -203.878852)
					(end 186.323478 -203.875132)
				)
				(arc
					(start 187.796678 -203.875132)
					(mid 187.805658 -203.878852)
					(end 187.809378 -203.887832)
				)
			)
		)
	)
	(zone
		(layer "In1.Cu")
		(hatch none 0.5)
		(connect_pads
			(clearance 0)
		)
		(min_thickness 0.25)
		(keepout
			(tracks not_allowed)
			(vias allowed)
			(pads allowed)
			(copperpour not_allowed)
			(footprints allowed)
		)
		(placement
			(enabled no)
			(sheetname "")
		)
		(fill
			(thermal_gap 0.5)
			(thermal_bridge_width 0.5)
			(island_removal_mode 0)
		)
		(polygon
			(pts
				(arc
					(start 60.177426 -199.282558)
					(mid 60.173706 -199.291538)
					(end 60.164726 -199.295258)
				)
				(arc
					(start 58.691526 -199.295258)
					(mid 58.682546 -199.291538)
					(end 58.678826 -199.282558)
				)
				(arc
					(start 58.678826 -198.78802)
					(mid 58.682546 -198.77904)
					(end 58.691526 -198.77532)
				)
				(arc
					(start 60.164726 -198.77532)
					(mid 60.173706 -198.77904)
					(end 60.177426 -198.78802)
				)
			)
		)
	)
	(zone
		(layer "In1.Cu")
		(hatch none 0.5)
		(connect_pads
			(clearance 0)
		)
		(min_thickness 0.25)
		(keepout
			(tracks not_allowed)
			(vias allowed)
			(pads allowed)
			(copperpour not_allowed)
			(footprints allowed)
		)
		(placement
			(enabled no)
			(sheetname "")
		)
		(fill
			(thermal_gap 0.5)
			(thermal_bridge_width 0.5)
			(island_removal_mode 0)
		)
		(polygon
			(pts
				(arc
					(start 206.5782 -275.53539)
					(mid 205.9178 -275.53539)
					(end 206.5782 -275.53539)
				)
			)
		)
	)
	(zone
		(layer "In1.Cu")
		(hatch none 0.5)
		(connect_pads
			(clearance 0)
		)
		(min_thickness 0.25)
		(keepout
			(tracks not_allowed)
			(vias allowed)
			(pads allowed)
			(copperpour not_allowed)
			(footprints allowed)
		)
		(placement
			(enabled no)
			(sheetname "")
		)
		(fill
			(thermal_gap 0.5)
			(thermal_bridge_width 0.5)
			(island_removal_mode 0)
		)
		(polygon
			(pts
				(arc
					(start 172.72127 -262.182356)
					(mid 172.71755 -262.191336)
					(end 172.70857 -262.195056)
				)
				(arc
					(start 171.23537 -262.195056)
					(mid 171.22639 -262.191336)
					(end 171.22267 -262.182356)
				)
				(arc
					(start 171.22267 -261.687818)
					(mid 171.22639 -261.678838)
					(end 171.23537 -261.675118)
				)
				(arc
					(start 172.70857 -261.675118)
					(mid 172.71755 -261.678838)
					(end 172.72127 -261.687818)
				)
			)
		)
	)
	(zone
		(layer "In1.Cu")
		(hatch none 0.5)
		(connect_pads
			(clearance 0)
		)
		(min_thickness 0.25)
		(keepout
			(tracks not_allowed)
			(vias allowed)
			(pads allowed)
			(copperpour not_allowed)
			(footprints allowed)
		)
		(placement
			(enabled no)
			(sheetname "")
		)
		(fill
			(thermal_gap 0.5)
			(thermal_bridge_width 0.5)
			(island_removal_mode 0)
		)
		(polygon
			(pts
				(arc
					(start 270.397478 -266.432284)
					(mid 270.393758 -266.441264)
					(end 270.384778 -266.444984)
				)
				(arc
					(start 268.911578 -266.444984)
					(mid 268.902598 -266.441264)
					(end 268.898878 -266.432284)
				)
				(arc
					(start 268.898878 -265.937746)
					(mid 268.902598 -265.928766)
					(end 268.911578 -265.925046)
				)
				(arc
					(start 270.384778 -265.925046)
					(mid 270.393758 -265.928766)
					(end 270.397478 -265.937746)
				)
			)
		)
	)
	(zone
		(layer "In1.Cu")
		(hatch none 0.5)
		(connect_pads
			(clearance 0)
		)
		(min_thickness 0.25)
		(keepout
			(tracks not_allowed)
			(vias allowed)
			(pads allowed)
			(copperpour not_allowed)
			(footprints allowed)
		)
		(placement
			(enabled no)
			(sheetname "")
		)
		(fill
			(thermal_gap 0.5)
			(thermal_bridge_width 0.5)
			(island_removal_mode 0)
		)
		(polygon
			(pts
				(arc
					(start 428.205392 -318.28232)
					(mid 428.201672 -318.2913)
					(end 428.192692 -318.29502)
				)
				(arc
					(start 426.719492 -318.29502)
					(mid 426.710512 -318.2913)
					(end 426.706792 -318.28232)
				)
				(arc
					(start 426.706792 -317.787782)
					(mid 426.710512 -317.778802)
					(end 426.719492 -317.775082)
				)
				(arc
					(start 428.192692 -317.775082)
					(mid 428.201672 -317.778802)
					(end 428.205392 -317.787782)
				)
			)
		)
	)
	(zone
		(layer "In1.Cu")
		(hatch none 0.5)
		(connect_pads
			(clearance 0)
		)
		(min_thickness 0.25)
		(keepout
			(tracks not_allowed)
			(vias allowed)
			(pads allowed)
			(copperpour not_allowed)
			(footprints allowed)
		)
		(placement
			(enabled no)
			(sheetname "")
		)
		(fill
			(thermal_gap 0.5)
			(thermal_bridge_width 0.5)
			(island_removal_mode 0)
		)
		(polygon
			(pts
				(arc
					(start 149.018752 -383.440686)
					(mid 149.145752 -383.567686)
					(end 149.272752 -383.440686)
				)
				(arc
					(start 149.272752 -383.364486)
					(mid 149.145752 -383.237486)
					(end 149.018752 -383.364486)
				)
			)
		)
	)
	(zone
		(layer "In1.Cu")
		(hatch none 0.5)
		(connect_pads
			(clearance 0)
		)
		(min_thickness 0.25)
		(keepout
			(tracks not_allowed)
			(vias allowed)
			(pads allowed)
			(copperpour not_allowed)
			(footprints allowed)
		)
		(placement
			(enabled no)
			(sheetname "")
		)
		(fill
			(thermal_gap 0.5)
			(thermal_bridge_width 0.5)
			(island_removal_mode 0)
		)
		(polygon
			(pts
				(arc
					(start 439.849514 -314.032138)
					(mid 439.845794 -314.041118)
					(end 439.836814 -314.044838)
				)
				(arc
					(start 438.363614 -314.044838)
					(mid 438.354634 -314.041118)
					(end 438.350914 -314.032138)
				)
				(arc
					(start 438.350914 -313.5376)
					(mid 438.354634 -313.52862)
					(end 438.363614 -313.5249)
				)
				(arc
					(start 439.836814 -313.5249)
					(mid 439.845794 -313.52862)
					(end 439.849514 -313.5376)
				)
			)
		)
	)
	(zone
		(layer "In1.Cu")
		(hatch none 0.5)
		(connect_pads
			(clearance 0)
		)
		(min_thickness 0.25)
		(keepout
			(tracks not_allowed)
			(vias allowed)
			(pads allowed)
			(copperpour not_allowed)
			(footprints allowed)
		)
		(placement
			(enabled no)
			(sheetname "")
		)
		(fill
			(thermal_gap 0.5)
			(thermal_bridge_width 0.5)
			(island_removal_mode 0)
		)
		(polygon
			(pts
				(arc
					(start 413.117284 -291.932106)
					(mid 413.113564 -291.941086)
					(end 413.104584 -291.944806)
				)
				(arc
					(start 411.631384 -291.944806)
					(mid 411.622404 -291.941086)
					(end 411.618684 -291.932106)
				)
				(arc
					(start 411.618684 -291.437568)
					(mid 411.622404 -291.428588)
					(end 411.631384 -291.424868)
				)
				(arc
					(start 413.104584 -291.424868)
					(mid 413.113564 -291.428588)
					(end 413.117284 -291.437568)
				)
			)
		)
	)
	(zone
		(layer "In1.Cu")
		(hatch none 0.5)
		(connect_pads
			(clearance 0)
		)
		(min_thickness 0.25)
		(keepout
			(tracks not_allowed)
			(vias allowed)
			(pads allowed)
			(copperpour not_allowed)
			(footprints allowed)
		)
		(placement
			(enabled no)
			(sheetname "")
		)
		(fill
			(thermal_gap 0.5)
			(thermal_bridge_width 0.5)
			(island_removal_mode 0)
		)
		(polygon
			(pts
				(arc
					(start 165.177216 -226.482402)
					(mid 165.173496 -226.491382)
					(end 165.164516 -226.495102)
				)
				(arc
					(start 163.691316 -226.495102)
					(mid 163.682336 -226.491382)
					(end 163.678616 -226.482402)
				)
				(arc
					(start 163.678616 -225.987864)
					(mid 163.682336 -225.978884)
					(end 163.691316 -225.975164)
				)
				(arc
					(start 165.164516 -225.975164)
					(mid 165.173496 -225.978884)
					(end 165.177216 -225.987864)
				)
			)
		)
	)
	(zone
		(layer "In1.Cu")
		(hatch none 0.5)
		(connect_pads
			(clearance 0)
		)
		(min_thickness 0.25)
		(keepout
			(tracks not_allowed)
			(vias allowed)
			(pads allowed)
			(copperpour not_allowed)
			(footprints allowed)
		)
		(placement
			(enabled no)
			(sheetname "")
		)
		(fill
			(thermal_gap 0.5)
			(thermal_bridge_width 0.5)
			(island_removal_mode 0)
		)
		(polygon
			(pts
				(arc
					(start 288.929318 -265.582146)
					(mid 288.925598 -265.591126)
					(end 288.916618 -265.594846)
				)
				(arc
					(start 287.443418 -265.594846)
					(mid 287.434438 -265.591126)
					(end 287.430718 -265.582146)
				)
				(arc
					(start 287.430718 -265.087608)
					(mid 287.434438 -265.078628)
					(end 287.443418 -265.074908)
				)
				(arc
					(start 288.916618 -265.074908)
					(mid 288.925598 -265.078628)
					(end 288.929318 -265.087608)
				)
			)
		)
	)
	(zone
		(layer "In1.Cu")
		(hatch none 0.5)
		(connect_pads
			(clearance 0)
		)
		(min_thickness 0.25)
		(keepout
			(tracks not_allowed)
			(vias allowed)
			(pads allowed)
			(copperpour not_allowed)
			(footprints allowed)
		)
		(placement
			(enabled no)
			(sheetname "")
		)
		(fill
			(thermal_gap 0.5)
			(thermal_bridge_width 0.5)
			(island_removal_mode 0)
		)
		(polygon
			(pts
				(arc
					(start 277.941532 -289.3822)
					(mid 277.937812 -289.39118)
					(end 277.928832 -289.3949)
				)
				(arc
					(start 276.455632 -289.3949)
					(mid 276.446652 -289.39118)
					(end 276.442932 -289.3822)
				)
				(arc
					(start 276.442932 -288.887662)
					(mid 276.446652 -288.878682)
					(end 276.455632 -288.874962)
				)
				(arc
					(start 277.928832 -288.874962)
					(mid 277.937812 -288.878682)
					(end 277.941532 -288.887662)
				)
			)
		)
	)
	(zone
		(layer "In1.Cu")
		(hatch none 0.5)
		(connect_pads
			(clearance 0)
		)
		(min_thickness 0.25)
		(keepout
			(tracks not_allowed)
			(vias allowed)
			(pads allowed)
			(copperpour not_allowed)
			(footprints allowed)
		)
		(placement
			(enabled no)
			(sheetname "")
		)
		(fill
			(thermal_gap 0.5)
			(thermal_bridge_width 0.5)
			(island_removal_mode 0)
		)
		(polygon
			(pts
				(arc
					(start 37.545264 -287.682432)
					(mid 37.541544 -287.691412)
					(end 37.532564 -287.695132)
				)
				(arc
					(start 36.059364 -287.695132)
					(mid 36.050384 -287.691412)
					(end 36.046664 -287.682432)
				)
				(arc
					(start 36.046664 -287.187894)
					(mid 36.050384 -287.178914)
					(end 36.059364 -287.175194)
				)
				(arc
					(start 37.532564 -287.175194)
					(mid 37.541544 -287.178914)
					(end 37.545264 -287.187894)
				)
			)
		)
	)
	(zone
		(layer "In1.Cu")
		(hatch none 0.5)
		(connect_pads
			(clearance 0)
		)
		(min_thickness 0.25)
		(keepout
			(tracks not_allowed)
			(vias allowed)
			(pads allowed)
			(copperpour not_allowed)
			(footprints allowed)
		)
		(placement
			(enabled no)
			(sheetname "")
		)
		(fill
			(thermal_gap 0.5)
			(thermal_bridge_width 0.5)
			(island_removal_mode 0)
		)
		(polygon
			(pts
				(arc
					(start 417.217352 -270.682212)
					(mid 417.213632 -270.691192)
					(end 417.204652 -270.694912)
				)
				(arc
					(start 415.731452 -270.694912)
					(mid 415.722472 -270.691192)
					(end 415.718752 -270.682212)
				)
				(arc
					(start 415.718752 -270.187674)
					(mid 415.722472 -270.178694)
					(end 415.731452 -270.174974)
				)
				(arc
					(start 417.204652 -270.174974)
					(mid 417.213632 -270.178694)
					(end 417.217352 -270.187674)
				)
			)
		)
	)
	(zone
		(layer "In1.Cu")
		(hatch none 0.5)
		(connect_pads
			(clearance 0)
		)
		(min_thickness 0.25)
		(keepout
			(tracks not_allowed)
			(vias allowed)
			(pads allowed)
			(copperpour not_allowed)
			(footprints allowed)
		)
		(placement
			(enabled no)
			(sheetname "")
		)
		(fill
			(thermal_gap 0.5)
			(thermal_bridge_width 0.5)
			(island_removal_mode 0)
		)
		(polygon
			(pts
				(arc
					(start 25.901396 -204.38237)
					(mid 25.897676 -204.39135)
					(end 25.888696 -204.39507)
				)
				(arc
					(start 24.415496 -204.39507)
					(mid 24.406516 -204.39135)
					(end 24.402796 -204.38237)
				)
				(arc
					(start 24.402796 -203.887832)
					(mid 24.406516 -203.878852)
					(end 24.415496 -203.875132)
				)
				(arc
					(start 25.888696 -203.875132)
					(mid 25.897676 -203.878852)
					(end 25.901396 -203.887832)
				)
			)
		)
	)
	(zone
		(layer "In1.Cu")
		(hatch none 0.5)
		(connect_pads
			(clearance 0)
		)
		(min_thickness 0.25)
		(keepout
			(tracks not_allowed)
			(vias allowed)
			(pads allowed)
			(copperpour not_allowed)
			(footprints allowed)
		)
		(placement
			(enabled no)
			(sheetname "")
		)
		(fill
			(thermal_gap 0.5)
			(thermal_bridge_width 0.5)
			(island_removal_mode 0)
		)
		(polygon
			(pts
				(arc
					(start 412.68904 -393.69238)
					(mid 412.30804 -393.69238)
					(end 412.68904 -393.69238)
				)
			)
		)
	)
	(zone
		(layer "In1.Cu")
		(hatch none 0.5)
		(connect_pads
			(clearance 0)
		)
		(min_thickness 0.25)
		(keepout
			(tracks not_allowed)
			(vias allowed)
			(pads allowed)
			(copperpour not_allowed)
			(footprints allowed)
		)
		(placement
			(enabled no)
			(sheetname "")
		)
		(fill
			(thermal_gap 0.5)
			(thermal_bridge_width 0.5)
			(island_removal_mode 0)
		)
		(polygon
			(pts
				(arc
					(start 375.760996 -397.849344)
					(mid 375.379996 -397.849344)
					(end 375.760996 -397.849344)
				)
			)
		)
	)
	(zone
		(layer "In1.Cu")
		(hatch none 0.5)
		(connect_pads
			(clearance 0)
		)
		(min_thickness 0.25)
		(keepout
			(tracks not_allowed)
			(vias allowed)
			(pads allowed)
			(copperpour not_allowed)
			(footprints allowed)
		)
		(placement
			(enabled no)
			(sheetname "")
		)
		(fill
			(thermal_gap 0.5)
			(thermal_bridge_width 0.5)
			(island_removal_mode 0)
		)
		(polygon
			(pts
				(arc
					(start 299.7835 -381.824484)
					(mid 299.803424 -381.83372)
					(end 299.825156 -381.83693)
				)
				(arc
					(start 300.01972 -381.83693)
					(mid 300.073602 -381.814612)
					(end 300.09592 -381.76073)
				)
				(arc
					(start 300.09592 -381.07493)
					(mid 300.073602 -381.021048)
					(end 300.01972 -380.99873)
				)
				(arc
					(start 299.825156 -380.99873)
					(mid 299.803412 -381.001898)
					(end 299.7835 -381.011176)
				)
				(arc
					(start 299.487336 -381.203962)
					(mid 299.445652 -381.216184)
					(end 299.404024 -381.203708)
				)
				(arc
					(start 299.1104 -381.011176)
					(mid 299.090476 -381.00194)
					(end 299.068744 -380.99873)
				)
				(arc
					(start 298.87418 -380.99873)
					(mid 298.820298 -381.021048)
					(end 298.79798 -381.07493)
				)
				(arc
					(start 298.79798 -381.76073)
					(mid 298.820298 -381.814612)
					(end 298.87418 -381.83693)
				)
				(arc
					(start 299.070014 -381.83693)
					(mid 299.091758 -381.833762)
					(end 299.11167 -381.824484)
				)
				(arc
					(start 299.405294 -381.631952)
					(mid 299.44695 -381.61955)
					(end 299.488606 -381.631952)
				)
			)
		)
	)
	(zone
		(layer "In1.Cu")
		(hatch none 0.5)
		(connect_pads
			(clearance 0)
		)
		(min_thickness 0.25)
		(keepout
			(tracks not_allowed)
			(vias allowed)
			(pads allowed)
			(copperpour not_allowed)
			(footprints allowed)
		)
		(placement
			(enabled no)
			(sheetname "")
		)
		(fill
			(thermal_gap 0.5)
			(thermal_bridge_width 0.5)
			(island_removal_mode 0)
		)
		(polygon
			(pts
				(arc
					(start 428.205392 -224.782126)
					(mid 428.201672 -224.791106)
					(end 428.192692 -224.794826)
				)
				(arc
					(start 426.719492 -224.794826)
					(mid 426.710512 -224.791106)
					(end 426.706792 -224.782126)
				)
				(arc
					(start 426.706792 -224.287588)
					(mid 426.710512 -224.278608)
					(end 426.719492 -224.274888)
				)
				(arc
					(start 428.192692 -224.274888)
					(mid 428.201672 -224.278608)
					(end 428.205392 -224.287588)
				)
			)
		)
	)
	(zone
		(layer "In1.Cu")
		(hatch none 0.5)
		(connect_pads
			(clearance 0)
		)
		(min_thickness 0.25)
		(keepout
			(tracks not_allowed)
			(vias allowed)
			(pads allowed)
			(copperpour not_allowed)
			(footprints allowed)
		)
		(placement
			(enabled no)
			(sheetname "")
		)
		(fill
			(thermal_gap 0.5)
			(thermal_bridge_width 0.5)
			(island_removal_mode 0)
		)
		(polygon
			(pts
				(arc
					(start 377.870466 -392.30427)
					(mid 377.565666 -392.30427)
					(end 377.870466 -392.30427)
				)
			)
		)
	)
	(zone
		(layer "In1.Cu")
		(hatch none 0.5)
		(connect_pads
			(clearance 0)
		)
		(min_thickness 0.25)
		(keepout
			(tracks not_allowed)
			(vias allowed)
			(pads allowed)
			(copperpour not_allowed)
			(footprints allowed)
		)
		(placement
			(enabled no)
			(sheetname "")
		)
		(fill
			(thermal_gap 0.5)
			(thermal_bridge_width 0.5)
			(island_removal_mode 0)
		)
		(polygon
			(pts
				(arc
					(start 293.029386 -201.83221)
					(mid 293.025666 -201.84119)
					(end 293.016686 -201.84491)
				)
				(arc
					(start 291.543486 -201.84491)
					(mid 291.534506 -201.84119)
					(end 291.530786 -201.83221)
				)
				(arc
					(start 291.530786 -201.337672)
					(mid 291.534506 -201.328692)
					(end 291.543486 -201.324972)
				)
				(arc
					(start 293.016686 -201.324972)
					(mid 293.025666 -201.328692)
					(end 293.029386 -201.337672)
				)
			)
		)
	)
	(zone
		(layer "In1.Cu")
		(hatch none 0.5)
		(connect_pads
			(clearance 0)
		)
		(min_thickness 0.25)
		(keepout
			(tracks not_allowed)
			(vias allowed)
			(pads allowed)
			(copperpour not_allowed)
			(footprints allowed)
		)
		(placement
			(enabled no)
			(sheetname "")
		)
		(fill
			(thermal_gap 0.5)
			(thermal_bridge_width 0.5)
			(island_removal_mode 0)
		)
		(polygon
			(pts
				(arc
					(start 281.385264 -234.13212)
					(mid 281.381544 -234.1411)
					(end 281.372564 -234.14482)
				)
				(arc
					(start 279.899364 -234.14482)
					(mid 279.890384 -234.1411)
					(end 279.886664 -234.13212)
				)
				(arc
					(start 279.886664 -233.637582)
					(mid 279.890384 -233.628602)
					(end 279.899364 -233.624882)
				)
				(arc
					(start 281.372564 -233.624882)
					(mid 281.381544 -233.628602)
					(end 281.385264 -233.637582)
				)
			)
		)
	)
	(zone
		(layer "In1.Cu")
		(hatch none 0.5)
		(connect_pads
			(clearance 0)
		)
		(min_thickness 0.25)
		(keepout
			(tracks not_allowed)
			(vias allowed)
			(pads allowed)
			(copperpour not_allowed)
			(footprints allowed)
		)
		(placement
			(enabled no)
			(sheetname "")
		)
		(fill
			(thermal_gap 0.5)
			(thermal_bridge_width 0.5)
			(island_removal_mode 0)
		)
		(polygon
			(pts
				(arc
					(start 428.205392 -286.832294)
					(mid 428.201672 -286.841274)
					(end 428.192692 -286.844994)
				)
				(arc
					(start 426.719492 -286.844994)
					(mid 426.710512 -286.841274)
					(end 426.706792 -286.832294)
				)
				(arc
					(start 426.706792 -286.337756)
					(mid 426.710512 -286.328776)
					(end 426.719492 -286.325056)
				)
				(arc
					(start 428.192692 -286.325056)
					(mid 428.201672 -286.328776)
					(end 428.205392 -286.337756)
				)
			)
		)
	)
	(zone
		(layer "In1.Cu")
		(hatch none 0.5)
		(connect_pads
			(clearance 0)
		)
		(min_thickness 0.25)
		(keepout
			(tracks not_allowed)
			(vias allowed)
			(pads allowed)
			(copperpour not_allowed)
			(footprints allowed)
		)
		(placement
			(enabled no)
			(sheetname "")
		)
		(fill
			(thermal_gap 0.5)
			(thermal_bridge_width 0.5)
			(island_removal_mode 0)
		)
		(polygon
			(pts
				(arc
					(start 304.017426 -224.782126)
					(mid 304.013706 -224.791106)
					(end 304.004726 -224.794826)
				)
				(arc
					(start 302.531526 -224.794826)
					(mid 302.522546 -224.791106)
					(end 302.518826 -224.782126)
				)
				(arc
					(start 302.518826 -224.287588)
					(mid 302.522546 -224.278608)
					(end 302.531526 -224.274888)
				)
				(arc
					(start 304.004726 -224.274888)
					(mid 304.013706 -224.278608)
					(end 304.017426 -224.287588)
				)
			)
		)
	)
	(zone
		(layer "In1.Cu")
		(hatch none 0.5)
		(connect_pads
			(clearance 0)
		)
		(min_thickness 0.25)
		(keepout
			(tracks not_allowed)
			(vias allowed)
			(pads allowed)
			(copperpour not_allowed)
			(footprints allowed)
		)
		(placement
			(enabled no)
			(sheetname "")
		)
		(fill
			(thermal_gap 0.5)
			(thermal_bridge_width 0.5)
			(island_removal_mode 0)
		)
		(polygon
			(pts
				(arc
					(start 388.090918 -391.822686)
					(mid 388.217918 -391.949686)
					(end 388.344918 -391.822686)
				)
				(arc
					(start 388.344918 -391.746486)
					(mid 388.217918 -391.619486)
					(end 388.090918 -391.746486)
				)
			)
		)
	)
	(zone
		(layer "In1.Cu")
		(hatch none 0.5)
		(connect_pads
			(clearance 0)
		)
		(min_thickness 0.25)
		(keepout
			(tracks not_allowed)
			(vias allowed)
			(pads allowed)
			(copperpour not_allowed)
			(footprints allowed)
		)
		(placement
			(enabled no)
			(sheetname "")
		)
		(fill
			(thermal_gap 0.5)
			(thermal_bridge_width 0.5)
			(island_removal_mode 0)
		)
		(polygon
			(pts
				(arc
					(start 308.990746 -399.701258)
					(mid 309.117746 -399.828258)
					(end 309.244746 -399.701258)
				)
				(arc
					(start 309.244746 -399.625058)
					(mid 309.117746 -399.498058)
					(end 308.990746 -399.625058)
				)
			)
		)
	)
	(zone
		(layer "In1.Cu")
		(hatch none 0.5)
		(connect_pads
			(clearance 0)
		)
		(min_thickness 0.25)
		(keepout
			(tracks not_allowed)
			(vias allowed)
			(pads allowed)
			(copperpour not_allowed)
			(footprints allowed)
		)
		(placement
			(enabled no)
			(sheetname "")
		)
		(fill
			(thermal_gap 0.5)
			(thermal_bridge_width 0.5)
			(island_removal_mode 0)
		)
		(polygon
			(pts
				(arc
					(start 48.533304 -246.882412)
					(mid 48.529584 -246.891392)
					(end 48.520604 -246.895112)
				)
				(arc
					(start 47.047404 -246.895112)
					(mid 47.038424 -246.891392)
					(end 47.034704 -246.882412)
				)
				(arc
					(start 47.034704 -246.387874)
					(mid 47.038424 -246.378894)
					(end 47.047404 -246.375174)
				)
				(arc
					(start 48.520604 -246.375174)
					(mid 48.529584 -246.378894)
					(end 48.533304 -246.387874)
				)
			)
		)
	)
	(zone
		(layer "In1.Cu")
		(hatch none 0.5)
		(connect_pads
			(clearance 0)
		)
		(min_thickness 0.25)
		(keepout
			(tracks not_allowed)
			(vias allowed)
			(pads allowed)
			(copperpour not_allowed)
			(footprints allowed)
		)
		(placement
			(enabled no)
			(sheetname "")
		)
		(fill
			(thermal_gap 0.5)
			(thermal_bridge_width 0.5)
			(island_removal_mode 0)
		)
		(polygon
			(pts
				(arc
					(start 161.598102 -383.92227)
					(mid 161.293302 -383.92227)
					(end 161.598102 -383.92227)
				)
			)
		)
	)
	(zone
		(layer "In1.Cu")
		(hatch none 0.5)
		(connect_pads
			(clearance 0)
		)
		(min_thickness 0.25)
		(keepout
			(tracks not_allowed)
			(vias allowed)
			(pads allowed)
			(copperpour not_allowed)
			(footprints allowed)
		)
		(placement
			(enabled no)
			(sheetname "")
		)
		(fill
			(thermal_gap 0.5)
			(thermal_bridge_width 0.5)
			(island_removal_mode 0)
		)
		(polygon
			(pts
				(arc
					(start 417.217352 -308.082188)
					(mid 417.213632 -308.091168)
					(end 417.204652 -308.094888)
				)
				(arc
					(start 415.731452 -308.094888)
					(mid 415.722472 -308.091168)
					(end 415.718752 -308.082188)
				)
				(arc
					(start 415.718752 -307.58765)
					(mid 415.722472 -307.57867)
					(end 415.731452 -307.57495)
				)
				(arc
					(start 417.204652 -307.57495)
					(mid 417.213632 -307.57867)
					(end 417.217352 -307.58765)
				)
			)
		)
	)
	(zone
		(layer "In1.Cu")
		(hatch none 0.5)
		(connect_pads
			(clearance 0)
		)
		(min_thickness 0.25)
		(keepout
			(tracks not_allowed)
			(vias allowed)
			(pads allowed)
			(copperpour not_allowed)
			(footprints allowed)
		)
		(placement
			(enabled no)
			(sheetname "")
		)
		(fill
			(thermal_gap 0.5)
			(thermal_bridge_width 0.5)
			(island_removal_mode 0)
		)
		(polygon
			(pts
				(arc
					(start 30.001464 -314.032392)
					(mid 29.997744 -314.041372)
					(end 29.988764 -314.045092)
				)
				(arc
					(start 28.515564 -314.045092)
					(mid 28.506584 -314.041372)
					(end 28.502864 -314.032392)
				)
				(arc
					(start 28.502864 -313.537854)
					(mid 28.506584 -313.528874)
					(end 28.515564 -313.525154)
				)
				(arc
					(start 29.988764 -313.525154)
					(mid 29.997744 -313.528874)
					(end 30.001464 -313.537854)
				)
			)
		)
	)
	(zone
		(layer "In1.Cu")
		(hatch none 0.5)
		(connect_pads
			(clearance 0)
		)
		(min_thickness 0.25)
		(keepout
			(tracks not_allowed)
			(vias allowed)
			(pads allowed)
			(copperpour not_allowed)
			(footprints allowed)
		)
		(placement
			(enabled no)
			(sheetname "")
		)
		(fill
			(thermal_gap 0.5)
			(thermal_bridge_width 0.5)
			(island_removal_mode 0)
		)
		(polygon
			(pts
				(arc
					(start 308.117494 -302.132238)
					(mid 308.113774 -302.141218)
					(end 308.104794 -302.144938)
				)
				(arc
					(start 306.631594 -302.144938)
					(mid 306.622614 -302.141218)
					(end 306.618894 -302.132238)
				)
				(arc
					(start 306.618894 -301.6377)
					(mid 306.622614 -301.62872)
					(end 306.631594 -301.625)
				)
				(arc
					(start 308.104794 -301.625)
					(mid 308.113774 -301.62872)
					(end 308.117494 -301.6377)
				)
			)
		)
	)
	(zone
		(layer "In1.Cu")
		(hatch none 0.5)
		(connect_pads
			(clearance 0)
		)
		(min_thickness 0.25)
		(keepout
			(tracks not_allowed)
			(vias allowed)
			(pads allowed)
			(copperpour not_allowed)
			(footprints allowed)
		)
		(placement
			(enabled no)
			(sheetname "")
		)
		(fill
			(thermal_gap 0.5)
			(thermal_bridge_width 0.5)
			(island_removal_mode 0)
		)
		(polygon
			(pts
				(arc
					(start 37.545264 -266.432538)
					(mid 37.541544 -266.441518)
					(end 37.532564 -266.445238)
				)
				(arc
					(start 36.059364 -266.445238)
					(mid 36.050384 -266.441518)
					(end 36.046664 -266.432538)
				)
				(arc
					(start 36.046664 -265.938)
					(mid 36.050384 -265.92902)
					(end 36.059364 -265.9253)
				)
				(arc
					(start 37.532564 -265.9253)
					(mid 37.541544 -265.92902)
					(end 37.545264 -265.938)
				)
			)
		)
	)
	(zone
		(layer "In1.Cu")
		(hatch none 0.5)
		(connect_pads
			(clearance 0)
		)
		(min_thickness 0.25)
		(keepout
			(tracks not_allowed)
			(vias allowed)
			(pads allowed)
			(copperpour not_allowed)
			(footprints allowed)
		)
		(placement
			(enabled no)
			(sheetname "")
		)
		(fill
			(thermal_gap 0.5)
			(thermal_bridge_width 0.5)
			(island_removal_mode 0)
		)
		(polygon
			(pts
				(arc
					(start 281.385264 -288.532316)
					(mid 281.381544 -288.541296)
					(end 281.372564 -288.545016)
				)
				(arc
					(start 279.899364 -288.545016)
					(mid 279.890384 -288.541296)
					(end 279.886664 -288.532316)
				)
				(arc
					(start 279.886664 -288.037778)
					(mid 279.890384 -288.028798)
					(end 279.899364 -288.025078)
				)
				(arc
					(start 281.372564 -288.025078)
					(mid 281.381544 -288.028798)
					(end 281.385264 -288.037778)
				)
			)
		)
	)
	(zone
		(layer "In1.Cu")
		(hatch none 0.5)
		(connect_pads
			(clearance 0)
		)
		(min_thickness 0.25)
		(keepout
			(tracks not_allowed)
			(vias allowed)
			(pads allowed)
			(copperpour not_allowed)
			(footprints allowed)
		)
		(placement
			(enabled no)
			(sheetname "")
		)
		(fill
			(thermal_gap 0.5)
			(thermal_bridge_width 0.5)
			(island_removal_mode 0)
		)
		(polygon
			(pts
				(arc
					(start 48.533304 -200.132442)
					(mid 48.529584 -200.141422)
					(end 48.520604 -200.145142)
				)
				(arc
					(start 47.047404 -200.145142)
					(mid 47.038424 -200.141422)
					(end 47.034704 -200.132442)
				)
				(arc
					(start 47.034704 -199.637904)
					(mid 47.038424 -199.628924)
					(end 47.047404 -199.625204)
				)
				(arc
					(start 48.520604 -199.625204)
					(mid 48.529584 -199.628924)
					(end 48.533304 -199.637904)
				)
			)
		)
	)
	(zone
		(layer "In1.Cu")
		(hatch none 0.5)
		(connect_pads
			(clearance 0)
		)
		(min_thickness 0.25)
		(keepout
			(tracks not_allowed)
			(vias allowed)
			(pads allowed)
			(copperpour not_allowed)
			(footprints allowed)
		)
		(placement
			(enabled no)
			(sheetname "")
		)
		(fill
			(thermal_gap 0.5)
			(thermal_bridge_width 0.5)
			(island_removal_mode 0)
		)
		(polygon
			(pts
				(arc
					(start 45.089318 -211.182458)
					(mid 45.085598 -211.191438)
					(end 45.076618 -211.195158)
				)
				(arc
					(start 43.603418 -211.195158)
					(mid 43.594438 -211.191438)
					(end 43.590718 -211.182458)
				)
				(arc
					(start 43.590718 -210.68792)
					(mid 43.594438 -210.67894)
					(end 43.603418 -210.67522)
				)
				(arc
					(start 45.076618 -210.67522)
					(mid 45.085598 -210.67894)
					(end 45.089318 -210.68792)
				)
			)
		)
	)
	(zone
		(layer "In1.Cu")
		(hatch none 0.5)
		(connect_pads
			(clearance 0)
		)
		(min_thickness 0.25)
		(keepout
			(tracks not_allowed)
			(vias allowed)
			(pads allowed)
			(copperpour not_allowed)
			(footprints allowed)
		)
		(placement
			(enabled no)
			(sheetname "")
		)
		(fill
			(thermal_gap 0.5)
			(thermal_bridge_width 0.5)
			(island_removal_mode 0)
		)
		(polygon
			(pts
				(arc
					(start 118.561104 -386.003292)
					(mid 118.180104 -386.003292)
					(end 118.561104 -386.003292)
				)
			)
		)
	)
	(zone
		(layer "In1.Cu")
		(hatch none 0.5)
		(connect_pads
			(clearance 0)
		)
		(min_thickness 0.25)
		(keepout
			(tracks not_allowed)
			(vias allowed)
			(pads allowed)
			(copperpour not_allowed)
			(footprints allowed)
		)
		(placement
			(enabled no)
			(sheetname "")
		)
		(fill
			(thermal_gap 0.5)
			(thermal_bridge_width 0.5)
			(island_removal_mode 0)
		)
		(polygon
			(pts
				(arc
					(start 40.98925 -211.182458)
					(mid 40.98553 -211.191438)
					(end 40.97655 -211.195158)
				)
				(arc
					(start 39.50335 -211.195158)
					(mid 39.49437 -211.191438)
					(end 39.49065 -211.182458)
				)
				(arc
					(start 39.49065 -210.68792)
					(mid 39.49437 -210.67894)
					(end 39.50335 -210.67522)
				)
				(arc
					(start 40.97655 -210.67522)
					(mid 40.98553 -210.67894)
					(end 40.98925 -210.68792)
				)
			)
		)
	)
	(zone
		(layer "In1.Cu")
		(hatch none 0.5)
		(connect_pads
			(clearance 0)
		)
		(min_thickness 0.25)
		(keepout
			(tracks not_allowed)
			(vias allowed)
			(pads allowed)
			(copperpour not_allowed)
			(footprints allowed)
		)
		(placement
			(enabled no)
			(sheetname "")
		)
		(fill
			(thermal_gap 0.5)
			(thermal_bridge_width 0.5)
			(island_removal_mode 0)
		)
		(polygon
			(pts
				(arc
					(start 180.265324 -243.482368)
					(mid 180.261604 -243.491348)
					(end 180.252624 -243.495068)
				)
				(arc
					(start 178.779424 -243.495068)
					(mid 178.770444 -243.491348)
					(end 178.766724 -243.482368)
				)
				(arc
					(start 178.766724 -242.98783)
					(mid 178.770444 -242.97885)
					(end 178.779424 -242.97513)
				)
				(arc
					(start 180.252624 -242.97513)
					(mid 180.261604 -242.97885)
					(end 180.265324 -242.98783)
				)
			)
		)
	)
	(zone
		(layer "In1.Cu")
		(hatch none 0.5)
		(connect_pads
			(clearance 0)
		)
		(min_thickness 0.25)
		(keepout
			(tracks not_allowed)
			(vias allowed)
			(pads allowed)
			(copperpour not_allowed)
			(footprints allowed)
		)
		(placement
			(enabled no)
			(sheetname "")
		)
		(fill
			(thermal_gap 0.5)
			(thermal_bridge_width 0.5)
			(island_removal_mode 0)
		)
		(polygon
			(pts
				(arc
					(start 18.357342 -308.93258)
					(mid 18.353622 -308.94156)
					(end 18.344642 -308.94528)
				)
				(arc
					(start 16.871442 -308.94528)
					(mid 16.862462 -308.94156)
					(end 16.858742 -308.93258)
				)
				(arc
					(start 16.858742 -308.438042)
					(mid 16.862462 -308.429062)
					(end 16.871442 -308.425342)
				)
				(arc
					(start 18.344642 -308.425342)
					(mid 18.353622 -308.429062)
					(end 18.357342 -308.438042)
				)
			)
		)
	)
	(zone
		(layer "In1.Cu")
		(hatch none 0.5)
		(connect_pads
			(clearance 0)
		)
		(min_thickness 0.25)
		(keepout
			(tracks not_allowed)
			(vias allowed)
			(pads allowed)
			(copperpour not_allowed)
			(footprints allowed)
		)
		(placement
			(enabled no)
			(sheetname "")
		)
		(fill
			(thermal_gap 0.5)
			(thermal_bridge_width 0.5)
			(island_removal_mode 0)
		)
		(polygon
			(pts
				(arc
					(start 435.749446 -308.932326)
					(mid 435.745726 -308.941306)
					(end 435.736746 -308.945026)
				)
				(arc
					(start 434.263546 -308.945026)
					(mid 434.254566 -308.941306)
					(end 434.250846 -308.932326)
				)
				(arc
					(start 434.250846 -308.437788)
					(mid 434.254566 -308.428808)
					(end 434.263546 -308.425088)
				)
				(arc
					(start 435.736746 -308.425088)
					(mid 435.745726 -308.428808)
					(end 435.749446 -308.437788)
				)
			)
		)
	)
	(zone
		(layer "In1.Cu")
		(hatch none 0.5)
		(connect_pads
			(clearance 0)
		)
		(min_thickness 0.25)
		(keepout
			(tracks not_allowed)
			(vias allowed)
			(pads allowed)
			(copperpour not_allowed)
			(footprints allowed)
		)
		(placement
			(enabled no)
			(sheetname "")
		)
		(fill
			(thermal_gap 0.5)
			(thermal_bridge_width 0.5)
			(island_removal_mode 0)
		)
		(polygon
			(pts
				(arc
					(start 18.357342 -301.282354)
					(mid 18.353622 -301.291334)
					(end 18.344642 -301.295054)
				)
				(arc
					(start 16.871442 -301.295054)
					(mid 16.862462 -301.291334)
					(end 16.858742 -301.282354)
				)
				(arc
					(start 16.858742 -300.787816)
					(mid 16.862462 -300.778836)
					(end 16.871442 -300.775116)
				)
				(arc
					(start 18.344642 -300.775116)
					(mid 18.353622 -300.778836)
					(end 18.357342 -300.787816)
				)
			)
		)
	)
	(zone
		(layer "In1.Cu")
		(hatch none 0.5)
		(connect_pads
			(clearance 0)
		)
		(min_thickness 0.25)
		(keepout
			(tracks not_allowed)
			(vias allowed)
			(pads allowed)
			(copperpour not_allowed)
			(footprints allowed)
		)
		(placement
			(enabled no)
			(sheetname "")
		)
		(fill
			(thermal_gap 0.5)
			(thermal_bridge_width 0.5)
			(island_removal_mode 0)
		)
		(polygon
			(pts
				(arc
					(start 25.901396 -265.5824)
					(mid 25.897676 -265.59138)
					(end 25.888696 -265.5951)
				)
				(arc
					(start 24.415496 -265.5951)
					(mid 24.406516 -265.59138)
					(end 24.402796 -265.5824)
				)
				(arc
					(start 24.402796 -265.087862)
					(mid 24.406516 -265.078882)
					(end 24.415496 -265.075162)
				)
				(arc
					(start 25.888696 -265.075162)
					(mid 25.897676 -265.078882)
					(end 25.901396 -265.087862)
				)
			)
		)
	)
	(zone
		(layer "In1.Cu")
		(hatch none 0.5)
		(connect_pads
			(clearance 0)
		)
		(min_thickness 0.25)
		(keepout
			(tracks not_allowed)
			(vias allowed)
			(pads allowed)
			(copperpour not_allowed)
			(footprints allowed)
		)
		(placement
			(enabled no)
			(sheetname "")
		)
		(fill
			(thermal_gap 0.5)
			(thermal_bridge_width 0.5)
			(island_removal_mode 0)
		)
		(polygon
			(pts
				(arc
					(start 169.277284 -246.032528)
					(mid 169.273564 -246.041508)
					(end 169.264584 -246.045228)
				)
				(arc
					(start 167.791384 -246.045228)
					(mid 167.782404 -246.041508)
					(end 167.778684 -246.032528)
				)
				(arc
					(start 167.778684 -245.53799)
					(mid 167.782404 -245.52901)
					(end 167.791384 -245.52529)
				)
				(arc
					(start 169.264584 -245.52529)
					(mid 169.273564 -245.52901)
					(end 169.277284 -245.53799)
				)
			)
		)
	)
	(zone
		(layer "In1.Cu")
		(hatch none 0.5)
		(connect_pads
			(clearance 0)
		)
		(min_thickness 0.25)
		(keepout
			(tracks not_allowed)
			(vias allowed)
			(pads allowed)
			(copperpour not_allowed)
			(footprints allowed)
		)
		(placement
			(enabled no)
			(sheetname "")
		)
		(fill
			(thermal_gap 0.5)
			(thermal_bridge_width 0.5)
			(island_removal_mode 0)
		)
		(polygon
			(pts
				(arc
					(start 273.841464 -207.78216)
					(mid 273.837744 -207.79114)
					(end 273.828764 -207.79486)
				)
				(arc
					(start 272.355564 -207.79486)
					(mid 272.346584 -207.79114)
					(end 272.342864 -207.78216)
				)
				(arc
					(start 272.342864 -207.287622)
					(mid 272.346584 -207.278642)
					(end 272.355564 -207.274922)
				)
				(arc
					(start 273.828764 -207.274922)
					(mid 273.837744 -207.278642)
					(end 273.841464 -207.287622)
				)
			)
		)
	)
	(zone
		(layer "In1.Cu")
		(hatch none 0.5)
		(connect_pads
			(clearance 0)
		)
		(min_thickness 0.25)
		(keepout
			(tracks not_allowed)
			(vias allowed)
			(pads allowed)
			(copperpour not_allowed)
			(footprints allowed)
		)
		(placement
			(enabled no)
			(sheetname "")
		)
		(fill
			(thermal_gap 0.5)
			(thermal_bridge_width 0.5)
			(island_removal_mode 0)
		)
		(polygon
			(pts
				(arc
					(start 60.177426 -289.382454)
					(mid 60.173706 -289.391434)
					(end 60.164726 -289.395154)
				)
				(arc
					(start 58.691526 -289.395154)
					(mid 58.682546 -289.391434)
					(end 58.678826 -289.382454)
				)
				(arc
					(start 58.678826 -288.887916)
					(mid 58.682546 -288.878936)
					(end 58.691526 -288.875216)
				)
				(arc
					(start 60.164726 -288.875216)
					(mid 60.173706 -288.878936)
					(end 60.177426 -288.887916)
				)
			)
		)
	)
	(zone
		(layer "In1.Cu")
		(hatch none 0.5)
		(connect_pads
			(clearance 0)
		)
		(min_thickness 0.25)
		(keepout
			(tracks not_allowed)
			(vias allowed)
			(pads allowed)
			(copperpour not_allowed)
			(footprints allowed)
		)
		(placement
			(enabled no)
			(sheetname "")
		)
		(fill
			(thermal_gap 0.5)
			(thermal_bridge_width 0.5)
			(island_removal_mode 0)
		)
		(polygon
			(pts
				(arc
					(start 413.117284 -240.082324)
					(mid 413.113564 -240.091304)
					(end 413.104584 -240.095024)
				)
				(arc
					(start 411.631384 -240.095024)
					(mid 411.622404 -240.091304)
					(end 411.618684 -240.082324)
				)
				(arc
					(start 411.618684 -239.587786)
					(mid 411.622404 -239.578806)
					(end 411.631384 -239.575086)
				)
				(arc
					(start 413.104584 -239.575086)
					(mid 413.113564 -239.578806)
					(end 413.117284 -239.587786)
				)
			)
		)
	)
	(zone
		(layer "In1.Cu")
		(hatch none 0.5)
		(connect_pads
			(clearance 0)
		)
		(min_thickness 0.25)
		(keepout
			(tracks not_allowed)
			(vias allowed)
			(pads allowed)
			(copperpour not_allowed)
			(footprints allowed)
		)
		(placement
			(enabled no)
			(sheetname "")
		)
		(fill
			(thermal_gap 0.5)
			(thermal_bridge_width 0.5)
			(island_removal_mode 0)
		)
		(polygon
			(pts
				(arc
					(start 273.841464 -295.33215)
					(mid 273.837744 -295.34113)
					(end 273.828764 -295.34485)
				)
				(arc
					(start 272.355564 -295.34485)
					(mid 272.346584 -295.34113)
					(end 272.342864 -295.33215)
				)
				(arc
					(start 272.342864 -294.837612)
					(mid 272.346584 -294.828632)
					(end 272.355564 -294.824912)
				)
				(arc
					(start 273.828764 -294.824912)
					(mid 273.837744 -294.828632)
					(end 273.841464 -294.837612)
				)
			)
		)
	)
	(zone
		(layer "In1.Cu")
		(hatch none 0.5)
		(connect_pads
			(clearance 0)
		)
		(min_thickness 0.25)
		(keepout
			(tracks not_allowed)
			(vias allowed)
			(pads allowed)
			(copperpour not_allowed)
			(footprints allowed)
		)
		(placement
			(enabled no)
			(sheetname "")
		)
		(fill
			(thermal_gap 0.5)
			(thermal_bridge_width 0.5)
			(island_removal_mode 0)
		)
		(polygon
			(pts
				(arc
					(start 325.334376 -388.647178)
					(mid 325.32514 -388.667102)
					(end 325.32193 -388.688834)
				)
				(arc
					(start 325.32193 -388.883398)
					(mid 325.344248 -388.93728)
					(end 325.39813 -388.959598)
				)
				(arc
					(start 326.08393 -388.959598)
					(mid 326.137812 -388.93728)
					(end 326.16013 -388.883398)
				)
				(arc
					(start 326.16013 -388.688834)
					(mid 326.156962 -388.66709)
					(end 326.147684 -388.647178)
				)
				(arc
					(start 325.954898 -388.351014)
					(mid 325.942676 -388.30933)
					(end 325.955152 -388.267702)
				)
				(arc
					(start 326.147684 -387.974078)
					(mid 326.15692 -387.954154)
					(end 326.16013 -387.932422)
				)
				(arc
					(start 326.16013 -387.737858)
					(mid 326.137812 -387.683976)
					(end 326.08393 -387.661658)
				)
				(arc
					(start 325.39813 -387.661658)
					(mid 325.344248 -387.683976)
					(end 325.32193 -387.737858)
				)
				(arc
					(start 325.32193 -387.933692)
					(mid 325.325098 -387.955436)
					(end 325.334376 -387.975348)
				)
				(arc
					(start 325.526908 -388.268972)
					(mid 325.53931 -388.310628)
					(end 325.526908 -388.352284)
				)
			)
		)
	)
	(zone
		(layer "In1.Cu")
		(hatch none 0.5)
		(connect_pads
			(clearance 0)
		)
		(min_thickness 0.25)
		(keepout
			(tracks not_allowed)
			(vias allowed)
			(pads allowed)
			(copperpour not_allowed)
			(footprints allowed)
		)
		(placement
			(enabled no)
			(sheetname "")
		)
		(fill
			(thermal_gap 0.5)
			(thermal_bridge_width 0.5)
			(island_removal_mode 0)
		)
		(polygon
			(pts
				(arc
					(start 439.849514 -229.032308)
					(mid 439.845794 -229.041288)
					(end 439.836814 -229.045008)
				)
				(arc
					(start 438.363614 -229.045008)
					(mid 438.354634 -229.041288)
					(end 438.350914 -229.032308)
				)
				(arc
					(start 438.350914 -228.53777)
					(mid 438.354634 -228.52879)
					(end 438.363614 -228.52507)
				)
				(arc
					(start 439.836814 -228.52507)
					(mid 439.845794 -228.52879)
					(end 439.849514 -228.53777)
				)
			)
		)
	)
	(zone
		(layer "In1.Cu")
		(hatch none 0.5)
		(connect_pads
			(clearance 0)
		)
		(min_thickness 0.25)
		(keepout
			(tracks not_allowed)
			(vias allowed)
			(pads allowed)
			(copperpour not_allowed)
			(footprints allowed)
		)
		(placement
			(enabled no)
			(sheetname "")
		)
		(fill
			(thermal_gap 0.5)
			(thermal_bridge_width 0.5)
			(island_removal_mode 0)
		)
		(polygon
			(pts
				(arc
					(start 270.397478 -311.482232)
					(mid 270.393758 -311.491212)
					(end 270.384778 -311.494932)
				)
				(arc
					(start 268.911578 -311.494932)
					(mid 268.902598 -311.491212)
					(end 268.898878 -311.482232)
				)
				(arc
					(start 268.898878 -310.987694)
					(mid 268.902598 -310.978714)
					(end 268.911578 -310.974994)
				)
				(arc
					(start 270.384778 -310.974994)
					(mid 270.393758 -310.978714)
					(end 270.397478 -310.987694)
				)
			)
		)
	)
	(zone
		(layer "In1.Cu")
		(hatch none 0.5)
		(connect_pads
			(clearance 0)
		)
		(min_thickness 0.25)
		(keepout
			(tracks not_allowed)
			(vias allowed)
			(pads allowed)
			(copperpour not_allowed)
			(footprints allowed)
		)
		(placement
			(enabled no)
			(sheetname "")
		)
		(fill
			(thermal_gap 0.5)
			(thermal_bridge_width 0.5)
			(island_removal_mode 0)
		)
		(polygon
			(pts
				(arc
					(start 353.51847 -399.701258)
					(mid 353.64547 -399.828258)
					(end 353.77247 -399.701258)
				)
				(arc
					(start 353.77247 -399.625058)
					(mid 353.64547 -399.498058)
					(end 353.51847 -399.625058)
				)
			)
		)
	)
	(zone
		(layer "In1.Cu")
		(hatch none 0.5)
		(connect_pads
			(clearance 0)
		)
		(min_thickness 0.25)
		(keepout
			(tracks not_allowed)
			(vias allowed)
			(pads allowed)
			(copperpour not_allowed)
			(footprints allowed)
		)
		(placement
			(enabled no)
			(sheetname "")
		)
		(fill
			(thermal_gap 0.5)
			(thermal_bridge_width 0.5)
			(island_removal_mode 0)
		)
		(polygon
			(pts
				(arc
					(start 296.473372 -268.98219)
					(mid 296.469652 -268.99117)
					(end 296.460672 -268.99489)
				)
				(arc
					(start 294.987472 -268.99489)
					(mid 294.978492 -268.99117)
					(end 294.974772 -268.98219)
				)
				(arc
					(start 294.974772 -268.487652)
					(mid 294.978492 -268.478672)
					(end 294.987472 -268.474952)
				)
				(arc
					(start 296.460672 -268.474952)
					(mid 296.469652 -268.478672)
					(end 296.473372 -268.487652)
				)
			)
		)
	)
	(zone
		(layer "In1.Cu")
		(hatch none 0.5)
		(connect_pads
			(clearance 0)
		)
		(min_thickness 0.25)
		(keepout
			(tracks not_allowed)
			(vias allowed)
			(pads allowed)
			(copperpour not_allowed)
			(footprints allowed)
		)
		(placement
			(enabled no)
			(sheetname "")
		)
		(fill
			(thermal_gap 0.5)
			(thermal_bridge_width 0.5)
			(island_removal_mode 0)
		)
		(polygon
			(pts
				(arc
					(start 447.393568 -309.78221)
					(mid 447.389848 -309.79119)
					(end 447.380868 -309.79491)
				)
				(arc
					(start 445.907668 -309.79491)
					(mid 445.898688 -309.79119)
					(end 445.894968 -309.78221)
				)
				(arc
					(start 445.894968 -309.287672)
					(mid 445.898688 -309.278692)
					(end 445.907668 -309.274972)
				)
				(arc
					(start 447.380868 -309.274972)
					(mid 447.389848 -309.278692)
					(end 447.393568 -309.287672)
				)
			)
		)
	)
	(zone
		(layer "In1.Cu")
		(hatch none 0.5)
		(connect_pads
			(clearance 0)
		)
		(min_thickness 0.25)
		(keepout
			(tracks not_allowed)
			(vias allowed)
			(pads allowed)
			(copperpour not_allowed)
			(footprints allowed)
		)
		(placement
			(enabled no)
			(sheetname "")
		)
		(fill
			(thermal_gap 0.5)
			(thermal_bridge_width 0.5)
			(island_removal_mode 0)
		)
		(polygon
			(pts
				(arc
					(start 37.545264 -214.582502)
					(mid 37.541544 -214.591482)
					(end 37.532564 -214.595202)
				)
				(arc
					(start 36.059364 -214.595202)
					(mid 36.050384 -214.591482)
					(end 36.046664 -214.582502)
				)
				(arc
					(start 36.046664 -214.087964)
					(mid 36.050384 -214.078984)
					(end 36.059364 -214.075264)
				)
				(arc
					(start 37.532564 -214.075264)
					(mid 37.541544 -214.078984)
					(end 37.545264 -214.087964)
				)
			)
		)
	)
	(zone
		(layer "In1.Cu")
		(hatch none 0.5)
		(connect_pads
			(clearance 0)
		)
		(min_thickness 0.25)
		(keepout
			(tracks not_allowed)
			(vias allowed)
			(pads allowed)
			(copperpour not_allowed)
			(footprints allowed)
		)
		(placement
			(enabled no)
			(sheetname "")
		)
		(fill
			(thermal_gap 0.5)
			(thermal_bridge_width 0.5)
			(island_removal_mode 0)
		)
		(polygon
			(pts
				(arc
					(start 428.205392 -204.382116)
					(mid 428.201672 -204.391096)
					(end 428.192692 -204.394816)
				)
				(arc
					(start 426.719492 -204.394816)
					(mid 426.710512 -204.391096)
					(end 426.706792 -204.382116)
				)
				(arc
					(start 426.706792 -203.887578)
					(mid 426.710512 -203.878598)
					(end 426.719492 -203.874878)
				)
				(arc
					(start 428.192692 -203.874878)
					(mid 428.201672 -203.878598)
					(end 428.205392 -203.887578)
				)
			)
		)
	)
	(zone
		(layer "In1.Cu")
		(hatch none 0.5)
		(connect_pads
			(clearance 0)
		)
		(min_thickness 0.25)
		(keepout
			(tracks not_allowed)
			(vias allowed)
			(pads allowed)
			(copperpour not_allowed)
			(footprints allowed)
		)
		(placement
			(enabled no)
			(sheetname "")
		)
		(fill
			(thermal_gap 0.5)
			(thermal_bridge_width 0.5)
			(island_removal_mode 0)
		)
		(polygon
			(pts
				(arc
					(start 22.45741 -300.43247)
					(mid 22.45369 -300.44145)
					(end 22.44471 -300.44517)
				)
				(arc
					(start 20.97151 -300.44517)
					(mid 20.96253 -300.44145)
					(end 20.95881 -300.43247)
				)
				(arc
					(start 20.95881 -299.937932)
					(mid 20.96253 -299.928952)
					(end 20.97151 -299.925232)
				)
				(arc
					(start 22.44471 -299.925232)
					(mid 22.45369 -299.928952)
					(end 22.45741 -299.937932)
				)
			)
		)
	)
	(zone
		(layer "In1.Cu")
		(hatch none 0.5)
		(connect_pads
			(clearance 0)
		)
		(min_thickness 0.25)
		(keepout
			(tracks not_allowed)
			(vias allowed)
			(pads allowed)
			(copperpour not_allowed)
			(footprints allowed)
		)
		(placement
			(enabled no)
			(sheetname "")
		)
		(fill
			(thermal_gap 0.5)
			(thermal_bridge_width 0.5)
			(island_removal_mode 0)
		)
		(polygon
			(pts
				(arc
					(start 37.545264 -302.132492)
					(mid 37.541544 -302.141472)
					(end 37.532564 -302.145192)
				)
				(arc
					(start 36.059364 -302.145192)
					(mid 36.050384 -302.141472)
					(end 36.046664 -302.132492)
				)
				(arc
					(start 36.046664 -301.637954)
					(mid 36.050384 -301.628974)
					(end 36.059364 -301.625254)
				)
				(arc
					(start 37.532564 -301.625254)
					(mid 37.541544 -301.628974)
					(end 37.545264 -301.637954)
				)
			)
		)
	)
	(zone
		(layer "In1.Cu")
		(hatch none 0.5)
		(connect_pads
			(clearance 0)
		)
		(min_thickness 0.25)
		(keepout
			(tracks not_allowed)
			(vias allowed)
			(pads allowed)
			(copperpour not_allowed)
			(footprints allowed)
		)
		(placement
			(enabled no)
			(sheetname "")
		)
		(fill
			(thermal_gap 0.5)
			(thermal_bridge_width 0.5)
			(island_removal_mode 0)
		)
		(polygon
			(pts
				(arc
					(start 384.16103 -397.849344)
					(mid 383.78003 -397.849344)
					(end 384.16103 -397.849344)
				)
			)
		)
	)
	(zone
		(layer "In1.Cu")
		(hatch none 0.5)
		(connect_pads
			(clearance 0)
		)
		(min_thickness 0.25)
		(keepout
			(tracks not_allowed)
			(vias allowed)
			(pads allowed)
			(copperpour not_allowed)
			(footprints allowed)
		)
		(placement
			(enabled no)
			(sheetname "")
		)
		(fill
			(thermal_gap 0.5)
			(thermal_bridge_width 0.5)
			(island_removal_mode 0)
		)
		(polygon
			(pts
				(arc
					(start 144.10944 -32.13989)
					(mid 144.131758 -32.193772)
					(end 144.18564 -32.21609)
				)
				(arc
					(start 144.54124 -32.21609)
					(mid 144.595122 -32.193772)
					(end 144.61744 -32.13989)
				)
				(arc
					(start 144.61744 -30.23489)
					(mid 144.595122 -30.181008)
					(end 144.54124 -30.15869)
				)
				(arc
					(start 144.18564 -30.15869)
					(mid 144.131758 -30.181008)
					(end 144.10944 -30.23489)
				)
			)
		)
	)
	(zone
		(layer "In1.Cu")
		(hatch none 0.5)
		(connect_pads
			(clearance 0)
		)
		(min_thickness 0.25)
		(keepout
			(tracks not_allowed)
			(vias allowed)
			(pads allowed)
			(copperpour not_allowed)
			(footprints allowed)
		)
		(placement
			(enabled no)
			(sheetname "")
		)
		(fill
			(thermal_gap 0.5)
			(thermal_bridge_width 0.5)
			(island_removal_mode 0)
		)
		(polygon
			(pts
				(arc
					(start 169.277284 -197.582536)
					(mid 169.273564 -197.591516)
					(end 169.264584 -197.595236)
				)
				(arc
					(start 167.791384 -197.595236)
					(mid 167.782404 -197.591516)
					(end 167.778684 -197.582536)
				)
				(arc
					(start 167.778684 -197.087998)
					(mid 167.782404 -197.079018)
					(end 167.791384 -197.075298)
				)
				(arc
					(start 169.264584 -197.075298)
					(mid 169.273564 -197.079018)
					(end 169.277284 -197.087998)
				)
			)
		)
	)
	(zone
		(layer "In1.Cu")
		(hatch none 0.5)
		(connect_pads
			(clearance 0)
		)
		(min_thickness 0.25)
		(keepout
			(tracks not_allowed)
			(vias allowed)
			(pads allowed)
			(copperpour not_allowed)
			(footprints allowed)
		)
		(placement
			(enabled no)
			(sheetname "")
		)
		(fill
			(thermal_gap 0.5)
			(thermal_bridge_width 0.5)
			(island_removal_mode 0)
		)
		(polygon
			(pts
				(arc
					(start 60.177426 -272.382488)
					(mid 60.173706 -272.391468)
					(end 60.164726 -272.395188)
				)
				(arc
					(start 58.691526 -272.395188)
					(mid 58.682546 -272.391468)
					(end 58.678826 -272.382488)
				)
				(arc
					(start 58.678826 -271.88795)
					(mid 58.682546 -271.87897)
					(end 58.691526 -271.87525)
				)
				(arc
					(start 60.164726 -271.87525)
					(mid 60.173706 -271.87897)
					(end 60.177426 -271.88795)
				)
			)
		)
	)
	(zone
		(layer "In1.Cu")
		(hatch none 0.5)
		(connect_pads
			(clearance 0)
		)
		(min_thickness 0.25)
		(keepout
			(tracks not_allowed)
			(vias allowed)
			(pads allowed)
			(copperpour not_allowed)
			(footprints allowed)
		)
		(placement
			(enabled no)
			(sheetname "")
		)
		(fill
			(thermal_gap 0.5)
			(thermal_bridge_width 0.5)
			(island_removal_mode 0)
		)
		(polygon
			(pts
				(arc
					(start 37.545264 -219.682568)
					(mid 37.541544 -219.691548)
					(end 37.532564 -219.695268)
				)
				(arc
					(start 36.059364 -219.695268)
					(mid 36.050384 -219.691548)
					(end 36.046664 -219.682568)
				)
				(arc
					(start 36.046664 -219.18803)
					(mid 36.050384 -219.17905)
					(end 36.059364 -219.17533)
				)
				(arc
					(start 37.532564 -219.17533)
					(mid 37.541544 -219.17905)
					(end 37.545264 -219.18803)
				)
			)
		)
	)
	(zone
		(layer "In1.Cu")
		(hatch none 0.5)
		(connect_pads
			(clearance 0)
		)
		(min_thickness 0.25)
		(keepout
			(tracks not_allowed)
			(vias allowed)
			(pads allowed)
			(copperpour not_allowed)
			(footprints allowed)
		)
		(placement
			(enabled no)
			(sheetname "")
		)
		(fill
			(thermal_gap 0.5)
			(thermal_bridge_width 0.5)
			(island_removal_mode 0)
		)
		(polygon
			(pts
				(arc
					(start 165.177216 -209.482436)
					(mid 165.173496 -209.491416)
					(end 165.164516 -209.495136)
				)
				(arc
					(start 163.691316 -209.495136)
					(mid 163.682336 -209.491416)
					(end 163.678616 -209.482436)
				)
				(arc
					(start 163.678616 -208.987898)
					(mid 163.682336 -208.978918)
					(end 163.691316 -208.975198)
				)
				(arc
					(start 165.164516 -208.975198)
					(mid 165.173496 -208.978918)
					(end 165.177216 -208.987898)
				)
			)
		)
	)
	(zone
		(layer "In1.Cu")
		(hatch none 0.5)
		(connect_pads
			(clearance 0)
		)
		(min_thickness 0.25)
		(keepout
			(tracks not_allowed)
			(vias allowed)
			(pads allowed)
			(copperpour not_allowed)
			(footprints allowed)
		)
		(placement
			(enabled no)
			(sheetname "")
		)
		(fill
			(thermal_gap 0.5)
			(thermal_bridge_width 0.5)
			(island_removal_mode 0)
		)
		(polygon
			(pts
				(arc
					(start 310.66105 -393.69238)
					(mid 310.28005 -393.69238)
					(end 310.66105 -393.69238)
				)
			)
		)
	)
	(zone
		(layer "In1.Cu")
		(hatch none 0.5)
		(connect_pads
			(clearance 0)
		)
		(min_thickness 0.25)
		(keepout
			(tracks not_allowed)
			(vias allowed)
			(pads allowed)
			(copperpour not_allowed)
			(footprints allowed)
		)
		(placement
			(enabled no)
			(sheetname "")
		)
		(fill
			(thermal_gap 0.5)
			(thermal_bridge_width 0.5)
			(island_removal_mode 0)
		)
		(polygon
			(pts
				(arc
					(start 64.370458 -390.761474)
					(mid 64.065658 -390.761474)
					(end 64.370458 -390.761474)
				)
			)
		)
	)
	(zone
		(layer "In1.Cu")
		(hatch none 0.5)
		(connect_pads
			(clearance 0)
		)
		(min_thickness 0.25)
		(keepout
			(tracks not_allowed)
			(vias allowed)
			(pads allowed)
			(copperpour not_allowed)
			(footprints allowed)
		)
		(placement
			(enabled no)
			(sheetname "")
		)
		(fill
			(thermal_gap 0.5)
			(thermal_bridge_width 0.5)
			(island_removal_mode 0)
		)
		(polygon
			(pts
				(arc
					(start 56.077358 -265.5824)
					(mid 56.073638 -265.59138)
					(end 56.064658 -265.5951)
				)
				(arc
					(start 54.591458 -265.5951)
					(mid 54.582478 -265.59138)
					(end 54.578758 -265.5824)
				)
				(arc
					(start 54.578758 -265.087862)
					(mid 54.582478 -265.078882)
					(end 54.591458 -265.075162)
				)
				(arc
					(start 56.064658 -265.075162)
					(mid 56.073638 -265.078882)
					(end 56.077358 -265.087862)
				)
			)
		)
	)
	(zone
		(layer "In1.Cu")
		(hatch none 0.5)
		(connect_pads
			(clearance 0)
		)
		(min_thickness 0.25)
		(keepout
			(tracks not_allowed)
			(vias allowed)
			(pads allowed)
			(copperpour not_allowed)
			(footprints allowed)
		)
		(placement
			(enabled no)
			(sheetname "")
		)
		(fill
			(thermal_gap 0.5)
			(thermal_bridge_width 0.5)
			(island_removal_mode 0)
		)
		(polygon
			(pts
				(arc
					(start 165.177216 -223.082358)
					(mid 165.173496 -223.091338)
					(end 165.164516 -223.095058)
				)
				(arc
					(start 163.691316 -223.095058)
					(mid 163.682336 -223.091338)
					(end 163.678616 -223.082358)
				)
				(arc
					(start 163.678616 -222.58782)
					(mid 163.682336 -222.57884)
					(end 163.691316 -222.57512)
				)
				(arc
					(start 165.164516 -222.57512)
					(mid 165.173496 -222.57884)
					(end 165.177216 -222.58782)
				)
			)
		)
	)
	(zone
		(layer "In1.Cu")
		(hatch none 0.5)
		(connect_pads
			(clearance 0)
		)
		(min_thickness 0.25)
		(keepout
			(tracks not_allowed)
			(vias allowed)
			(pads allowed)
			(copperpour not_allowed)
			(footprints allowed)
		)
		(placement
			(enabled no)
			(sheetname "")
		)
		(fill
			(thermal_gap 0.5)
			(thermal_bridge_width 0.5)
			(island_removal_mode 0)
		)
		(polygon
			(pts
				(arc
					(start 37.545264 -199.282558)
					(mid 37.541544 -199.291538)
					(end 37.532564 -199.295258)
				)
				(arc
					(start 36.059364 -199.295258)
					(mid 36.050384 -199.291538)
					(end 36.046664 -199.282558)
				)
				(arc
					(start 36.046664 -198.78802)
					(mid 36.050384 -198.77904)
					(end 36.059364 -198.77532)
				)
				(arc
					(start 37.532564 -198.77532)
					(mid 37.541544 -198.77904)
					(end 37.545264 -198.78802)
				)
			)
		)
	)
	(zone
		(layer "In1.Cu")
		(hatch none 0.5)
		(connect_pads
			(clearance 0)
		)
		(min_thickness 0.25)
		(keepout
			(tracks not_allowed)
			(vias allowed)
			(pads allowed)
			(copperpour not_allowed)
			(footprints allowed)
		)
		(placement
			(enabled no)
			(sheetname "")
		)
		(fill
			(thermal_gap 0.5)
			(thermal_bridge_width 0.5)
			(island_removal_mode 0)
		)
		(polygon
			(pts
				(arc
					(start 60.177426 -306.38242)
					(mid 60.173706 -306.3914)
					(end 60.164726 -306.39512)
				)
				(arc
					(start 58.691526 -306.39512)
					(mid 58.682546 -306.3914)
					(end 58.678826 -306.38242)
				)
				(arc
					(start 58.678826 -305.887882)
					(mid 58.682546 -305.878902)
					(end 58.691526 -305.875182)
				)
				(arc
					(start 60.164726 -305.875182)
					(mid 60.173706 -305.878902)
					(end 60.177426 -305.887882)
				)
			)
		)
	)
	(zone
		(layer "In1.Cu")
		(hatch none 0.5)
		(connect_pads
			(clearance 0)
		)
		(min_thickness 0.25)
		(keepout
			(tracks not_allowed)
			(vias allowed)
			(pads allowed)
			(copperpour not_allowed)
			(footprints allowed)
		)
		(placement
			(enabled no)
			(sheetname "")
		)
		(fill
			(thermal_gap 0.5)
			(thermal_bridge_width 0.5)
			(island_removal_mode 0)
		)
		(polygon
			(pts
				(arc
					(start 277.941532 -285.982156)
					(mid 277.937812 -285.991136)
					(end 277.928832 -285.994856)
				)
				(arc
					(start 276.455632 -285.994856)
					(mid 276.446652 -285.991136)
					(end 276.442932 -285.982156)
				)
				(arc
					(start 276.442932 -285.487618)
					(mid 276.446652 -285.478638)
					(end 276.455632 -285.474918)
				)
				(arc
					(start 277.928832 -285.474918)
					(mid 277.937812 -285.478638)
					(end 277.941532 -285.487618)
				)
			)
		)
	)
	(zone
		(layer "In1.Cu")
		(hatch none 0.5)
		(connect_pads
			(clearance 0)
		)
		(min_thickness 0.25)
		(keepout
			(tracks not_allowed)
			(vias allowed)
			(pads allowed)
			(copperpour not_allowed)
			(footprints allowed)
		)
		(placement
			(enabled no)
			(sheetname "")
		)
		(fill
			(thermal_gap 0.5)
			(thermal_bridge_width 0.5)
			(island_removal_mode 0)
		)
		(polygon
			(pts
				(arc
					(start 439.849514 -261.332218)
					(mid 439.845794 -261.341198)
					(end 439.836814 -261.344918)
				)
				(arc
					(start 438.363614 -261.344918)
					(mid 438.354634 -261.341198)
					(end 438.350914 -261.332218)
				)
				(arc
					(start 438.350914 -260.83768)
					(mid 438.354634 -260.8287)
					(end 438.363614 -260.82498)
				)
				(arc
					(start 439.836814 -260.82498)
					(mid 439.845794 -260.8287)
					(end 439.849514 -260.83768)
				)
			)
		)
	)
	(zone
		(layer "In1.Cu")
		(hatch none 0.5)
		(connect_pads
			(clearance 0)
		)
		(min_thickness 0.25)
		(keepout
			(tracks not_allowed)
			(vias allowed)
			(pads allowed)
			(copperpour not_allowed)
			(footprints allowed)
		)
		(placement
			(enabled no)
			(sheetname "")
		)
		(fill
			(thermal_gap 0.5)
			(thermal_bridge_width 0.5)
			(island_removal_mode 0)
		)
		(polygon
			(pts
				(arc
					(start 350.497902 -392.30427)
					(mid 350.193102 -392.30427)
					(end 350.497902 -392.30427)
				)
			)
		)
	)
	(zone
		(layer "In1.Cu")
		(hatch none 0.5)
		(connect_pads
			(clearance 0)
		)
		(min_thickness 0.25)
		(keepout
			(tracks not_allowed)
			(vias allowed)
			(pads allowed)
			(copperpour not_allowed)
			(footprints allowed)
		)
		(placement
			(enabled no)
			(sheetname "")
		)
		(fill
			(thermal_gap 0.5)
			(thermal_bridge_width 0.5)
			(island_removal_mode 0)
		)
		(polygon
			(pts
				(arc
					(start 176.821338 -315.732414)
					(mid 176.817618 -315.741394)
					(end 176.808638 -315.745114)
				)
				(arc
					(start 175.335438 -315.745114)
					(mid 175.326458 -315.741394)
					(end 175.322738 -315.732414)
				)
				(arc
					(start 175.322738 -315.237876)
					(mid 175.326458 -315.228896)
					(end 175.335438 -315.225176)
				)
				(arc
					(start 176.808638 -315.225176)
					(mid 176.817618 -315.228896)
					(end 176.821338 -315.237876)
				)
			)
		)
	)
	(zone
		(layer "In1.Cu")
		(hatch none 0.5)
		(connect_pads
			(clearance 0)
		)
		(min_thickness 0.25)
		(keepout
			(tracks not_allowed)
			(vias allowed)
			(pads allowed)
			(copperpour not_allowed)
			(footprints allowed)
		)
		(placement
			(enabled no)
			(sheetname "")
		)
		(fill
			(thermal_gap 0.5)
			(thermal_bridge_width 0.5)
			(island_removal_mode 0)
		)
		(polygon
			(pts
				(arc
					(start 447.393568 -216.28227)
					(mid 447.389848 -216.29125)
					(end 447.380868 -216.29497)
				)
				(arc
					(start 445.907668 -216.29497)
					(mid 445.898688 -216.29125)
					(end 445.894968 -216.28227)
				)
				(arc
					(start 445.894968 -215.787732)
					(mid 445.898688 -215.778752)
					(end 445.907668 -215.775032)
				)
				(arc
					(start 447.380868 -215.775032)
					(mid 447.389848 -215.778752)
					(end 447.393568 -215.787732)
				)
			)
		)
	)
	(zone
		(layer "In1.Cu")
		(hatch none 0.5)
		(connect_pads
			(clearance 0)
		)
		(min_thickness 0.25)
		(keepout
			(tracks not_allowed)
			(vias allowed)
			(pads allowed)
			(copperpour not_allowed)
			(footprints allowed)
		)
		(placement
			(enabled no)
			(sheetname "")
		)
		(fill
			(thermal_gap 0.5)
			(thermal_bridge_width 0.5)
			(island_removal_mode 0)
		)
		(polygon
			(pts
				(arc
					(start 169.277284 -261.332472)
					(mid 169.273564 -261.341452)
					(end 169.264584 -261.345172)
				)
				(arc
					(start 167.791384 -261.345172)
					(mid 167.782404 -261.341452)
					(end 167.778684 -261.332472)
				)
				(arc
					(start 167.778684 -260.837934)
					(mid 167.782404 -260.828954)
					(end 167.791384 -260.825234)
				)
				(arc
					(start 169.264584 -260.825234)
					(mid 169.273564 -260.828954)
					(end 169.277284 -260.837934)
				)
			)
		)
	)
	(zone
		(layer "In1.Cu")
		(hatch none 0.5)
		(connect_pads
			(clearance 0)
		)
		(min_thickness 0.25)
		(keepout
			(tracks not_allowed)
			(vias allowed)
			(pads allowed)
			(copperpour not_allowed)
			(footprints allowed)
		)
		(placement
			(enabled no)
			(sheetname "")
		)
		(fill
			(thermal_gap 0.5)
			(thermal_bridge_width 0.5)
			(island_removal_mode 0)
		)
		(polygon
			(pts
				(arc
					(start 165.177216 -241.782346)
					(mid 165.173496 -241.791326)
					(end 165.164516 -241.795046)
				)
				(arc
					(start 163.691316 -241.795046)
					(mid 163.682336 -241.791326)
					(end 163.678616 -241.782346)
				)
				(arc
					(start 163.678616 -241.287808)
					(mid 163.682336 -241.278828)
					(end 163.691316 -241.275108)
				)
				(arc
					(start 165.164516 -241.275108)
					(mid 165.173496 -241.278828)
					(end 165.177216 -241.287808)
				)
			)
		)
	)
	(zone
		(layer "In1.Cu")
		(hatch none 0.5)
		(connect_pads
			(clearance 0)
		)
		(min_thickness 0.25)
		(keepout
			(tracks not_allowed)
			(vias allowed)
			(pads allowed)
			(copperpour not_allowed)
			(footprints allowed)
		)
		(placement
			(enabled no)
			(sheetname "")
		)
		(fill
			(thermal_gap 0.5)
			(thermal_bridge_width 0.5)
			(island_removal_mode 0)
		)
		(polygon
			(pts
				(arc
					(start 386.270246 -392.30427)
					(mid 385.965446 -392.30427)
					(end 386.270246 -392.30427)
				)
			)
		)
	)
	(zone
		(layer "In1.Cu")
		(hatch none 0.5)
		(connect_pads
			(clearance 0)
		)
		(min_thickness 0.25)
		(keepout
			(tracks not_allowed)
			(vias allowed)
			(pads allowed)
			(copperpour not_allowed)
			(footprints allowed)
		)
		(placement
			(enabled no)
			(sheetname "")
		)
		(fill
			(thermal_gap 0.5)
			(thermal_bridge_width 0.5)
			(island_removal_mode 0)
		)
		(polygon
			(pts
				(arc
					(start 56.077358 -288.53257)
					(mid 56.073638 -288.54155)
					(end 56.064658 -288.54527)
				)
				(arc
					(start 54.591458 -288.54527)
					(mid 54.582478 -288.54155)
					(end 54.578758 -288.53257)
				)
				(arc
					(start 54.578758 -288.038032)
					(mid 54.582478 -288.029052)
					(end 54.591458 -288.025332)
				)
				(arc
					(start 56.064658 -288.025332)
					(mid 56.073638 -288.029052)
					(end 56.077358 -288.038032)
				)
			)
		)
	)
	(zone
		(layer "In1.Cu")
		(hatch none 0.5)
		(connect_pads
			(clearance 0)
		)
		(min_thickness 0.25)
		(keepout
			(tracks not_allowed)
			(vias allowed)
			(pads allowed)
			(copperpour not_allowed)
			(footprints allowed)
		)
		(placement
			(enabled no)
			(sheetname "")
		)
		(fill
			(thermal_gap 0.5)
			(thermal_bridge_width 0.5)
			(island_removal_mode 0)
		)
		(polygon
			(pts
				(arc
					(start 308.117494 -295.33215)
					(mid 308.113774 -295.34113)
					(end 308.104794 -295.34485)
				)
				(arc
					(start 306.631594 -295.34485)
					(mid 306.622614 -295.34113)
					(end 306.618894 -295.33215)
				)
				(arc
					(start 306.618894 -294.837612)
					(mid 306.622614 -294.828632)
					(end 306.631594 -294.824912)
				)
				(arc
					(start 308.104794 -294.824912)
					(mid 308.113774 -294.828632)
					(end 308.117494 -294.837612)
				)
			)
		)
	)
	(zone
		(layer "In1.Cu")
		(hatch none 0.5)
		(connect_pads
			(clearance 0)
		)
		(min_thickness 0.25)
		(keepout
			(tracks not_allowed)
			(vias allowed)
			(pads allowed)
			(copperpour not_allowed)
			(footprints allowed)
		)
		(placement
			(enabled no)
			(sheetname "")
		)
		(fill
			(thermal_gap 0.5)
			(thermal_bridge_width 0.5)
			(island_removal_mode 0)
		)
		(polygon
			(pts
				(arc
					(start 206.5782 -312.935366)
					(mid 205.9178 -312.935366)
					(end 206.5782 -312.935366)
				)
			)
		)
	)
	(zone
		(layer "In1.Cu")
		(hatch none 0.5)
		(connect_pads
			(clearance 0)
		)
		(min_thickness 0.25)
		(keepout
			(tracks not_allowed)
			(vias allowed)
			(pads allowed)
			(copperpour not_allowed)
			(footprints allowed)
		)
		(placement
			(enabled no)
			(sheetname "")
		)
		(fill
			(thermal_gap 0.5)
			(thermal_bridge_width 0.5)
			(island_removal_mode 0)
		)
		(polygon
			(pts
				(arc
					(start 37.545264 -229.032562)
					(mid 37.541544 -229.041542)
					(end 37.532564 -229.045262)
				)
				(arc
					(start 36.059364 -229.045262)
					(mid 36.050384 -229.041542)
					(end 36.046664 -229.032562)
				)
				(arc
					(start 36.046664 -228.538024)
					(mid 36.050384 -228.529044)
					(end 36.059364 -228.525324)
				)
				(arc
					(start 37.532564 -228.525324)
					(mid 37.541544 -228.529044)
					(end 37.545264 -228.538024)
				)
			)
		)
	)
	(zone
		(layer "In1.Cu")
		(hatch none 0.5)
		(connect_pads
			(clearance 0)
		)
		(min_thickness 0.25)
		(keepout
			(tracks not_allowed)
			(vias allowed)
			(pads allowed)
			(copperpour not_allowed)
			(footprints allowed)
		)
		(placement
			(enabled no)
			(sheetname "")
		)
		(fill
			(thermal_gap 0.5)
			(thermal_bridge_width 0.5)
			(island_removal_mode 0)
		)
		(polygon
			(pts
				(arc
					(start 80.388968 -389.467344)
					(mid 80.007968 -389.467344)
					(end 80.388968 -389.467344)
				)
			)
		)
	)
	(zone
		(layer "In1.Cu")
		(hatch none 0.5)
		(connect_pads
			(clearance 0)
		)
		(min_thickness 0.25)
		(keepout
			(tracks not_allowed)
			(vias allowed)
			(pads allowed)
			(copperpour not_allowed)
			(footprints allowed)
		)
		(placement
			(enabled no)
			(sheetname "")
		)
		(fill
			(thermal_gap 0.5)
			(thermal_bridge_width 0.5)
			(island_removal_mode 0)
		)
		(polygon
			(pts
				(arc
					(start 129.690876 -391.319258)
					(mid 129.817876 -391.446258)
					(end 129.944876 -391.319258)
				)
				(arc
					(start 129.944876 -391.243058)
					(mid 129.817876 -391.116058)
					(end 129.690876 -391.243058)
				)
			)
		)
	)
	(zone
		(layer "In1.Cu")
		(hatch none 0.5)
		(connect_pads
			(clearance 0)
		)
		(min_thickness 0.25)
		(keepout
			(tracks not_allowed)
			(vias allowed)
			(pads allowed)
			(copperpour not_allowed)
			(footprints allowed)
		)
		(placement
			(enabled no)
			(sheetname "")
		)
		(fill
			(thermal_gap 0.5)
			(thermal_bridge_width 0.5)
			(island_removal_mode 0)
		)
		(polygon
			(pts
				(arc
					(start 309.461154 -393.69238)
					(mid 309.080154 -393.69238)
					(end 309.461154 -393.69238)
				)
			)
		)
	)
	(zone
		(layer "In1.Cu")
		(hatch none 0.5)
		(connect_pads
			(clearance 0)
		)
		(min_thickness 0.25)
		(keepout
			(tracks not_allowed)
			(vias allowed)
			(pads allowed)
			(copperpour not_allowed)
			(footprints allowed)
		)
		(placement
			(enabled no)
			(sheetname "")
		)
		(fill
			(thermal_gap 0.5)
			(thermal_bridge_width 0.5)
			(island_removal_mode 0)
		)
		(polygon
			(pts
				(arc
					(start 420.661338 -243.482114)
					(mid 420.657618 -243.491094)
					(end 420.648638 -243.494814)
				)
				(arc
					(start 419.175438 -243.494814)
					(mid 419.166458 -243.491094)
					(end 419.162738 -243.482114)
				)
				(arc
					(start 419.162738 -242.987576)
					(mid 419.166458 -242.978596)
					(end 419.175438 -242.974876)
				)
				(arc
					(start 420.648638 -242.974876)
					(mid 420.657618 -242.978596)
					(end 420.661338 -242.987576)
				)
			)
		)
	)
	(zone
		(layer "In1.Cu")
		(hatch none 0.5)
		(connect_pads
			(clearance 0)
		)
		(min_thickness 0.25)
		(keepout
			(tracks not_allowed)
			(vias allowed)
			(pads allowed)
			(copperpour not_allowed)
			(footprints allowed)
		)
		(placement
			(enabled no)
			(sheetname "")
		)
		(fill
			(thermal_gap 0.5)
			(thermal_bridge_width 0.5)
			(island_removal_mode 0)
		)
		(polygon
			(pts
				(arc
					(start 56.077358 -285.98241)
					(mid 56.073638 -285.99139)
					(end 56.064658 -285.99511)
				)
				(arc
					(start 54.591458 -285.99511)
					(mid 54.582478 -285.99139)
					(end 54.578758 -285.98241)
				)
				(arc
					(start 54.578758 -285.487872)
					(mid 54.582478 -285.478892)
					(end 54.591458 -285.475172)
				)
				(arc
					(start 56.064658 -285.475172)
					(mid 56.073638 -285.478892)
					(end 56.077358 -285.487872)
				)
			)
		)
	)
	(zone
		(layer "In1.Cu")
		(hatch none 0.5)
		(connect_pads
			(clearance 0)
		)
		(min_thickness 0.25)
		(keepout
			(tracks not_allowed)
			(vias allowed)
			(pads allowed)
			(copperpour not_allowed)
			(footprints allowed)
		)
		(placement
			(enabled no)
			(sheetname "")
		)
		(fill
			(thermal_gap 0.5)
			(thermal_bridge_width 0.5)
			(island_removal_mode 0)
		)
		(polygon
			(pts
				(arc
					(start 202.897232 -265.5824)
					(mid 202.893512 -265.59138)
					(end 202.884532 -265.5951)
				)
				(arc
					(start 201.411332 -265.5951)
					(mid 201.402352 -265.59138)
					(end 201.398632 -265.5824)
				)
				(arc
					(start 201.398632 -265.087862)
					(mid 201.402352 -265.078882)
					(end 201.411332 -265.075162)
				)
				(arc
					(start 202.884532 -265.075162)
					(mid 202.893512 -265.078882)
					(end 202.897232 -265.087862)
				)
			)
		)
	)
	(zone
		(layer "In1.Cu")
		(hatch none 0.5)
		(connect_pads
			(clearance 0)
		)
		(min_thickness 0.25)
		(keepout
			(tracks not_allowed)
			(vias allowed)
			(pads allowed)
			(copperpour not_allowed)
			(footprints allowed)
		)
		(placement
			(enabled no)
			(sheetname "")
		)
		(fill
			(thermal_gap 0.5)
			(thermal_bridge_width 0.5)
			(island_removal_mode 0)
		)
		(polygon
			(pts
				(arc
					(start 428.205392 -245.182136)
					(mid 428.201672 -245.191116)
					(end 428.192692 -245.194836)
				)
				(arc
					(start 426.719492 -245.194836)
					(mid 426.710512 -245.191116)
					(end 426.706792 -245.182136)
				)
				(arc
					(start 426.706792 -244.687598)
					(mid 426.710512 -244.678618)
					(end 426.719492 -244.674898)
				)
				(arc
					(start 428.192692 -244.674898)
					(mid 428.201672 -244.678618)
					(end 428.205392 -244.687598)
				)
			)
		)
	)
	(zone
		(layer "In1.Cu")
		(hatch none 0.5)
		(connect_pads
			(clearance 0)
		)
		(min_thickness 0.25)
		(keepout
			(tracks not_allowed)
			(vias allowed)
			(pads allowed)
			(copperpour not_allowed)
			(footprints allowed)
		)
		(placement
			(enabled no)
			(sheetname "")
		)
		(fill
			(thermal_gap 0.5)
			(thermal_bridge_width 0.5)
			(island_removal_mode 0)
		)
		(polygon
			(pts
				(arc
					(start 16.391382 -106.11866)
					(mid 16.4137 -106.172542)
					(end 16.467582 -106.19486)
				)
				(arc
					(start 16.823182 -106.19486)
					(mid 16.877064 -106.172542)
					(end 16.899382 -106.11866)
				)
				(arc
					(start 16.899382 -104.21366)
					(mid 16.877064 -104.159778)
					(end 16.823182 -104.13746)
				)
				(arc
					(start 16.467582 -104.13746)
					(mid 16.4137 -104.159778)
					(end 16.391382 -104.21366)
				)
			)
		)
	)
	(zone
		(layer "In1.Cu")
		(hatch none 0.5)
		(connect_pads
			(clearance 0)
		)
		(min_thickness 0.25)
		(keepout
			(tracks not_allowed)
			(vias allowed)
			(pads allowed)
			(copperpour not_allowed)
			(footprints allowed)
		)
		(placement
			(enabled no)
			(sheetname "")
		)
		(fill
			(thermal_gap 0.5)
			(thermal_bridge_width 0.5)
			(island_removal_mode 0)
		)
		(polygon
			(pts
				(arc
					(start 191.909446 -233.28249)
					(mid 191.905726 -233.29147)
					(end 191.896746 -233.29519)
				)
				(arc
					(start 190.423546 -233.29519)
					(mid 190.414566 -233.29147)
					(end 190.410846 -233.28249)
				)
				(arc
					(start 190.410846 -232.787952)
					(mid 190.414566 -232.778972)
					(end 190.423546 -232.775252)
				)
				(arc
					(start 191.896746 -232.775252)
					(mid 191.905726 -232.778972)
					(end 191.909446 -232.787952)
				)
			)
		)
	)
	(zone
		(layer "In1.Cu")
		(hatch none 0.5)
		(connect_pads
			(clearance 0)
		)
		(min_thickness 0.25)
		(keepout
			(tracks not_allowed)
			(vias allowed)
			(pads allowed)
			(copperpour not_allowed)
			(footprints allowed)
		)
		(placement
			(enabled no)
			(sheetname "")
		)
		(fill
			(thermal_gap 0.5)
			(thermal_bridge_width 0.5)
			(island_removal_mode 0)
		)
		(polygon
			(pts
				(arc
					(start 180.265324 -273.232372)
					(mid 180.261604 -273.241352)
					(end 180.252624 -273.245072)
				)
				(arc
					(start 178.779424 -273.245072)
					(mid 178.770444 -273.241352)
					(end 178.766724 -273.232372)
				)
				(arc
					(start 178.766724 -272.737834)
					(mid 178.770444 -272.728854)
					(end 178.779424 -272.725134)
				)
				(arc
					(start 180.252624 -272.725134)
					(mid 180.261604 -272.728854)
					(end 180.265324 -272.737834)
				)
			)
		)
	)
	(zone
		(layer "In1.Cu")
		(hatch none 0.5)
		(connect_pads
			(clearance 0)
		)
		(min_thickness 0.25)
		(keepout
			(tracks not_allowed)
			(vias allowed)
			(pads allowed)
			(copperpour not_allowed)
			(footprints allowed)
		)
		(placement
			(enabled no)
			(sheetname "")
		)
		(fill
			(thermal_gap 0.5)
			(thermal_bridge_width 0.5)
			(island_removal_mode 0)
		)
		(polygon
			(pts
				(arc
					(start 114.090958 -391.319258)
					(mid 114.217958 -391.446258)
					(end 114.344958 -391.319258)
				)
				(arc
					(start 114.344958 -391.243058)
					(mid 114.217958 -391.116058)
					(end 114.090958 -391.243058)
				)
			)
		)
	)
	(zone
		(layer "In1.Cu")
		(hatch none 0.5)
		(connect_pads
			(clearance 0)
		)
		(min_thickness 0.25)
		(keepout
			(tracks not_allowed)
			(vias allowed)
			(pads allowed)
			(copperpour not_allowed)
			(footprints allowed)
		)
		(placement
			(enabled no)
			(sheetname "")
		)
		(fill
			(thermal_gap 0.5)
			(thermal_bridge_width 0.5)
			(island_removal_mode 0)
		)
		(polygon
			(pts
				(arc
					(start 281.385264 -286.832294)
					(mid 281.381544 -286.841274)
					(end 281.372564 -286.844994)
				)
				(arc
					(start 279.899364 -286.844994)
					(mid 279.890384 -286.841274)
					(end 279.886664 -286.832294)
				)
				(arc
					(start 279.886664 -286.337756)
					(mid 279.890384 -286.328776)
					(end 279.899364 -286.325056)
				)
				(arc
					(start 281.372564 -286.325056)
					(mid 281.381544 -286.328776)
					(end 281.385264 -286.337756)
				)
			)
		)
	)
	(zone
		(layer "In1.Cu")
		(hatch none 0.5)
		(connect_pads
			(clearance 0)
		)
		(min_thickness 0.25)
		(keepout
			(tracks not_allowed)
			(vias allowed)
			(pads allowed)
			(copperpour not_allowed)
			(footprints allowed)
		)
		(placement
			(enabled no)
			(sheetname "")
		)
		(fill
			(thermal_gap 0.5)
			(thermal_bridge_width 0.5)
			(island_removal_mode 0)
		)
		(polygon
			(pts
				(arc
					(start 30.001464 -242.632484)
					(mid 29.997744 -242.641464)
					(end 29.988764 -242.645184)
				)
				(arc
					(start 28.515564 -242.645184)
					(mid 28.506584 -242.641464)
					(end 28.502864 -242.632484)
				)
				(arc
					(start 28.502864 -242.137946)
					(mid 28.506584 -242.128966)
					(end 28.515564 -242.125246)
				)
				(arc
					(start 29.988764 -242.125246)
					(mid 29.997744 -242.128966)
					(end 30.001464 -242.137946)
				)
			)
		)
	)
	(zone
		(layer "In1.Cu")
		(hatch none 0.5)
		(connect_pads
			(clearance 0)
		)
		(min_thickness 0.25)
		(keepout
			(tracks not_allowed)
			(vias allowed)
			(pads allowed)
			(copperpour not_allowed)
			(footprints allowed)
		)
		(placement
			(enabled no)
			(sheetname "")
		)
		(fill
			(thermal_gap 0.5)
			(thermal_bridge_width 0.5)
			(island_removal_mode 0)
		)
		(polygon
			(pts
				(arc
					(start 300.57344 -306.382166)
					(mid 300.56972 -306.391146)
					(end 300.56074 -306.394866)
				)
				(arc
					(start 299.08754 -306.394866)
					(mid 299.07856 -306.391146)
					(end 299.07484 -306.382166)
				)
				(arc
					(start 299.07484 -305.887628)
					(mid 299.07856 -305.878648)
					(end 299.08754 -305.874928)
				)
				(arc
					(start 300.56074 -305.874928)
					(mid 300.56972 -305.878648)
					(end 300.57344 -305.887628)
				)
			)
		)
	)
	(zone
		(layer "In1.Cu")
		(hatch none 0.5)
		(connect_pads
			(clearance 0)
		)
		(min_thickness 0.25)
		(keepout
			(tracks not_allowed)
			(vias allowed)
			(pads allowed)
			(copperpour not_allowed)
			(footprints allowed)
		)
		(placement
			(enabled no)
			(sheetname "")
		)
		(fill
			(thermal_gap 0.5)
			(thermal_bridge_width 0.5)
			(island_removal_mode 0)
		)
		(polygon
			(pts
				(arc
					(start 52.633372 -214.582502)
					(mid 52.629652 -214.591482)
					(end 52.620672 -214.595202)
				)
				(arc
					(start 51.147472 -214.595202)
					(mid 51.138492 -214.591482)
					(end 51.134772 -214.582502)
				)
				(arc
					(start 51.134772 -214.087964)
					(mid 51.138492 -214.078984)
					(end 51.147472 -214.075264)
				)
				(arc
					(start 52.620672 -214.075264)
					(mid 52.629652 -214.078984)
					(end 52.633372 -214.087964)
				)
			)
		)
	)
	(zone
		(layer "In1.Cu")
		(hatch none 0.5)
		(connect_pads
			(clearance 0)
		)
		(min_thickness 0.25)
		(keepout
			(tracks not_allowed)
			(vias allowed)
			(pads allowed)
			(copperpour not_allowed)
			(footprints allowed)
		)
		(placement
			(enabled no)
			(sheetname "")
		)
		(fill
			(thermal_gap 0.5)
			(thermal_bridge_width 0.5)
			(island_removal_mode 0)
		)
		(polygon
			(pts
				(arc
					(start 163.998148 -390.761474)
					(mid 163.693348 -390.761474)
					(end 163.998148 -390.761474)
				)
			)
		)
	)
	(zone
		(layer "In1.Cu")
		(hatch none 0.5)
		(connect_pads
			(clearance 0)
		)
		(min_thickness 0.25)
		(keepout
			(tracks not_allowed)
			(vias allowed)
			(pads allowed)
			(copperpour not_allowed)
			(footprints allowed)
		)
		(placement
			(enabled no)
			(sheetname "")
		)
		(fill
			(thermal_gap 0.5)
			(thermal_bridge_width 0.5)
			(island_removal_mode 0)
		)
		(polygon
			(pts
				(arc
					(start 439.849514 -199.282304)
					(mid 439.845794 -199.291284)
					(end 439.836814 -199.295004)
				)
				(arc
					(start 438.363614 -199.295004)
					(mid 438.354634 -199.291284)
					(end 438.350914 -199.282304)
				)
				(arc
					(start 438.350914 -198.787766)
					(mid 438.354634 -198.778786)
					(end 438.363614 -198.775066)
				)
				(arc
					(start 439.836814 -198.775066)
					(mid 439.845794 -198.778786)
					(end 439.849514 -198.787766)
				)
			)
		)
	)
	(zone
		(layer "In1.Cu")
		(hatch none 0.5)
		(connect_pads
			(clearance 0)
		)
		(min_thickness 0.25)
		(keepout
			(tracks not_allowed)
			(vias allowed)
			(pads allowed)
			(copperpour not_allowed)
			(footprints allowed)
		)
		(placement
			(enabled no)
			(sheetname "")
		)
		(fill
			(thermal_gap 0.5)
			(thermal_bridge_width 0.5)
			(island_removal_mode 0)
		)
		(polygon
			(pts
				(arc
					(start 450.8373 -284.282134)
					(mid 450.83358 -284.291114)
					(end 450.8246 -284.294834)
				)
				(arc
					(start 449.3514 -284.294834)
					(mid 449.34242 -284.291114)
					(end 449.3387 -284.282134)
				)
				(arc
					(start 449.3387 -283.787596)
					(mid 449.34242 -283.778616)
					(end 449.3514 -283.774896)
				)
				(arc
					(start 450.8246 -283.774896)
					(mid 450.83358 -283.778616)
					(end 450.8373 -283.787596)
				)
			)
		)
	)
	(zone
		(layer "In1.Cu")
		(hatch none 0.5)
		(connect_pads
			(clearance 0)
		)
		(min_thickness 0.25)
		(keepout
			(tracks not_allowed)
			(vias allowed)
			(pads allowed)
			(copperpour not_allowed)
			(footprints allowed)
		)
		(placement
			(enabled no)
			(sheetname "")
		)
		(fill
			(thermal_gap 0.5)
			(thermal_bridge_width 0.5)
			(island_removal_mode 0)
		)
		(polygon
			(pts
				(arc
					(start 304.017426 -288.532316)
					(mid 304.013706 -288.541296)
					(end 304.004726 -288.545016)
				)
				(arc
					(start 302.531526 -288.545016)
					(mid 302.522546 -288.541296)
					(end 302.518826 -288.532316)
				)
				(arc
					(start 302.518826 -288.037778)
					(mid 302.522546 -288.028798)
					(end 302.531526 -288.025078)
				)
				(arc
					(start 304.004726 -288.025078)
					(mid 304.013706 -288.028798)
					(end 304.017426 -288.037778)
				)
			)
		)
	)
	(zone
		(layer "In1.Cu")
		(hatch none 0.5)
		(connect_pads
			(clearance 0)
		)
		(min_thickness 0.25)
		(keepout
			(tracks not_allowed)
			(vias allowed)
			(pads allowed)
			(copperpour not_allowed)
			(footprints allowed)
		)
		(placement
			(enabled no)
			(sheetname "")
		)
		(fill
			(thermal_gap 0.5)
			(thermal_bridge_width 0.5)
			(island_removal_mode 0)
		)
		(polygon
			(pts
				(arc
					(start 300.57344 -311.482232)
					(mid 300.56972 -311.491212)
					(end 300.56074 -311.494932)
				)
				(arc
					(start 299.08754 -311.494932)
					(mid 299.07856 -311.491212)
					(end 299.07484 -311.482232)
				)
				(arc
					(start 299.07484 -310.987694)
					(mid 299.07856 -310.978714)
					(end 299.08754 -310.974994)
				)
				(arc
					(start 300.56074 -310.974994)
					(mid 300.56972 -310.978714)
					(end 300.57344 -310.987694)
				)
			)
		)
	)
	(zone
		(layer "In1.Cu")
		(hatch none 0.5)
		(connect_pads
			(clearance 0)
		)
		(min_thickness 0.25)
		(keepout
			(tracks not_allowed)
			(vias allowed)
			(pads allowed)
			(copperpour not_allowed)
			(footprints allowed)
		)
		(placement
			(enabled no)
			(sheetname "")
		)
		(fill
			(thermal_gap 0.5)
			(thermal_bridge_width 0.5)
			(island_removal_mode 0)
		)
		(polygon
			(pts
				(arc
					(start 293.029386 -297.032172)
					(mid 293.025666 -297.041152)
					(end 293.016686 -297.044872)
				)
				(arc
					(start 291.543486 -297.044872)
					(mid 291.534506 -297.041152)
					(end 291.530786 -297.032172)
				)
				(arc
					(start 291.530786 -296.537634)
					(mid 291.534506 -296.528654)
					(end 291.543486 -296.524934)
				)
				(arc
					(start 293.016686 -296.524934)
					(mid 293.025666 -296.528654)
					(end 293.029386 -296.537634)
				)
			)
		)
	)
	(zone
		(layer "In1.Cu")
		(hatch none 0.5)
		(connect_pads
			(clearance 0)
		)
		(min_thickness 0.25)
		(keepout
			(tracks not_allowed)
			(vias allowed)
			(pads allowed)
			(copperpour not_allowed)
			(footprints allowed)
		)
		(placement
			(enabled no)
			(sheetname "")
		)
		(fill
			(thermal_gap 0.5)
			(thermal_bridge_width 0.5)
			(island_removal_mode 0)
		)
		(polygon
			(pts
				(arc
					(start 61.970412 -390.761474)
					(mid 61.665612 -390.761474)
					(end 61.970412 -390.761474)
				)
			)
		)
	)
	(zone
		(layer "In1.Cu")
		(hatch none 0.5)
		(connect_pads
			(clearance 0)
		)
		(min_thickness 0.25)
		(keepout
			(tracks not_allowed)
			(vias allowed)
			(pads allowed)
			(copperpour not_allowed)
			(footprints allowed)
		)
		(placement
			(enabled no)
			(sheetname "")
		)
		(fill
			(thermal_gap 0.5)
			(thermal_bridge_width 0.5)
			(island_removal_mode 0)
		)
		(polygon
			(pts
				(arc
					(start 61.861192 -388.774432)
					(mid 61.480192 -388.774432)
					(end 61.861192 -388.774432)
				)
			)
		)
	)
	(zone
		(layer "In1.Cu")
		(hatch none 0.5)
		(connect_pads
			(clearance 0)
		)
		(min_thickness 0.25)
		(keepout
			(tracks not_allowed)
			(vias allowed)
			(pads allowed)
			(copperpour not_allowed)
			(footprints allowed)
		)
		(placement
			(enabled no)
			(sheetname "")
		)
		(fill
			(thermal_gap 0.5)
			(thermal_bridge_width 0.5)
			(island_removal_mode 0)
		)
		(polygon
			(pts
				(arc
					(start 304.017426 -318.28232)
					(mid 304.013706 -318.2913)
					(end 304.004726 -318.29502)
				)
				(arc
					(start 302.531526 -318.29502)
					(mid 302.522546 -318.2913)
					(end 302.518826 -318.28232)
				)
				(arc
					(start 302.518826 -317.787782)
					(mid 302.522546 -317.778802)
					(end 302.531526 -317.775082)
				)
				(arc
					(start 304.004726 -317.775082)
					(mid 304.013706 -317.778802)
					(end 304.017426 -317.787782)
				)
			)
		)
	)
	(zone
		(layer "In1.Cu")
		(hatch none 0.5)
		(connect_pads
			(clearance 0)
		)
		(min_thickness 0.25)
		(keepout
			(tracks not_allowed)
			(vias allowed)
			(pads allowed)
			(copperpour not_allowed)
			(footprints allowed)
		)
		(placement
			(enabled no)
			(sheetname "")
		)
		(fill
			(thermal_gap 0.5)
			(thermal_bridge_width 0.5)
			(island_removal_mode 0)
		)
		(polygon
			(pts
				(arc
					(start 126.561342 -385.31038)
					(mid 126.180342 -385.31038)
					(end 126.561342 -385.31038)
				)
			)
		)
	)
	(zone
		(layer "In1.Cu")
		(hatch none 0.5)
		(connect_pads
			(clearance 0)
		)
		(min_thickness 0.25)
		(keepout
			(tracks not_allowed)
			(vias allowed)
			(pads allowed)
			(copperpour not_allowed)
			(footprints allowed)
		)
		(placement
			(enabled no)
			(sheetname "")
		)
		(fill
			(thermal_gap 0.5)
			(thermal_bridge_width 0.5)
			(island_removal_mode 0)
		)
		(polygon
			(pts
				(arc
					(start 426.272452 -7.672324)
					(mid 426.29477 -7.618442)
					(end 426.348652 -7.596124)
				)
				(arc
					(start 427.385226 -7.596124)
					(mid 427.439108 -7.618442)
					(end 427.461426 -7.672324)
				)
				(arc
					(start 427.461426 -9.071864)
					(mid 427.439108 -9.125746)
					(end 427.385226 -9.148064)
				)
				(arc
					(start 426.348652 -9.148064)
					(mid 426.29477 -9.125746)
					(end 426.272452 -9.071864)
				)
			)
		)
	)
	(zone
		(layer "In1.Cu")
		(hatch none 0.5)
		(connect_pads
			(clearance 0)
		)
		(min_thickness 0.25)
		(keepout
			(tracks not_allowed)
			(vias allowed)
			(pads allowed)
			(copperpour not_allowed)
			(footprints allowed)
		)
		(placement
			(enabled no)
			(sheetname "")
		)
		(fill
			(thermal_gap 0.5)
			(thermal_bridge_width 0.5)
			(island_removal_mode 0)
		)
		(polygon
			(pts
				(arc
					(start 40.98925 -207.782414)
					(mid 40.98553 -207.791394)
					(end 40.97655 -207.795114)
				)
				(arc
					(start 39.50335 -207.795114)
					(mid 39.49437 -207.791394)
					(end 39.49065 -207.782414)
				)
				(arc
					(start 39.49065 -207.287876)
					(mid 39.49437 -207.278896)
					(end 39.50335 -207.275176)
				)
				(arc
					(start 40.97655 -207.275176)
					(mid 40.98553 -207.278896)
					(end 40.98925 -207.287876)
				)
			)
		)
	)
	(zone
		(layer "In1.Cu")
		(hatch none 0.5)
		(connect_pads
			(clearance 0)
		)
		(min_thickness 0.25)
		(keepout
			(tracks not_allowed)
			(vias allowed)
			(pads allowed)
			(copperpour not_allowed)
			(footprints allowed)
		)
		(placement
			(enabled no)
			(sheetname "")
		)
		(fill
			(thermal_gap 0.5)
			(thermal_bridge_width 0.5)
			(island_removal_mode 0)
		)
		(polygon
			(pts
				(arc
					(start 102.681024 -294.031416)
					(mid 102.376224 -294.336216)
					(end 102.681024 -294.641016)
				)
				(arc
					(start 103.621078 -294.641016)
					(mid 103.925878 -294.336216)
					(end 103.621078 -294.031416)
				)
			)
		)
	)
	(zone
		(layer "In1.Cu")
		(hatch none 0.5)
		(connect_pads
			(clearance 0)
		)
		(min_thickness 0.25)
		(keepout
			(tracks not_allowed)
			(vias allowed)
			(pads allowed)
			(copperpour not_allowed)
			(footprints allowed)
		)
		(placement
			(enabled no)
			(sheetname "")
		)
		(fill
			(thermal_gap 0.5)
			(thermal_bridge_width 0.5)
			(island_removal_mode 0)
		)
		(polygon
			(pts
				(arc
					(start 435.749446 -230.73233)
					(mid 435.745726 -230.74131)
					(end 435.736746 -230.74503)
				)
				(arc
					(start 434.263546 -230.74503)
					(mid 434.254566 -230.74131)
					(end 434.250846 -230.73233)
				)
				(arc
					(start 434.250846 -230.237792)
					(mid 434.254566 -230.228812)
					(end 434.263546 -230.225092)
				)
				(arc
					(start 435.736746 -230.225092)
					(mid 435.745726 -230.228812)
					(end 435.749446 -230.237792)
				)
			)
		)
	)
	(zone
		(layer "In1.Cu")
		(hatch none 0.5)
		(connect_pads
			(clearance 0)
		)
		(min_thickness 0.25)
		(keepout
			(tracks not_allowed)
			(vias allowed)
			(pads allowed)
			(copperpour not_allowed)
			(footprints allowed)
		)
		(placement
			(enabled no)
			(sheetname "")
		)
		(fill
			(thermal_gap 0.5)
			(thermal_bridge_width 0.5)
			(island_removal_mode 0)
		)
		(polygon
			(pts
				(arc
					(start 308.117494 -291.082222)
					(mid 308.113774 -291.091202)
					(end 308.104794 -291.094922)
				)
				(arc
					(start 306.631594 -291.094922)
					(mid 306.622614 -291.091202)
					(end 306.618894 -291.082222)
				)
				(arc
					(start 306.618894 -290.587684)
					(mid 306.622614 -290.578704)
					(end 306.631594 -290.574984)
				)
				(arc
					(start 308.104794 -290.574984)
					(mid 308.113774 -290.578704)
					(end 308.117494 -290.587684)
				)
			)
		)
	)
	(zone
		(layer "In1.Cu")
		(hatch none 0.5)
		(connect_pads
			(clearance 0)
		)
		(min_thickness 0.25)
		(keepout
			(tracks not_allowed)
			(vias allowed)
			(pads allowed)
			(copperpour not_allowed)
			(footprints allowed)
		)
		(placement
			(enabled no)
			(sheetname "")
		)
		(fill
			(thermal_gap 0.5)
			(thermal_bridge_width 0.5)
			(island_removal_mode 0)
		)
		(polygon
			(pts
				(arc
					(start 443.2935 -200.132188)
					(mid 443.28978 -200.141168)
					(end 443.2808 -200.144888)
				)
				(arc
					(start 441.8076 -200.144888)
					(mid 441.79862 -200.141168)
					(end 441.7949 -200.132188)
				)
				(arc
					(start 441.7949 -199.63765)
					(mid 441.79862 -199.62867)
					(end 441.8076 -199.62495)
				)
				(arc
					(start 443.2808 -199.62495)
					(mid 443.28978 -199.62867)
					(end 443.2935 -199.63765)
				)
			)
		)
	)
	(zone
		(layer "In1.Cu")
		(hatch none 0.5)
		(connect_pads
			(clearance 0)
		)
		(min_thickness 0.25)
		(keepout
			(tracks not_allowed)
			(vias allowed)
			(pads allowed)
			(copperpour not_allowed)
			(footprints allowed)
		)
		(placement
			(enabled no)
			(sheetname "")
		)
		(fill
			(thermal_gap 0.5)
			(thermal_bridge_width 0.5)
			(island_removal_mode 0)
		)
		(polygon
			(pts
				(arc
					(start 270.397478 -261.332218)
					(mid 270.393758 -261.341198)
					(end 270.384778 -261.344918)
				)
				(arc
					(start 268.911578 -261.344918)
					(mid 268.902598 -261.341198)
					(end 268.898878 -261.332218)
				)
				(arc
					(start 268.898878 -260.83768)
					(mid 268.902598 -260.8287)
					(end 268.911578 -260.82498)
				)
				(arc
					(start 270.384778 -260.82498)
					(mid 270.393758 -260.8287)
					(end 270.397478 -260.83768)
				)
			)
		)
	)
	(zone
		(layer "In1.Cu")
		(hatch none 0.5)
		(connect_pads
			(clearance 0)
		)
		(min_thickness 0.25)
		(keepout
			(tracks not_allowed)
			(vias allowed)
			(pads allowed)
			(copperpour not_allowed)
			(footprints allowed)
		)
		(placement
			(enabled no)
			(sheetname "")
		)
		(fill
			(thermal_gap 0.5)
			(thermal_bridge_width 0.5)
			(island_removal_mode 0)
		)
		(polygon
			(pts
				(arc
					(start 432.30546 -244.332252)
					(mid 432.30174 -244.341232)
					(end 432.29276 -244.344952)
				)
				(arc
					(start 430.81956 -244.344952)
					(mid 430.81058 -244.341232)
					(end 430.80686 -244.332252)
				)
				(arc
					(start 430.80686 -243.837714)
					(mid 430.81058 -243.828734)
					(end 430.81956 -243.825014)
				)
				(arc
					(start 432.29276 -243.825014)
					(mid 432.30174 -243.828734)
					(end 432.30546 -243.837714)
				)
			)
		)
	)
	(zone
		(layer "In1.Cu")
		(hatch none 0.5)
		(connect_pads
			(clearance 0)
		)
		(min_thickness 0.25)
		(keepout
			(tracks not_allowed)
			(vias allowed)
			(pads allowed)
			(copperpour not_allowed)
			(footprints allowed)
		)
		(placement
			(enabled no)
			(sheetname "")
		)
		(fill
			(thermal_gap 0.5)
			(thermal_bridge_width 0.5)
			(island_removal_mode 0)
		)
		(polygon
			(pts
				(arc
					(start 202.897232 -318.282574)
					(mid 202.893512 -318.291554)
					(end 202.884532 -318.295274)
				)
				(arc
					(start 201.411332 -318.295274)
					(mid 201.402352 -318.291554)
					(end 201.398632 -318.282574)
				)
				(arc
					(start 201.398632 -317.788036)
					(mid 201.402352 -317.779056)
					(end 201.411332 -317.775336)
				)
				(arc
					(start 202.884532 -317.775336)
					(mid 202.893512 -317.779056)
					(end 202.897232 -317.788036)
				)
			)
		)
	)
	(zone
		(layer "In1.Cu")
		(hatch none 0.5)
		(connect_pads
			(clearance 0)
		)
		(min_thickness 0.25)
		(keepout
			(tracks not_allowed)
			(vias allowed)
			(pads allowed)
			(copperpour not_allowed)
			(footprints allowed)
		)
		(placement
			(enabled no)
			(sheetname "")
		)
		(fill
			(thermal_gap 0.5)
			(thermal_bridge_width 0.5)
			(island_removal_mode 0)
		)
		(polygon
			(pts
				(arc
					(start 30.001464 -311.482486)
					(mid 29.997744 -311.491466)
					(end 29.988764 -311.495186)
				)
				(arc
					(start 28.515564 -311.495186)
					(mid 28.506584 -311.491466)
					(end 28.502864 -311.482486)
				)
				(arc
					(start 28.502864 -310.987948)
					(mid 28.506584 -310.978968)
					(end 28.515564 -310.975248)
				)
				(arc
					(start 29.988764 -310.975248)
					(mid 29.997744 -310.978968)
					(end 30.001464 -310.987948)
				)
			)
		)
	)
	(zone
		(layer "In1.Cu")
		(hatch none 0.5)
		(connect_pads
			(clearance 0)
		)
		(min_thickness 0.25)
		(keepout
			(tracks not_allowed)
			(vias allowed)
			(pads allowed)
			(copperpour not_allowed)
			(footprints allowed)
		)
		(placement
			(enabled no)
			(sheetname "")
		)
		(fill
			(thermal_gap 0.5)
			(thermal_bridge_width 0.5)
			(island_removal_mode 0)
		)
		(polygon
			(pts
				(arc
					(start 428.205392 -312.332116)
					(mid 428.201672 -312.341096)
					(end 428.192692 -312.344816)
				)
				(arc
					(start 426.719492 -312.344816)
					(mid 426.710512 -312.341096)
					(end 426.706792 -312.332116)
				)
				(arc
					(start 426.706792 -311.837578)
					(mid 426.710512 -311.828598)
					(end 426.719492 -311.824878)
				)
				(arc
					(start 428.192692 -311.824878)
					(mid 428.201672 -311.828598)
					(end 428.205392 -311.837578)
				)
			)
		)
	)
	(zone
		(layer "In1.Cu")
		(hatch none 0.5)
		(connect_pads
			(clearance 0)
		)
		(min_thickness 0.25)
		(keepout
			(tracks not_allowed)
			(vias allowed)
			(pads allowed)
			(copperpour not_allowed)
			(footprints allowed)
		)
		(placement
			(enabled no)
			(sheetname "")
		)
		(fill
			(thermal_gap 0.5)
			(thermal_bridge_width 0.5)
			(island_removal_mode 0)
		)
		(polygon
			(pts
				(arc
					(start 296.473372 -276.632162)
					(mid 296.469652 -276.641142)
					(end 296.460672 -276.644862)
				)
				(arc
					(start 294.987472 -276.644862)
					(mid 294.978492 -276.641142)
					(end 294.974772 -276.632162)
				)
				(arc
					(start 294.974772 -276.137624)
					(mid 294.978492 -276.128644)
					(end 294.987472 -276.124924)
				)
				(arc
					(start 296.460672 -276.124924)
					(mid 296.469652 -276.128644)
					(end 296.473372 -276.137624)
				)
			)
		)
	)
	(zone
		(layer "In1.Cu")
		(hatch none 0.5)
		(connect_pads
			(clearance 0)
		)
		(min_thickness 0.25)
		(keepout
			(tracks not_allowed)
			(vias allowed)
			(pads allowed)
			(copperpour not_allowed)
			(footprints allowed)
		)
		(placement
			(enabled no)
			(sheetname "")
		)
		(fill
			(thermal_gap 0.5)
			(thermal_bridge_width 0.5)
			(island_removal_mode 0)
		)
		(polygon
			(pts
				(arc
					(start 64.370458 -383.92227)
					(mid 64.065658 -383.92227)
					(end 64.370458 -383.92227)
				)
			)
		)
	)
	(zone
		(layer "In1.Cu")
		(hatch none 0.5)
		(connect_pads
			(clearance 0)
		)
		(min_thickness 0.25)
		(keepout
			(tracks not_allowed)
			(vias allowed)
			(pads allowed)
			(copperpour not_allowed)
			(footprints allowed)
		)
		(placement
			(enabled no)
			(sheetname "")
		)
		(fill
			(thermal_gap 0.5)
			(thermal_bridge_width 0.5)
			(island_removal_mode 0)
		)
		(polygon
			(pts
				(arc
					(start 308.117494 -249.432318)
					(mid 308.113774 -249.441298)
					(end 308.104794 -249.445018)
				)
				(arc
					(start 306.631594 -249.445018)
					(mid 306.622614 -249.441298)
					(end 306.618894 -249.432318)
				)
				(arc
					(start 306.618894 -248.93778)
					(mid 306.622614 -248.9288)
					(end 306.631594 -248.92508)
				)
				(arc
					(start 308.104794 -248.92508)
					(mid 308.113774 -248.9288)
					(end 308.117494 -248.93778)
				)
			)
		)
	)
	(zone
		(layer "In1.Cu")
		(hatch none 0.5)
		(connect_pads
			(clearance 0)
		)
		(min_thickness 0.25)
		(keepout
			(tracks not_allowed)
			(vias allowed)
			(pads allowed)
			(copperpour not_allowed)
			(footprints allowed)
		)
		(placement
			(enabled no)
			(sheetname "")
		)
		(fill
			(thermal_gap 0.5)
			(thermal_bridge_width 0.5)
			(island_removal_mode 0)
		)
		(polygon
			(pts
				(arc
					(start 411.48889 -393.69238)
					(mid 411.10789 -393.69238)
					(end 411.48889 -393.69238)
				)
			)
		)
	)
	(zone
		(layer "In1.Cu")
		(hatch none 0.5)
		(connect_pads
			(clearance 0)
		)
		(min_thickness 0.25)
		(keepout
			(tracks not_allowed)
			(vias allowed)
			(pads allowed)
			(copperpour not_allowed)
			(footprints allowed)
		)
		(placement
			(enabled no)
			(sheetname "")
		)
		(fill
			(thermal_gap 0.5)
			(thermal_bridge_width 0.5)
			(island_removal_mode 0)
		)
		(polygon
			(pts
				(arc
					(start 415.818828 -399.701258)
					(mid 415.945828 -399.828258)
					(end 416.072828 -399.701258)
				)
				(arc
					(start 416.072828 -399.625058)
					(mid 415.945828 -399.498058)
					(end 415.818828 -399.625058)
				)
			)
		)
	)
	(zone
		(layer "In1.Cu")
		(hatch none 0.5)
		(connect_pads
			(clearance 0)
		)
		(min_thickness 0.25)
		(keepout
			(tracks not_allowed)
			(vias allowed)
			(pads allowed)
			(copperpour not_allowed)
			(footprints allowed)
		)
		(placement
			(enabled no)
			(sheetname "")
		)
		(fill
			(thermal_gap 0.5)
			(thermal_bridge_width 0.5)
			(island_removal_mode 0)
		)
		(polygon
			(pts
				(arc
					(start 421.48887 -397.849344)
					(mid 421.10787 -397.849344)
					(end 421.48887 -397.849344)
				)
			)
		)
	)
	(zone
		(layer "In1.Cu")
		(hatch none 0.5)
		(connect_pads
			(clearance 0)
		)
		(min_thickness 0.25)
		(keepout
			(tracks not_allowed)
			(vias allowed)
			(pads allowed)
			(copperpour not_allowed)
			(footprints allowed)
		)
		(placement
			(enabled no)
			(sheetname "")
		)
		(fill
			(thermal_gap 0.5)
			(thermal_bridge_width 0.5)
			(island_removal_mode 0)
		)
		(polygon
			(pts
				(arc
					(start 288.929318 -262.182102)
					(mid 288.925598 -262.191082)
					(end 288.916618 -262.194802)
				)
				(arc
					(start 287.443418 -262.194802)
					(mid 287.434438 -262.191082)
					(end 287.430718 -262.182102)
				)
				(arc
					(start 287.430718 -261.687564)
					(mid 287.434438 -261.678584)
					(end 287.443418 -261.674864)
				)
				(arc
					(start 288.916618 -261.674864)
					(mid 288.925598 -261.678584)
					(end 288.929318 -261.687564)
				)
			)
		)
	)
	(zone
		(layer "In1.Cu")
		(hatch none 0.5)
		(connect_pads
			(clearance 0)
		)
		(min_thickness 0.25)
		(keepout
			(tracks not_allowed)
			(vias allowed)
			(pads allowed)
			(copperpour not_allowed)
			(footprints allowed)
		)
		(placement
			(enabled no)
			(sheetname "")
		)
		(fill
			(thermal_gap 0.5)
			(thermal_bridge_width 0.5)
			(island_removal_mode 0)
		)
		(polygon
			(pts
				(arc
					(start 202.897232 -262.182356)
					(mid 202.893512 -262.191336)
					(end 202.884532 -262.195056)
				)
				(arc
					(start 201.411332 -262.195056)
					(mid 201.402352 -262.191336)
					(end 201.398632 -262.182356)
				)
				(arc
					(start 201.398632 -261.687818)
					(mid 201.402352 -261.678838)
					(end 201.411332 -261.675118)
				)
				(arc
					(start 202.884532 -261.675118)
					(mid 202.893512 -261.678838)
					(end 202.897232 -261.687818)
				)
			)
		)
	)
	(zone
		(layer "In1.Cu")
		(hatch none 0.5)
		(connect_pads
			(clearance 0)
		)
		(min_thickness 0.25)
		(keepout
			(tracks not_allowed)
			(vias allowed)
			(pads allowed)
			(copperpour not_allowed)
			(footprints allowed)
		)
		(placement
			(enabled no)
			(sheetname "")
		)
		(fill
			(thermal_gap 0.5)
			(thermal_bridge_width 0.5)
			(island_removal_mode 0)
		)
		(polygon
			(pts
				(arc
					(start 432.30546 -295.33215)
					(mid 432.30174 -295.34113)
					(end 432.29276 -295.34485)
				)
				(arc
					(start 430.81956 -295.34485)
					(mid 430.81058 -295.34113)
					(end 430.80686 -295.33215)
				)
				(arc
					(start 430.80686 -294.837612)
					(mid 430.81058 -294.828632)
					(end 430.81956 -294.824912)
				)
				(arc
					(start 432.29276 -294.824912)
					(mid 432.30174 -294.828632)
					(end 432.30546 -294.837612)
				)
			)
		)
	)
	(zone
		(layers "In1.Cu" "In2.Cu")
		(hatch none 0.5)
		(connect_pads
			(clearance 0)
		)
		(min_thickness 0.25)
		(keepout
			(tracks not_allowed)
			(vias allowed)
			(pads allowed)
			(copperpour not_allowed)
			(footprints allowed)
		)
		(placement
			(enabled no)
			(sheetname "")
		)
		(fill yes
			(thermal_gap 0.5)
			(thermal_bridge_width 0.5)
			(island_removal_mode 0)
		)
		(polygon
			(pts
				(arc
					(start 446.974468 -267.885164)
					(mid 446.314068 -267.885164)
					(end 446.974468 -267.885164)
				)
			)
		)
	)
	(zone
		(layers "In1.Cu" "In2.Cu")
		(hatch none 0.5)
		(connect_pads
			(clearance 0)
		)
		(min_thickness 0.25)
		(keepout
			(tracks not_allowed)
			(vias allowed)
			(pads allowed)
			(copperpour not_allowed)
			(footprints allowed)
		)
		(placement
			(enabled no)
			(sheetname "")
		)
		(fill yes
			(thermal_gap 0.5)
			(thermal_bridge_width 0.5)
			(island_removal_mode 0)
		)
		(polygon
			(pts
				(arc
					(start 280.966164 -291.684964)
					(mid 280.305764 -291.684964)
					(end 280.966164 -291.684964)
				)
			)
		)
	)
	(zone
		(layers "In1.Cu" "In2.Cu")
		(hatch none 0.5)
		(connect_pads
			(clearance 0)
		)
		(min_thickness 0.25)
		(keepout
			(tracks not_allowed)
			(vias allowed)
			(pads allowed)
			(copperpour not_allowed)
			(footprints allowed)
		)
		(placement
			(enabled no)
			(sheetname "")
		)
		(fill yes
			(thermal_gap 0.5)
			(thermal_bridge_width 0.5)
			(island_removal_mode 0)
		)
		(polygon
			(pts
				(arc
					(start 435.330346 -261.93496)
					(mid 434.669946 -261.93496)
					(end 435.330346 -261.93496)
				)
			)
		)
	)
	(zone
		(layers "In1.Cu" "In2.Cu")
		(hatch none 0.5)
		(connect_pads
			(clearance 0)
		)
		(min_thickness 0.25)
		(keepout
			(tracks not_allowed)
			(vias allowed)
			(pads allowed)
			(copperpour not_allowed)
			(footprints allowed)
		)
		(placement
			(enabled no)
			(sheetname "")
		)
		(fill yes
			(thermal_gap 0.5)
			(thermal_bridge_width 0.5)
			(island_removal_mode 0)
		)
		(polygon
			(pts
				(arc
					(start 194.934332 -297.635422)
					(mid 194.273932 -297.635422)
					(end 194.934332 -297.635422)
				)
			)
		)
	)
	(zone
		(layers "In1.Cu" "In2.Cu")
		(hatch none 0.5)
		(connect_pads
			(clearance 0)
		)
		(min_thickness 0.25)
		(keepout
			(tracks not_allowed)
			(vias allowed)
			(pads allowed)
			(copperpour not_allowed)
			(footprints allowed)
		)
		(placement
			(enabled no)
			(sheetname "")
		)
		(fill yes
			(thermal_gap 0.5)
			(thermal_bridge_width 0.5)
			(island_removal_mode 0)
		)
		(polygon
			(pts
				(arc
					(start 17.938242 -239.835436)
					(mid 17.277842 -239.835436)
					(end 17.938242 -239.835436)
				)
			)
		)
	)
	(zone
		(layers "In1.Cu" "In2.Cu")
		(hatch none 0.5)
		(connect_pads
			(clearance 0)
		)
		(min_thickness 0.25)
		(keepout
			(tracks not_allowed)
			(vias allowed)
			(pads allowed)
			(copperpour not_allowed)
			(footprints allowed)
		)
		(placement
			(enabled no)
			(sheetname "")
		)
		(fill yes
			(thermal_gap 0.5)
			(thermal_bridge_width 0.5)
			(island_removal_mode 0)
		)
		(polygon
			(pts
				(arc
					(start 33.026096 -251.735336)
					(mid 32.365696 -251.735336)
					(end 33.026096 -251.735336)
				)
			)
		)
	)
	(zone
		(layers "In1.Cu" "In2.Cu")
		(hatch none 0.5)
		(connect_pads
			(clearance 0)
		)
		(min_thickness 0.25)
		(keepout
			(tracks not_allowed)
			(vias allowed)
			(pads allowed)
			(copperpour not_allowed)
			(footprints allowed)
		)
		(placement
			(enabled no)
			(sheetname "")
		)
		(fill yes
			(thermal_gap 0.5)
			(thermal_bridge_width 0.5)
			(island_removal_mode 0)
		)
		(polygon
			(pts
				(arc
					(start 292.610286 -278.085042)
					(mid 291.949886 -278.085042)
					(end 292.610286 -278.085042)
				)
			)
		)
	)
	(zone
		(layers "In1.Cu" "In2.Cu")
		(hatch none 0.5)
		(connect_pads
			(clearance 0)
		)
		(min_thickness 0.25)
		(keepout
			(tracks not_allowed)
			(vias allowed)
			(pads allowed)
			(copperpour not_allowed)
			(footprints allowed)
		)
		(placement
			(enabled no)
			(sheetname "")
		)
		(fill yes
			(thermal_gap 0.5)
			(thermal_bridge_width 0.5)
			(island_removal_mode 0)
		)
		(polygon
			(pts
				(arc
					(start 431.88636 -221.985078)
					(mid 431.22596 -221.985078)
					(end 431.88636 -221.985078)
				)
			)
		)
	)
	(zone
		(layers "In1.Cu" "In2.Cu")
		(hatch none 0.5)
		(connect_pads
			(clearance 0)
		)
		(min_thickness 0.25)
		(keepout
			(tracks not_allowed)
			(vias allowed)
			(pads allowed)
			(copperpour not_allowed)
			(footprints allowed)
		)
		(placement
			(enabled no)
			(sheetname "")
		)
		(fill yes
			(thermal_gap 0.5)
			(thermal_bridge_width 0.5)
			(island_removal_mode 0)
		)
		(polygon
			(pts
				(arc
					(start 25.482296 -215.185244)
					(mid 24.821896 -215.185244)
					(end 25.482296 -215.185244)
				)
			)
		)
	)
	(zone
		(layers "In1.Cu" "In2.Cu")
		(hatch none 0.5)
		(connect_pads
			(clearance 0)
		)
		(min_thickness 0.25)
		(keepout
			(tracks not_allowed)
			(vias allowed)
			(pads allowed)
			(copperpour not_allowed)
			(footprints allowed)
		)
		(placement
			(enabled no)
			(sheetname "")
		)
		(fill yes
			(thermal_gap 0.5)
			(thermal_bridge_width 0.5)
			(island_removal_mode 0)
		)
		(polygon
			(pts
				(arc
					(start 277.522432 -312.935112)
					(mid 276.862032 -312.935112)
					(end 277.522432 -312.935112)
				)
			)
		)
	)
	(zone
		(layers "In1.Cu" "In2.Cu")
		(hatch none 0.5)
		(connect_pads
			(clearance 0)
		)
		(min_thickness 0.25)
		(keepout
			(tracks not_allowed)
			(vias allowed)
			(pads allowed)
			(copperpour not_allowed)
			(footprints allowed)
		)
		(placement
			(enabled no)
			(sheetname "")
		)
		(fill yes
			(thermal_gap 0.5)
			(thermal_bridge_width 0.5)
			(island_removal_mode 0)
		)
		(polygon
			(pts
				(arc
					(start 183.946292 -287.43529)
					(mid 183.285892 -287.43529)
					(end 183.946292 -287.43529)
				)
			)
		)
	)
	(zone
		(layers "In1.Cu" "In2.Cu")
		(hatch none 0.5)
		(connect_pads
			(clearance 0)
		)
		(min_thickness 0.25)
		(keepout
			(tracks not_allowed)
			(vias allowed)
			(pads allowed)
			(copperpour not_allowed)
			(footprints allowed)
		)
		(placement
			(enabled no)
			(sheetname "")
		)
		(fill yes
			(thermal_gap 0.5)
			(thermal_bridge_width 0.5)
			(island_removal_mode 0)
		)
		(polygon
			(pts
				(arc
					(start 285.066232 -214.335106)
					(mid 284.405832 -214.335106)
					(end 285.066232 -214.335106)
				)
			)
		)
	)
	(zone
		(layers "In1.Cu" "In2.Cu")
		(hatch none 0.5)
		(connect_pads
			(clearance 0)
		)
		(min_thickness 0.25)
		(keepout
			(tracks not_allowed)
			(vias allowed)
			(pads allowed)
			(copperpour not_allowed)
			(footprints allowed)
		)
		(placement
			(enabled no)
			(sheetname "")
		)
		(fill yes
			(thermal_gap 0.5)
			(thermal_bridge_width 0.5)
			(island_removal_mode 0)
		)
		(polygon
			(pts
				(arc
					(start 40.57015 -316.33541)
					(mid 39.90975 -316.33541)
					(end 40.57015 -316.33541)
				)
			)
		)
	)
	(zone
		(layers "In1.Cu" "In2.Cu")
		(hatch none 0.5)
		(connect_pads
			(clearance 0)
		)
		(min_thickness 0.25)
		(keepout
			(tracks not_allowed)
			(vias allowed)
			(pads allowed)
			(copperpour not_allowed)
			(footprints allowed)
		)
		(placement
			(enabled no)
			(sheetname "")
		)
		(fill yes
			(thermal_gap 0.5)
			(thermal_bridge_width 0.5)
			(island_removal_mode 0)
		)
		(polygon
			(pts
				(arc
					(start 277.522432 -284.88513)
					(mid 276.862032 -284.88513)
					(end 277.522432 -284.88513)
				)
			)
		)
	)
	(zone
		(layers "In1.Cu" "In2.Cu")
		(hatch none 0.5)
		(connect_pads
			(clearance 0)
		)
		(min_thickness 0.25)
		(keepout
			(tracks not_allowed)
			(vias allowed)
			(pads allowed)
			(copperpour not_allowed)
			(footprints allowed)
		)
		(placement
			(enabled no)
			(sheetname "")
		)
		(fill yes
			(thermal_gap 0.5)
			(thermal_bridge_width 0.5)
			(island_removal_mode 0)
		)
		(polygon
			(pts
				(arc
					(start 280.966164 -276.38502)
					(mid 280.305764 -276.38502)
					(end 280.966164 -276.38502)
				)
			)
		)
	)
	(zone
		(layers "In1.Cu" "In2.Cu")
		(hatch none 0.5)
		(connect_pads
			(clearance 0)
		)
		(min_thickness 0.25)
		(keepout
			(tracks not_allowed)
			(vias allowed)
			(pads allowed)
			(copperpour not_allowed)
			(footprints allowed)
		)
		(placement
			(enabled no)
			(sheetname "")
		)
		(fill yes
			(thermal_gap 0.5)
			(thermal_bridge_width 0.5)
			(island_removal_mode 0)
		)
		(polygon
			(pts
				(arc
					(start 424.342306 -278.085042)
					(mid 423.681906 -278.085042)
					(end 424.342306 -278.085042)
				)
			)
		)
	)
	(zone
		(layers "In1.Cu" "In2.Cu")
		(hatch none 0.5)
		(connect_pads
			(clearance 0)
		)
		(min_thickness 0.25)
		(keepout
			(tracks not_allowed)
			(vias allowed)
			(pads allowed)
			(copperpour not_allowed)
			(footprints allowed)
		)
		(placement
			(enabled no)
			(sheetname "")
		)
		(fill yes
			(thermal_gap 0.5)
			(thermal_bridge_width 0.5)
			(island_removal_mode 0)
		)
		(polygon
			(pts
				(arc
					(start 145.309336 -408.860244)
					(mid 145.331654 -408.914126)
					(end 145.385536 -408.936444)
				)
				(arc
					(start 145.581116 -408.936444)
					(mid 145.602992 -408.933312)
					(end 145.623026 -408.923998)
				)
				(arc
					(start 145.91665 -408.731466)
					(mid 145.958306 -408.719064)
					(end 145.999962 -408.731466)
				)
				(arc
					(start 146.294856 -408.923998)
					(mid 146.31478 -408.933234)
					(end 146.336512 -408.936444)
				)
				(arc
					(start 146.531076 -408.936444)
					(mid 146.584958 -408.914126)
					(end 146.607276 -408.860244)
				)
				(arc
					(start 146.607276 -408.174444)
					(mid 146.584958 -408.120562)
					(end 146.531076 -408.098244)
				)
				(arc
					(start 146.336512 -408.098244)
					(mid 146.314768 -408.101412)
					(end 146.294856 -408.11069)
				)
				(arc
					(start 145.998692 -408.303476)
					(mid 145.957008 -408.315698)
					(end 145.91538 -408.303222)
				)
				(arc
					(start 145.621756 -408.11069)
					(mid 145.601832 -408.101454)
					(end 145.5801 -408.098244)
				)
				(arc
					(start 145.385536 -408.098244)
					(mid 145.331654 -408.120562)
					(end 145.309336 -408.174444)
				)
			)
		)
	)
	(zone
		(layers "In1.Cu" "In2.Cu")
		(hatch none 0.5)
		(connect_pads
			(clearance 0)
		)
		(min_thickness 0.25)
		(keepout
			(tracks not_allowed)
			(vias allowed)
			(pads allowed)
			(copperpour not_allowed)
			(footprints allowed)
		)
		(placement
			(enabled no)
			(sheetname "")
		)
		(fill yes
			(thermal_gap 0.5)
			(thermal_bridge_width 0.5)
			(island_removal_mode 0)
		)
		(polygon
			(pts
				(arc
					(start 179.846224 -235.585254)
					(mid 179.185824 -235.585254)
					(end 179.846224 -235.585254)
				)
			)
		)
	)
	(zone
		(layers "In1.Cu" "In2.Cu")
		(hatch none 0.5)
		(connect_pads
			(clearance 0)
		)
		(min_thickness 0.25)
		(keepout
			(tracks not_allowed)
			(vias allowed)
			(pads allowed)
			(copperpour not_allowed)
			(footprints allowed)
		)
		(placement
			(enabled no)
			(sheetname "")
		)
		(fill yes
			(thermal_gap 0.5)
			(thermal_bridge_width 0.5)
			(island_removal_mode 0)
		)
		(polygon
			(pts
				(arc
					(start 285.066232 -315.485018)
					(mid 284.405832 -315.485018)
					(end 285.066232 -315.485018)
				)
			)
		)
	)
	(zone
		(layers "In1.Cu" "In2.Cu")
		(hatch none 0.5)
		(connect_pads
			(clearance 0)
		)
		(min_thickness 0.25)
		(keepout
			(tracks not_allowed)
			(vias allowed)
			(pads allowed)
			(copperpour not_allowed)
			(footprints allowed)
		)
		(placement
			(enabled no)
			(sheetname "")
		)
		(fill yes
			(thermal_gap 0.5)
			(thermal_bridge_width 0.5)
			(island_removal_mode 0)
		)
		(polygon
			(pts
				(arc
					(start 450.4182 -224.534984)
					(mid 449.7578 -224.534984)
					(end 450.4182 -224.534984)
				)
			)
		)
	)
	(zone
		(layers "In1.Cu" "In2.Cu")
		(hatch none 0.5)
		(connect_pads
			(clearance 0)
		)
		(min_thickness 0.25)
		(keepout
			(tracks not_allowed)
			(vias allowed)
			(pads allowed)
			(copperpour not_allowed)
			(footprints allowed)
		)
		(placement
			(enabled no)
			(sheetname "")
		)
		(fill yes
			(thermal_gap 0.5)
			(thermal_bridge_width 0.5)
			(island_removal_mode 0)
		)
		(polygon
			(pts
				(arc
					(start 280.966164 -304.435002)
					(mid 280.305764 -304.435002)
					(end 280.966164 -304.435002)
				)
			)
		)
	)
	(zone
		(layers "In1.Cu" "In2.Cu")
		(hatch none 0.5)
		(connect_pads
			(clearance 0)
		)
		(min_thickness 0.25)
		(keepout
			(tracks not_allowed)
			(vias allowed)
			(pads allowed)
			(copperpour not_allowed)
			(footprints allowed)
		)
		(placement
			(enabled no)
			(sheetname "")
		)
		(fill yes
			(thermal_gap 0.5)
			(thermal_bridge_width 0.5)
			(island_removal_mode 0)
		)
		(polygon
			(pts
				(arc
					(start 187.390278 -201.585322)
					(mid 186.729878 -201.585322)
					(end 187.390278 -201.585322)
				)
			)
		)
	)
	(zone
		(layers "In1.Cu" "In2.Cu")
		(hatch none 0.5)
		(connect_pads
			(clearance 0)
		)
		(min_thickness 0.25)
		(keepout
			(tracks not_allowed)
			(vias allowed)
			(pads allowed)
			(copperpour not_allowed)
			(footprints allowed)
		)
		(placement
			(enabled no)
			(sheetname "")
		)
		(fill yes
			(thermal_gap 0.5)
			(thermal_bridge_width 0.5)
			(island_removal_mode 0)
		)
		(polygon
			(pts
				(arc
					(start 176.402238 -283.185362)
					(mid 175.741838 -283.185362)
					(end 176.402238 -283.185362)
				)
			)
		)
	)
	(zone
		(layers "In1.Cu" "In2.Cu")
		(hatch none 0.5)
		(connect_pads
			(clearance 0)
		)
		(min_thickness 0.25)
		(keepout
			(tracks not_allowed)
			(vias allowed)
			(pads allowed)
			(copperpour not_allowed)
			(footprints allowed)
		)
		(placement
			(enabled no)
			(sheetname "")
		)
		(fill yes
			(thermal_gap 0.5)
			(thermal_bridge_width 0.5)
			(island_removal_mode 0)
		)
		(polygon
			(pts
				(arc
					(start 29.582364 -225.385376)
					(mid 28.921964 -225.385376)
					(end 29.582364 -225.385376)
				)
			)
		)
	)
	(zone
		(layers "In1.Cu" "In2.Cu")
		(hatch none 0.5)
		(connect_pads
			(clearance 0)
		)
		(min_thickness 0.25)
		(keepout
			(tracks not_allowed)
			(vias allowed)
			(pads allowed)
			(copperpour not_allowed)
			(footprints allowed)
		)
		(placement
			(enabled no)
			(sheetname "")
		)
		(fill yes
			(thermal_gap 0.5)
			(thermal_bridge_width 0.5)
			(island_removal_mode 0)
		)
		(polygon
			(pts
				(arc
					(start 176.402238 -317.185294)
					(mid 175.741838 -317.185294)
					(end 176.402238 -317.185294)
				)
			)
		)
	)
	(zone
		(layers "In1.Cu" "In2.Cu")
		(hatch none 0.5)
		(connect_pads
			(clearance 0)
		)
		(min_thickness 0.25)
		(keepout
			(tracks not_allowed)
			(vias allowed)
			(pads allowed)
			(copperpour not_allowed)
			(footprints allowed)
		)
		(placement
			(enabled no)
			(sheetname "")
		)
		(fill yes
			(thermal_gap 0.5)
			(thermal_bridge_width 0.5)
			(island_removal_mode 0)
		)
		(polygon
			(pts
				(arc
					(start 40.57015 -232.18521)
					(mid 39.90975 -232.18521)
					(end 40.57015 -232.18521)
				)
			)
		)
	)
	(zone
		(layers "In1.Cu" "In2.Cu")
		(hatch none 0.5)
		(connect_pads
			(clearance 0)
		)
		(min_thickness 0.25)
		(keepout
			(tracks not_allowed)
			(vias allowed)
			(pads allowed)
			(copperpour not_allowed)
			(footprints allowed)
		)
		(placement
			(enabled no)
			(sheetname "")
		)
		(fill yes
			(thermal_gap 0.5)
			(thermal_bridge_width 0.5)
			(island_removal_mode 0)
		)
		(polygon
			(pts
				(arc
					(start 420.242238 -248.335038)
					(mid 419.581838 -248.335038)
					(end 420.242238 -248.335038)
				)
			)
		)
	)
	(zone
		(layers "In1.Cu" "In2.Cu")
		(hatch none 0.5)
		(connect_pads
			(clearance 0)
		)
		(min_thickness 0.25)
		(keepout
			(tracks not_allowed)
			(vias allowed)
			(pads allowed)
			(copperpour not_allowed)
			(footprints allowed)
		)
		(placement
			(enabled no)
			(sheetname "")
		)
		(fill yes
			(thermal_gap 0.5)
			(thermal_bridge_width 0.5)
			(island_removal_mode 0)
		)
		(polygon
			(pts
				(arc
					(start 296.054272 -254.284988)
					(mid 295.393872 -254.284988)
					(end 296.054272 -254.284988)
				)
			)
		)
	)
	(zone
		(layers "In1.Cu" "In2.Cu")
		(hatch none 0.5)
		(connect_pads
			(clearance 0)
		)
		(min_thickness 0.25)
		(keepout
			(tracks not_allowed)
			(vias allowed)
			(pads allowed)
			(copperpour not_allowed)
			(footprints allowed)
		)
		(placement
			(enabled no)
			(sheetname "")
		)
		(fill yes
			(thermal_gap 0.5)
			(thermal_bridge_width 0.5)
			(island_removal_mode 0)
		)
		(polygon
			(pts
				(arc
					(start 285.066232 -279.785064)
					(mid 284.405832 -279.785064)
					(end 285.066232 -279.785064)
				)
			)
		)
	)
	(zone
		(layers "In1.Cu" "In2.Cu")
		(hatch none 0.5)
		(connect_pads
			(clearance 0)
		)
		(min_thickness 0.25)
		(keepout
			(tracks not_allowed)
			(vias allowed)
			(pads allowed)
			(copperpour not_allowed)
			(footprints allowed)
		)
		(placement
			(enabled no)
			(sheetname "")
		)
		(fill yes
			(thermal_gap 0.5)
			(thermal_bridge_width 0.5)
			(island_removal_mode 0)
		)
		(polygon
			(pts
				(arc
					(start 296.054272 -204.134974)
					(mid 295.393872 -204.134974)
					(end 296.054272 -204.134974)
				)
			)
		)
	)
	(zone
		(layers "In1.Cu" "In2.Cu")
		(hatch none 0.5)
		(connect_pads
			(clearance 0)
		)
		(min_thickness 0.25)
		(keepout
			(tracks not_allowed)
			(vias allowed)
			(pads allowed)
			(copperpour not_allowed)
			(footprints allowed)
		)
		(placement
			(enabled no)
			(sheetname "")
		)
		(fill yes
			(thermal_gap 0.5)
			(thermal_bridge_width 0.5)
			(island_removal_mode 0)
		)
		(polygon
			(pts
				(arc
					(start 442.8744 -209.23504)
					(mid 442.214 -209.23504)
					(end 442.8744 -209.23504)
				)
			)
		)
	)
	(zone
		(layers "In1.Cu" "In2.Cu")
		(hatch none 0.5)
		(connect_pads
			(clearance 0)
		)
		(min_thickness 0.25)
		(keepout
			(tracks not_allowed)
			(vias allowed)
			(pads allowed)
			(copperpour not_allowed)
			(footprints allowed)
		)
		(placement
			(enabled no)
			(sheetname "")
		)
		(fill yes
			(thermal_gap 0.5)
			(thermal_bridge_width 0.5)
			(island_removal_mode 0)
		)
		(polygon
			(pts
				(arc
					(start 183.946292 -290.835334)
					(mid 183.285892 -290.835334)
					(end 183.946292 -290.835334)
				)
			)
		)
	)
	(zone
		(layers "In1.Cu" "In2.Cu")
		(hatch none 0.5)
		(connect_pads
			(clearance 0)
		)
		(min_thickness 0.25)
		(keepout
			(tracks not_allowed)
			(vias allowed)
			(pads allowed)
			(copperpour not_allowed)
			(footprints allowed)
		)
		(placement
			(enabled no)
			(sheetname "")
		)
		(fill yes
			(thermal_gap 0.5)
			(thermal_bridge_width 0.5)
			(island_removal_mode 0)
		)
		(polygon
			(pts
				(arc
					(start 22.03831 -210.085432)
					(mid 21.37791 -210.085432)
					(end 22.03831 -210.085432)
				)
			)
		)
	)
	(zone
		(layers "In1.Cu" "In2.Cu")
		(hatch none 0.5)
		(connect_pads
			(clearance 0)
		)
		(min_thickness 0.25)
		(keepout
			(tracks not_allowed)
			(vias allowed)
			(pads allowed)
			(copperpour not_allowed)
			(footprints allowed)
		)
		(placement
			(enabled no)
			(sheetname "")
		)
		(fill yes
			(thermal_gap 0.5)
			(thermal_bridge_width 0.5)
			(island_removal_mode 0)
		)
		(polygon
			(pts
				(arc
					(start 33.026096 -288.285428)
					(mid 32.365696 -288.285428)
					(end 33.026096 -288.285428)
				)
			)
		)
	)
	(zone
		(layers "In1.Cu" "In2.Cu")
		(hatch none 0.5)
		(connect_pads
			(clearance 0)
		)
		(min_thickness 0.25)
		(keepout
			(tracks not_allowed)
			(vias allowed)
			(pads allowed)
			(copperpour not_allowed)
			(footprints allowed)
		)
		(placement
			(enabled no)
			(sheetname "")
		)
		(fill yes
			(thermal_gap 0.5)
			(thermal_bridge_width 0.5)
			(island_removal_mode 0)
		)
		(polygon
			(pts
				(arc
					(start 33.026096 -295.9354)
					(mid 32.365696 -295.9354)
					(end 33.026096 -295.9354)
				)
			)
		)
	)
	(zone
		(layers "In1.Cu" "In2.Cu")
		(hatch none 0.5)
		(connect_pads
			(clearance 0)
		)
		(min_thickness 0.25)
		(keepout
			(tracks not_allowed)
			(vias allowed)
			(pads allowed)
			(copperpour not_allowed)
			(footprints allowed)
		)
		(placement
			(enabled no)
			(sheetname "")
		)
		(fill yes
			(thermal_gap 0.5)
			(thermal_bridge_width 0.5)
			(island_removal_mode 0)
		)
		(polygon
			(pts
				(arc
					(start 194.934332 -246.63527)
					(mid 194.273932 -246.63527)
					(end 194.934332 -246.63527)
				)
			)
		)
	)
	(zone
		(layers "In1.Cu" "In2.Cu")
		(hatch none 0.5)
		(connect_pads
			(clearance 0)
		)
		(min_thickness 0.25)
		(keepout
			(tracks not_allowed)
			(vias allowed)
			(pads allowed)
			(copperpour not_allowed)
			(footprints allowed)
		)
		(placement
			(enabled no)
			(sheetname "")
		)
		(fill yes
			(thermal_gap 0.5)
			(thermal_bridge_width 0.5)
			(island_removal_mode 0)
		)
		(polygon
			(pts
				(arc
					(start 194.934332 -316.33541)
					(mid 194.273932 -316.33541)
					(end 194.934332 -316.33541)
				)
			)
		)
	)
	(zone
		(layers "In1.Cu" "In2.Cu")
		(hatch none 0.5)
		(connect_pads
			(clearance 0)
		)
		(min_thickness 0.25)
		(keepout
			(tracks not_allowed)
			(vias allowed)
			(pads allowed)
			(copperpour not_allowed)
			(footprints allowed)
		)
		(placement
			(enabled no)
			(sheetname "")
		)
		(fill yes
			(thermal_gap 0.5)
			(thermal_bridge_width 0.5)
			(island_removal_mode 0)
		)
		(polygon
			(pts
				(arc
					(start 450.4182 -209.23504)
					(mid 449.7578 -209.23504)
					(end 450.4182 -209.23504)
				)
			)
		)
	)
	(zone
		(layers "In1.Cu" "In2.Cu")
		(hatch none 0.5)
		(connect_pads
			(clearance 0)
		)
		(min_thickness 0.25)
		(keepout
			(tracks not_allowed)
			(vias allowed)
			(pads allowed)
			(copperpour not_allowed)
			(footprints allowed)
		)
		(placement
			(enabled no)
			(sheetname "")
		)
		(fill yes
			(thermal_gap 0.5)
			(thermal_bridge_width 0.5)
			(island_removal_mode 0)
		)
		(polygon
			(pts
				(arc
					(start 179.846224 -243.235226)
					(mid 179.185824 -243.235226)
					(end 179.846224 -243.235226)
				)
			)
		)
	)
	(zone
		(layers "In1.Cu" "In2.Cu")
		(hatch none 0.5)
		(connect_pads
			(clearance 0)
		)
		(min_thickness 0.25)
		(keepout
			(tracks not_allowed)
			(vias allowed)
			(pads allowed)
			(copperpour not_allowed)
			(footprints allowed)
		)
		(placement
			(enabled no)
			(sheetname "")
		)
		(fill yes
			(thermal_gap 0.5)
			(thermal_bridge_width 0.5)
			(island_removal_mode 0)
		)
		(polygon
			(pts
				(arc
					(start 424.342306 -269.585186)
					(mid 423.681906 -269.585186)
					(end 424.342306 -269.585186)
				)
			)
		)
	)
	(zone
		(layers "In1.Cu" "In2.Cu")
		(hatch none 0.5)
		(connect_pads
			(clearance 0)
		)
		(min_thickness 0.25)
		(keepout
			(tracks not_allowed)
			(vias allowed)
			(pads allowed)
			(copperpour not_allowed)
			(footprints allowed)
		)
		(placement
			(enabled no)
			(sheetname "")
		)
		(fill yes
			(thermal_gap 0.5)
			(thermal_bridge_width 0.5)
			(island_removal_mode 0)
		)
		(polygon
			(pts
				(arc
					(start 176.402238 -267.885418)
					(mid 175.741838 -267.885418)
					(end 176.402238 -267.885418)
				)
			)
		)
	)
	(zone
		(layers "In1.Cu" "In2.Cu")
		(hatch none 0.5)
		(connect_pads
			(clearance 0)
		)
		(min_thickness 0.25)
		(keepout
			(tracks not_allowed)
			(vias allowed)
			(pads allowed)
			(copperpour not_allowed)
			(footprints allowed)
		)
		(placement
			(enabled no)
			(sheetname "")
		)
		(fill yes
			(thermal_gap 0.5)
			(thermal_bridge_width 0.5)
			(island_removal_mode 0)
		)
		(polygon
			(pts
				(arc
					(start 180.121814 -44.884848)
					(mid 180.112578 -44.904772)
					(end 180.109368 -44.926504)
				)
				(arc
					(start 180.109368 -45.121068)
					(mid 180.131686 -45.17495)
					(end 180.185568 -45.197268)
				)
				(arc
					(start 180.871368 -45.197268)
					(mid 180.92525 -45.17495)
					(end 180.947568 -45.121068)
				)
				(arc
					(start 180.947568 -44.926504)
					(mid 180.9444 -44.90476)
					(end 180.935122 -44.884848)
				)
				(arc
					(start 180.742336 -44.588684)
					(mid 180.730114 -44.547)
					(end 180.74259 -44.505372)
				)
				(arc
					(start 180.935122 -44.211748)
					(mid 180.944358 -44.191824)
					(end 180.947568 -44.170092)
				)
				(arc
					(start 180.947568 -43.975528)
					(mid 180.92525 -43.921646)
					(end 180.871368 -43.899328)
				)
				(arc
					(start 180.185568 -43.899328)
					(mid 180.131686 -43.921646)
					(end 180.109368 -43.975528)
				)
				(arc
					(start 180.109368 -44.171362)
					(mid 180.112536 -44.193106)
					(end 180.121814 -44.213018)
				)
				(arc
					(start 180.314346 -44.506642)
					(mid 180.326748 -44.548298)
					(end 180.314346 -44.589954)
				)
			)
		)
	)
	(zone
		(layers "In1.Cu" "In2.Cu")
		(hatch none 0.5)
		(connect_pads
			(clearance 0)
		)
		(min_thickness 0.25)
		(keepout
			(tracks not_allowed)
			(vias allowed)
			(pads allowed)
			(copperpour not_allowed)
			(footprints allowed)
		)
		(placement
			(enabled no)
			(sheetname "")
		)
		(fill yes
			(thermal_gap 0.5)
			(thermal_bridge_width 0.5)
			(island_removal_mode 0)
		)
		(polygon
			(pts
				(arc
					(start 22.03831 -276.385274)
					(mid 21.37791 -276.385274)
					(end 22.03831 -276.385274)
				)
			)
		)
	)
	(zone
		(layers "In1.Cu" "In2.Cu")
		(hatch none 0.5)
		(connect_pads
			(clearance 0)
		)
		(min_thickness 0.25)
		(keepout
			(tracks not_allowed)
			(vias allowed)
			(pads allowed)
			(copperpour not_allowed)
			(footprints allowed)
		)
		(placement
			(enabled no)
			(sheetname "")
		)
		(fill yes
			(thermal_gap 0.5)
			(thermal_bridge_width 0.5)
			(island_removal_mode 0)
		)
		(polygon
			(pts
				(arc
					(start 199.0344 -216.035382)
					(mid 198.374 -216.035382)
					(end 199.0344 -216.035382)
				)
			)
		)
	)
	(zone
		(layers "In1.Cu" "In2.Cu")
		(hatch none 0.5)
		(connect_pads
			(clearance 0)
		)
		(min_thickness 0.25)
		(keepout
			(tracks not_allowed)
			(vias allowed)
			(pads allowed)
			(copperpour not_allowed)
			(footprints allowed)
		)
		(placement
			(enabled no)
			(sheetname "")
		)
		(fill yes
			(thermal_gap 0.5)
			(thermal_bridge_width 0.5)
			(island_removal_mode 0)
		)
		(polygon
			(pts
				(arc
					(start 273.422364 -232.184956)
					(mid 272.761964 -232.184956)
					(end 273.422364 -232.184956)
				)
			)
		)
	)
	(zone
		(layers "In1.Cu" "In2.Cu")
		(hatch none 0.5)
		(connect_pads
			(clearance 0)
		)
		(min_thickness 0.25)
		(keepout
			(tracks not_allowed)
			(vias allowed)
			(pads allowed)
			(copperpour not_allowed)
			(footprints allowed)
		)
		(placement
			(enabled no)
			(sheetname "")
		)
		(fill yes
			(thermal_gap 0.5)
			(thermal_bridge_width 0.5)
			(island_removal_mode 0)
		)
		(polygon
			(pts
				(arc
					(start 44.670218 -245.785386)
					(mid 44.009818 -245.785386)
					(end 44.670218 -245.785386)
				)
			)
		)
	)
	(zone
		(layers "In1.Cu" "In2.Cu")
		(hatch none 0.5)
		(connect_pads
			(clearance 0)
		)
		(min_thickness 0.25)
		(keepout
			(tracks not_allowed)
			(vias allowed)
			(pads allowed)
			(copperpour not_allowed)
			(footprints allowed)
		)
		(placement
			(enabled no)
			(sheetname "")
		)
		(fill yes
			(thermal_gap 0.5)
			(thermal_bridge_width 0.5)
			(island_removal_mode 0)
		)
		(polygon
			(pts
				(arc
					(start 277.522432 -289.135058)
					(mid 276.862032 -289.135058)
					(end 277.522432 -289.135058)
				)
			)
		)
	)
	(zone
		(layers "In1.Cu" "In2.Cu")
		(hatch none 0.5)
		(connect_pads
			(clearance 0)
		)
		(min_thickness 0.25)
		(keepout
			(tracks not_allowed)
			(vias allowed)
			(pads allowed)
			(copperpour not_allowed)
			(footprints allowed)
		)
		(placement
			(enabled no)
			(sheetname "")
		)
		(fill yes
			(thermal_gap 0.5)
			(thermal_bridge_width 0.5)
			(island_removal_mode 0)
		)
		(polygon
			(pts
				(arc
					(start 446.974468 -216.035128)
					(mid 446.314068 -216.035128)
					(end 446.974468 -216.035128)
				)
			)
		)
	)
	(zone
		(layers "In1.Cu" "In2.Cu")
		(hatch none 0.5)
		(connect_pads
			(clearance 0)
		)
		(min_thickness 0.25)
		(keepout
			(tracks not_allowed)
			(vias allowed)
			(pads allowed)
			(copperpour not_allowed)
			(footprints allowed)
		)
		(placement
			(enabled no)
			(sheetname "")
		)
		(fill yes
			(thermal_gap 0.5)
			(thermal_bridge_width 0.5)
			(island_removal_mode 0)
		)
		(polygon
			(pts
				(arc
					(start 454.518268 -214.335106)
					(mid 453.857868 -214.335106)
					(end 454.518268 -214.335106)
				)
			)
		)
	)
	(zone
		(layers "In1.Cu" "In2.Cu")
		(hatch none 0.5)
		(connect_pads
			(clearance 0)
		)
		(min_thickness 0.25)
		(keepout
			(tracks not_allowed)
			(vias allowed)
			(pads allowed)
			(copperpour not_allowed)
			(footprints allowed)
		)
		(placement
			(enabled no)
			(sheetname "")
		)
		(fill yes
			(thermal_gap 0.5)
			(thermal_bridge_width 0.5)
			(island_removal_mode 0)
		)
		(polygon
			(pts
				(arc
					(start 14.418564 -423.80535)
					(mid 14.433443 -423.769429)
					(end 14.469364 -423.75455)
				)
				(arc
					(start 14.977364 -423.75455)
					(mid 15.013285 -423.769429)
					(end 15.028164 -423.80535)
				)
				(arc
					(start 15.028164 -424.461686)
					(mid 15.013285 -424.497607)
					(end 14.977364 -424.512486)
				)
				(arc
					(start 14.469364 -424.512486)
					(mid 14.433443 -424.497607)
					(end 14.418564 -424.461686)
				)
			)
		)
	)
	(zone
		(layers "In1.Cu" "In2.Cu")
		(hatch none 0.5)
		(connect_pads
			(clearance 0)
		)
		(min_thickness 0.25)
		(keepout
			(tracks not_allowed)
			(vias allowed)
			(pads allowed)
			(copperpour not_allowed)
			(footprints allowed)
		)
		(placement
			(enabled no)
			(sheetname "")
		)
		(fill yes
			(thermal_gap 0.5)
			(thermal_bridge_width 0.5)
			(island_removal_mode 0)
		)
		(polygon
			(pts
				(arc
					(start 435.330346 -213.484968)
					(mid 434.669946 -213.484968)
					(end 435.330346 -213.484968)
				)
			)
		)
	)
	(zone
		(layers "In1.Cu" "In2.Cu")
		(hatch none 0.5)
		(connect_pads
			(clearance 0)
		)
		(min_thickness 0.25)
		(keepout
			(tracks not_allowed)
			(vias allowed)
			(pads allowed)
			(copperpour not_allowed)
			(footprints allowed)
		)
		(placement
			(enabled no)
			(sheetname "")
		)
		(fill yes
			(thermal_gap 0.5)
			(thermal_bridge_width 0.5)
			(island_removal_mode 0)
		)
		(polygon
			(pts
				(arc
					(start 22.03831 -247.485408)
					(mid 21.37791 -247.485408)
					(end 22.03831 -247.485408)
				)
			)
		)
	)
	(zone
		(layers "In1.Cu" "In2.Cu")
		(hatch none 0.5)
		(connect_pads
			(clearance 0)
		)
		(min_thickness 0.25)
		(keepout
			(tracks not_allowed)
			(vias allowed)
			(pads allowed)
			(copperpour not_allowed)
			(footprints allowed)
		)
		(placement
			(enabled no)
			(sheetname "")
		)
		(fill yes
			(thermal_gap 0.5)
			(thermal_bridge_width 0.5)
			(island_removal_mode 0)
		)
		(polygon
			(pts
				(arc
					(start 199.0344 -210.935316)
					(mid 198.374 -210.935316)
					(end 199.0344 -210.935316)
				)
			)
		)
	)
	(zone
		(layers "In1.Cu" "In2.Cu")
		(hatch none 0.5)
		(connect_pads
			(clearance 0)
		)
		(min_thickness 0.25)
		(keepout
			(tracks not_allowed)
			(vias allowed)
			(pads allowed)
			(copperpour not_allowed)
			(footprints allowed)
		)
		(placement
			(enabled no)
			(sheetname "")
		)
		(fill yes
			(thermal_gap 0.5)
			(thermal_bridge_width 0.5)
			(island_removal_mode 0)
		)
		(polygon
			(pts
				(arc
					(start 199.0344 -266.185396)
					(mid 198.374 -266.185396)
					(end 199.0344 -266.185396)
				)
			)
		)
	)
	(zone
		(layers "In1.Cu" "In2.Cu")
		(hatch none 0.5)
		(connect_pads
			(clearance 0)
		)
		(min_thickness 0.25)
		(keepout
			(tracks not_allowed)
			(vias allowed)
			(pads allowed)
			(copperpour not_allowed)
			(footprints allowed)
		)
		(placement
			(enabled no)
			(sheetname "")
		)
		(fill yes
			(thermal_gap 0.5)
			(thermal_bridge_width 0.5)
			(island_removal_mode 0)
		)
		(polygon
			(pts
				(arc
					(start 446.974468 -311.23509)
					(mid 446.314068 -311.23509)
					(end 446.974468 -311.23509)
				)
			)
		)
	)
	(zone
		(layers "In1.Cu" "In2.Cu")
		(hatch none 0.5)
		(connect_pads
			(clearance 0)
		)
		(min_thickness 0.25)
		(keepout
			(tracks not_allowed)
			(vias allowed)
			(pads allowed)
			(copperpour not_allowed)
			(footprints allowed)
		)
		(placement
			(enabled no)
			(sheetname "")
		)
		(fill yes
			(thermal_gap 0.5)
			(thermal_bridge_width 0.5)
			(island_removal_mode 0)
		)
		(polygon
			(pts
				(arc
					(start 29.582364 -317.185294)
					(mid 28.921964 -317.185294)
					(end 29.582364 -317.185294)
				)
			)
		)
	)
	(zone
		(layers "In1.Cu" "In2.Cu")
		(hatch none 0.5)
		(connect_pads
			(clearance 0)
		)
		(min_thickness 0.25)
		(keepout
			(tracks not_allowed)
			(vias allowed)
			(pads allowed)
			(copperpour not_allowed)
			(footprints allowed)
		)
		(placement
			(enabled no)
			(sheetname "")
		)
		(fill yes
			(thermal_gap 0.5)
			(thermal_bridge_width 0.5)
			(island_removal_mode 0)
		)
		(polygon
			(pts
				(arc
					(start 420.242238 -246.635016)
					(mid 419.581838 -246.635016)
					(end 420.242238 -246.635016)
				)
			)
		)
	)
	(zone
		(layers "In1.Cu" "In2.Cu")
		(hatch none 0.5)
		(connect_pads
			(clearance 0)
		)
		(min_thickness 0.25)
		(keepout
			(tracks not_allowed)
			(vias allowed)
			(pads allowed)
			(copperpour not_allowed)
			(footprints allowed)
		)
		(placement
			(enabled no)
			(sheetname "")
		)
		(fill yes
			(thermal_gap 0.5)
			(thermal_bridge_width 0.5)
			(island_removal_mode 0)
		)
		(polygon
			(pts
				(arc
					(start 202.478132 -299.335444)
					(mid 201.817732 -299.335444)
					(end 202.478132 -299.335444)
				)
			)
		)
	)
	(zone
		(layers "In1.Cu" "In2.Cu")
		(hatch none 0.5)
		(connect_pads
			(clearance 0)
		)
		(min_thickness 0.25)
		(keepout
			(tracks not_allowed)
			(vias allowed)
			(pads allowed)
			(copperpour not_allowed)
			(footprints allowed)
		)
		(placement
			(enabled no)
			(sheetname "")
		)
		(fill yes
			(thermal_gap 0.5)
			(thermal_bridge_width 0.5)
			(island_removal_mode 0)
		)
		(polygon
			(pts
				(arc
					(start 183.946292 -247.485408)
					(mid 183.285892 -247.485408)
					(end 183.946292 -247.485408)
				)
			)
		)
	)
	(zone
		(layers "In1.Cu" "In2.Cu")
		(hatch none 0.5)
		(connect_pads
			(clearance 0)
		)
		(min_thickness 0.25)
		(keepout
			(tracks not_allowed)
			(vias allowed)
			(pads allowed)
			(copperpour not_allowed)
			(footprints allowed)
		)
		(placement
			(enabled no)
			(sheetname "")
		)
		(fill yes
			(thermal_gap 0.5)
			(thermal_bridge_width 0.5)
			(island_removal_mode 0)
		)
		(polygon
			(pts
				(arc
					(start 40.57015 -289.98545)
					(mid 39.90975 -289.98545)
					(end 40.57015 -289.98545)
				)
			)
		)
	)
	(zone
		(layers "In1.Cu" "In2.Cu")
		(hatch none 0.5)
		(connect_pads
			(clearance 0)
		)
		(min_thickness 0.25)
		(keepout
			(tracks not_allowed)
			(vias allowed)
			(pads allowed)
			(copperpour not_allowed)
			(footprints allowed)
		)
		(placement
			(enabled no)
			(sheetname "")
		)
		(fill yes
			(thermal_gap 0.5)
			(thermal_bridge_width 0.5)
			(island_removal_mode 0)
		)
		(polygon
			(pts
				(arc
					(start 37.126164 -217.735404)
					(mid 36.465764 -217.735404)
					(end 37.126164 -217.735404)
				)
			)
		)
	)
	(zone
		(layers "In1.Cu" "In2.Cu")
		(hatch none 0.5)
		(connect_pads
			(clearance 0)
		)
		(min_thickness 0.25)
		(keepout
			(tracks not_allowed)
			(vias allowed)
			(pads allowed)
			(copperpour not_allowed)
			(footprints allowed)
		)
		(placement
			(enabled no)
			(sheetname "")
		)
		(fill yes
			(thermal_gap 0.5)
			(thermal_bridge_width 0.5)
			(island_removal_mode 0)
		)
		(polygon
			(pts
				(arc
					(start 296.054272 -282.33497)
					(mid 295.393872 -282.33497)
					(end 296.054272 -282.33497)
				)
			)
		)
	)
	(zone
		(layers "In1.Cu" "In2.Cu")
		(hatch none 0.5)
		(connect_pads
			(clearance 0)
		)
		(min_thickness 0.25)
		(keepout
			(tracks not_allowed)
			(vias allowed)
			(pads allowed)
			(copperpour not_allowed)
			(footprints allowed)
		)
		(placement
			(enabled no)
			(sheetname "")
		)
		(fill yes
			(thermal_gap 0.5)
			(thermal_bridge_width 0.5)
			(island_removal_mode 0)
		)
		(polygon
			(pts
				(arc
					(start 37.126164 -203.285344)
					(mid 36.465764 -203.285344)
					(end 37.126164 -203.285344)
				)
			)
		)
	)
	(zone
		(layers "In1.Cu" "In2.Cu")
		(hatch none 0.5)
		(connect_pads
			(clearance 0)
		)
		(min_thickness 0.25)
		(keepout
			(tracks not_allowed)
			(vias allowed)
			(pads allowed)
			(copperpour not_allowed)
			(footprints allowed)
		)
		(placement
			(enabled no)
			(sheetname "")
		)
		(fill yes
			(thermal_gap 0.5)
			(thermal_bridge_width 0.5)
			(island_removal_mode 0)
		)
		(polygon
			(pts
				(arc
					(start 424.342306 -306.135024)
					(mid 423.681906 -306.135024)
					(end 424.342306 -306.135024)
				)
			)
		)
	)
	(zone
		(layers "In1.Cu" "In2.Cu")
		(hatch none 0.5)
		(connect_pads
			(clearance 0)
		)
		(min_thickness 0.25)
		(keepout
			(tracks not_allowed)
			(vias allowed)
			(pads allowed)
			(copperpour not_allowed)
			(footprints allowed)
		)
		(placement
			(enabled no)
			(sheetname "")
		)
		(fill yes
			(thermal_gap 0.5)
			(thermal_bridge_width 0.5)
			(island_removal_mode 0)
		)
		(polygon
			(pts
				(arc
					(start 131.50088 -26.57348)
					(mid 131.464959 -26.588359)
					(end 131.45008 -26.62428)
				)
				(arc
					(start 131.45008 -27.89428)
					(mid 131.464959 -27.930201)
					(end 131.50088 -27.94508)
				)
				(arc
					(start 131.78028 -27.94508)
					(mid 131.816201 -27.930201)
					(end 131.83108 -27.89428)
				)
				(arc
					(start 131.83108 -26.62428)
					(mid 131.816201 -26.588359)
					(end 131.78028 -26.57348)
				)
			)
		)
	)
	(zone
		(layers "In1.Cu" "In2.Cu")
		(hatch none 0.5)
		(connect_pads
			(clearance 0)
		)
		(min_thickness 0.25)
		(keepout
			(tracks not_allowed)
			(vias allowed)
			(pads allowed)
			(copperpour not_allowed)
			(footprints allowed)
		)
		(placement
			(enabled no)
			(sheetname "")
		)
		(fill yes
			(thermal_gap 0.5)
			(thermal_bridge_width 0.5)
			(island_removal_mode 0)
		)
		(polygon
			(pts
				(arc
					(start 288.510218 -316.335156)
					(mid 287.849818 -316.335156)
					(end 288.510218 -316.335156)
				)
			)
		)
	)
	(zone
		(layers "In1.Cu" "In2.Cu")
		(hatch none 0.5)
		(connect_pads
			(clearance 0)
		)
		(min_thickness 0.25)
		(keepout
			(tracks not_allowed)
			(vias allowed)
			(pads allowed)
			(copperpour not_allowed)
			(footprints allowed)
		)
		(placement
			(enabled no)
			(sheetname "")
		)
		(fill yes
			(thermal_gap 0.5)
			(thermal_bridge_width 0.5)
			(island_removal_mode 0)
		)
		(polygon
			(pts
				(arc
					(start 427.786292 -213.484968)
					(mid 427.125892 -213.484968)
					(end 427.786292 -213.484968)
				)
			)
		)
	)
	(zone
		(layers "In1.Cu" "In2.Cu")
		(hatch none 0.5)
		(connect_pads
			(clearance 0)
		)
		(min_thickness 0.25)
		(keepout
			(tracks not_allowed)
			(vias allowed)
			(pads allowed)
			(copperpour not_allowed)
			(footprints allowed)
		)
		(placement
			(enabled no)
			(sheetname "")
		)
		(fill yes
			(thermal_gap 0.5)
			(thermal_bridge_width 0.5)
			(island_removal_mode 0)
		)
		(polygon
			(pts
				(arc
					(start 277.522432 -206.685134)
					(mid 276.862032 -206.685134)
					(end 277.522432 -206.685134)
				)
			)
		)
	)
	(zone
		(layers "In1.Cu" "In2.Cu")
		(hatch none 0.5)
		(connect_pads
			(clearance 0)
		)
		(min_thickness 0.25)
		(keepout
			(tracks not_allowed)
			(vias allowed)
			(pads allowed)
			(copperpour not_allowed)
			(footprints allowed)
		)
		(placement
			(enabled no)
			(sheetname "")
		)
		(fill yes
			(thermal_gap 0.5)
			(thermal_bridge_width 0.5)
			(island_removal_mode 0)
		)
		(polygon
			(pts
				(arc
					(start 191.490346 -262.785352)
					(mid 190.829946 -262.785352)
					(end 191.490346 -262.785352)
				)
			)
		)
	)
	(zone
		(layers "In1.Cu" "In2.Cu")
		(hatch none 0.5)
		(connect_pads
			(clearance 0)
		)
		(min_thickness 0.25)
		(keepout
			(tracks not_allowed)
			(vias allowed)
			(pads allowed)
			(copperpour not_allowed)
			(footprints allowed)
		)
		(placement
			(enabled no)
			(sheetname "")
		)
		(fill yes
			(thermal_gap 0.5)
			(thermal_bridge_width 0.5)
			(island_removal_mode 0)
		)
		(polygon
			(pts
				(arc
					(start 431.88636 -295.085008)
					(mid 431.22596 -295.085008)
					(end 431.88636 -295.085008)
				)
			)
		)
	)
	(zone
		(layers "In1.Cu" "In2.Cu")
		(hatch none 0.5)
		(connect_pads
			(clearance 0)
		)
		(min_thickness 0.25)
		(keepout
			(tracks not_allowed)
			(vias allowed)
			(pads allowed)
			(copperpour not_allowed)
			(footprints allowed)
		)
		(placement
			(enabled no)
			(sheetname "")
		)
		(fill yes
			(thermal_gap 0.5)
			(thermal_bridge_width 0.5)
			(island_removal_mode 0)
		)
		(polygon
			(pts
				(arc
					(start 22.03831 -287.43529)
					(mid 21.37791 -287.43529)
					(end 22.03831 -287.43529)
				)
			)
		)
	)
	(zone
		(layers "In1.Cu" "In2.Cu")
		(hatch none 0.5)
		(connect_pads
			(clearance 0)
		)
		(min_thickness 0.25)
		(keepout
			(tracks not_allowed)
			(vias allowed)
			(pads allowed)
			(copperpour not_allowed)
			(footprints allowed)
		)
		(placement
			(enabled no)
			(sheetname "")
		)
		(fill yes
			(thermal_gap 0.5)
			(thermal_bridge_width 0.5)
			(island_removal_mode 0)
		)
		(polygon
			(pts
				(arc
					(start 296.054272 -295.935146)
					(mid 295.393872 -295.935146)
					(end 296.054272 -295.935146)
				)
			)
		)
	)
	(zone
		(layers "In1.Cu" "In2.Cu")
		(hatch none 0.5)
		(connect_pads
			(clearance 0)
		)
		(min_thickness 0.25)
		(keepout
			(tracks not_allowed)
			(vias allowed)
			(pads allowed)
			(copperpour not_allowed)
			(footprints allowed)
		)
		(placement
			(enabled no)
			(sheetname "")
		)
		(fill yes
			(thermal_gap 0.5)
			(thermal_bridge_width 0.5)
			(island_removal_mode 0)
		)
		(polygon
			(pts
				(arc
					(start 269.978378 -216.035128)
					(mid 269.317978 -216.035128)
					(end 269.978378 -216.035128)
				)
			)
		)
	)
	(zone
		(layers "In1.Cu" "In2.Cu")
		(hatch none 0.5)
		(connect_pads
			(clearance 0)
		)
		(min_thickness 0.25)
		(keepout
			(tracks not_allowed)
			(vias allowed)
			(pads allowed)
			(copperpour not_allowed)
			(footprints allowed)
		)
		(placement
			(enabled no)
			(sheetname "")
		)
		(fill yes
			(thermal_gap 0.5)
			(thermal_bridge_width 0.5)
			(island_removal_mode 0)
		)
		(polygon
			(pts
				(arc
					(start 40.57015 -199.8853)
					(mid 39.90975 -199.8853)
					(end 40.57015 -199.8853)
				)
			)
		)
	)
	(zone
		(layers "In1.Cu" "In2.Cu")
		(hatch none 0.5)
		(connect_pads
			(clearance 0)
		)
		(min_thickness 0.25)
		(keepout
			(tracks not_allowed)
			(vias allowed)
			(pads allowed)
			(copperpour not_allowed)
			(footprints allowed)
		)
		(placement
			(enabled no)
			(sheetname "")
		)
		(fill yes
			(thermal_gap 0.5)
			(thermal_bridge_width 0.5)
			(island_removal_mode 0)
		)
		(polygon
			(pts
				(arc
					(start 22.03831 -234.73537)
					(mid 21.37791 -234.73537)
					(end 22.03831 -234.73537)
				)
			)
		)
	)
	(zone
		(layers "In1.Cu" "In2.Cu")
		(hatch none 0.5)
		(connect_pads
			(clearance 0)
		)
		(min_thickness 0.25)
		(keepout
			(tracks not_allowed)
			(vias allowed)
			(pads allowed)
			(copperpour not_allowed)
			(footprints allowed)
		)
		(placement
			(enabled no)
			(sheetname "")
		)
		(fill yes
			(thermal_gap 0.5)
			(thermal_bridge_width 0.5)
			(island_removal_mode 0)
		)
		(polygon
			(pts
				(arc
					(start 435.330346 -276.38502)
					(mid 434.669946 -276.38502)
					(end 435.330346 -276.38502)
				)
			)
		)
	)
	(zone
		(layers "In1.Cu" "In2.Cu")
		(hatch none 0.5)
		(connect_pads
			(clearance 0)
		)
		(min_thickness 0.25)
		(keepout
			(tracks not_allowed)
			(vias allowed)
			(pads allowed)
			(copperpour not_allowed)
			(footprints allowed)
		)
		(placement
			(enabled no)
			(sheetname "")
		)
		(fill yes
			(thermal_gap 0.5)
			(thermal_bridge_width 0.5)
			(island_removal_mode 0)
		)
		(polygon
			(pts
				(arc
					(start 285.066232 -296.78503)
					(mid 284.405832 -296.78503)
					(end 285.066232 -296.78503)
				)
			)
		)
	)
	(zone
		(layers "In1.Cu" "In2.Cu")
		(hatch none 0.5)
		(connect_pads
			(clearance 0)
		)
		(min_thickness 0.25)
		(keepout
			(tracks not_allowed)
			(vias allowed)
			(pads allowed)
			(copperpour not_allowed)
			(footprints allowed)
		)
		(placement
			(enabled no)
			(sheetname "")
		)
		(fill yes
			(thermal_gap 0.5)
			(thermal_bridge_width 0.5)
			(island_removal_mode 0)
		)
		(polygon
			(pts
				(arc
					(start 37.126164 -307.8353)
					(mid 36.465764 -307.8353)
					(end 37.126164 -307.8353)
				)
			)
		)
	)
	(zone
		(layers "In1.Cu" "In2.Cu")
		(hatch none 0.5)
		(connect_pads
			(clearance 0)
		)
		(min_thickness 0.25)
		(keepout
			(tracks not_allowed)
			(vias allowed)
			(pads allowed)
			(copperpour not_allowed)
			(footprints allowed)
		)
		(placement
			(enabled no)
			(sheetname "")
		)
		(fill yes
			(thermal_gap 0.5)
			(thermal_bridge_width 0.5)
			(island_removal_mode 0)
		)
		(polygon
			(pts
				(arc
					(start 187.390278 -211.7852)
					(mid 186.729878 -211.7852)
					(end 187.390278 -211.7852)
				)
			)
		)
	)
	(zone
		(layers "In1.Cu" "In2.Cu")
		(hatch none 0.5)
		(connect_pads
			(clearance 0)
		)
		(min_thickness 0.25)
		(keepout
			(tracks not_allowed)
			(vias allowed)
			(pads allowed)
			(copperpour not_allowed)
			(footprints allowed)
		)
		(placement
			(enabled no)
			(sheetname "")
		)
		(fill yes
			(thermal_gap 0.5)
			(thermal_bridge_width 0.5)
			(island_removal_mode 0)
		)
		(polygon
			(pts
				(arc
					(start 424.342306 -210.935062)
					(mid 423.681906 -210.935062)
					(end 424.342306 -210.935062)
				)
			)
		)
	)
	(zone
		(layers "In1.Cu" "In2.Cu")
		(hatch none 0.5)
		(connect_pads
			(clearance 0)
		)
		(min_thickness 0.25)
		(keepout
			(tracks not_allowed)
			(vias allowed)
			(pads allowed)
			(copperpour not_allowed)
			(footprints allowed)
		)
		(placement
			(enabled no)
			(sheetname "")
		)
		(fill yes
			(thermal_gap 0.5)
			(thermal_bridge_width 0.5)
			(island_removal_mode 0)
		)
		(polygon
			(pts
				(arc
					(start 52.214272 -204.985366)
					(mid 51.553872 -204.985366)
					(end 52.214272 -204.985366)
				)
			)
		)
	)
	(zone
		(layers "In1.Cu" "In2.Cu")
		(hatch none 0.5)
		(connect_pads
			(clearance 0)
		)
		(min_thickness 0.25)
		(keepout
			(tracks not_allowed)
			(vias allowed)
			(pads allowed)
			(copperpour not_allowed)
			(footprints allowed)
		)
		(placement
			(enabled no)
			(sheetname "")
		)
		(fill yes
			(thermal_gap 0.5)
			(thermal_bridge_width 0.5)
			(island_removal_mode 0)
		)
		(polygon
			(pts
				(arc
					(start 191.490346 -245.785386)
					(mid 190.829946 -245.785386)
					(end 191.490346 -245.785386)
				)
			)
		)
	)
	(zone
		(layers "In1.Cu" "In2.Cu")
		(hatch none 0.5)
		(connect_pads
			(clearance 0)
		)
		(min_thickness 0.25)
		(keepout
			(tracks not_allowed)
			(vias allowed)
			(pads allowed)
			(copperpour not_allowed)
			(footprints allowed)
		)
		(placement
			(enabled no)
			(sheetname "")
		)
		(fill yes
			(thermal_gap 0.5)
			(thermal_bridge_width 0.5)
			(island_removal_mode 0)
		)
		(polygon
			(pts
				(arc
					(start 172.30217 -310.385206)
					(mid 171.64177 -310.385206)
					(end 172.30217 -310.385206)
				)
			)
		)
	)
	(zone
		(layers "In1.Cu" "In2.Cu")
		(hatch none 0.5)
		(connect_pads
			(clearance 0)
		)
		(min_thickness 0.25)
		(keepout
			(tracks not_allowed)
			(vias allowed)
			(pads allowed)
			(copperpour not_allowed)
			(footprints allowed)
		)
		(placement
			(enabled no)
			(sheetname "")
		)
		(fill yes
			(thermal_gap 0.5)
			(thermal_bridge_width 0.5)
			(island_removal_mode 0)
		)
		(polygon
			(pts
				(arc
					(start 176.402238 -200.735438)
					(mid 175.741838 -200.735438)
					(end 176.402238 -200.735438)
				)
			)
		)
	)
	(zone
		(layers "In1.Cu" "In2.Cu")
		(hatch none 0.5)
		(connect_pads
			(clearance 0)
		)
		(min_thickness 0.25)
		(keepout
			(tracks not_allowed)
			(vias allowed)
			(pads allowed)
			(copperpour not_allowed)
			(footprints allowed)
		)
		(placement
			(enabled no)
			(sheetname "")
		)
		(fill yes
			(thermal_gap 0.5)
			(thermal_bridge_width 0.5)
			(island_removal_mode 0)
		)
		(polygon
			(pts
				(arc
					(start 37.126164 -279.785318)
					(mid 36.465764 -279.785318)
					(end 37.126164 -279.785318)
				)
			)
		)
	)
	(zone
		(layers "In1.Cu" "In2.Cu")
		(hatch none 0.5)
		(connect_pads
			(clearance 0)
		)
		(min_thickness 0.25)
		(keepout
			(tracks not_allowed)
			(vias allowed)
			(pads allowed)
			(copperpour not_allowed)
			(footprints allowed)
		)
		(placement
			(enabled no)
			(sheetname "")
		)
		(fill yes
			(thermal_gap 0.5)
			(thermal_bridge_width 0.5)
			(island_removal_mode 0)
		)
		(polygon
			(pts
				(arc
					(start 420.242238 -277.235158)
					(mid 419.581838 -277.235158)
					(end 420.242238 -277.235158)
				)
			)
		)
	)
	(zone
		(layers "In1.Cu" "In2.Cu")
		(hatch none 0.5)
		(connect_pads
			(clearance 0)
		)
		(min_thickness 0.25)
		(keepout
			(tracks not_allowed)
			(vias allowed)
			(pads allowed)
			(copperpour not_allowed)
			(footprints allowed)
		)
		(placement
			(enabled no)
			(sheetname "")
		)
		(fill yes
			(thermal_gap 0.5)
			(thermal_bridge_width 0.5)
			(island_removal_mode 0)
		)
		(polygon
			(pts
				(arc
					(start 37.126164 -298.485306)
					(mid 36.465764 -298.485306)
					(end 37.126164 -298.485306)
				)
			)
		)
	)
	(zone
		(layers "In1.Cu" "In2.Cu")
		(hatch none 0.5)
		(connect_pads
			(clearance 0)
		)
		(min_thickness 0.25)
		(keepout
			(tracks not_allowed)
			(vias allowed)
			(pads allowed)
			(copperpour not_allowed)
			(footprints allowed)
		)
		(placement
			(enabled no)
			(sheetname "")
		)
		(fill yes
			(thermal_gap 0.5)
			(thermal_bridge_width 0.5)
			(island_removal_mode 0)
		)
		(polygon
			(pts
				(arc
					(start 273.422364 -239.835182)
					(mid 272.761964 -239.835182)
					(end 273.422364 -239.835182)
				)
			)
		)
	)
	(zone
		(layers "In1.Cu" "In2.Cu")
		(hatch none 0.5)
		(connect_pads
			(clearance 0)
		)
		(min_thickness 0.25)
		(keepout
			(tracks not_allowed)
			(vias allowed)
			(pads allowed)
			(copperpour not_allowed)
			(footprints allowed)
		)
		(placement
			(enabled no)
			(sheetname "")
		)
		(fill yes
			(thermal_gap 0.5)
			(thermal_bridge_width 0.5)
			(island_removal_mode 0)
		)
		(polygon
			(pts
				(arc
					(start 183.946292 -313.78525)
					(mid 183.285892 -313.78525)
					(end 183.946292 -313.78525)
				)
			)
		)
	)
	(zone
		(layers "In1.Cu" "In2.Cu")
		(hatch none 0.5)
		(connect_pads
			(clearance 0)
		)
		(min_thickness 0.25)
		(keepout
			(tracks not_allowed)
			(vias allowed)
			(pads allowed)
			(copperpour not_allowed)
			(footprints allowed)
		)
		(placement
			(enabled no)
			(sheetname "")
		)
		(fill yes
			(thermal_gap 0.5)
			(thermal_bridge_width 0.5)
			(island_removal_mode 0)
		)
		(polygon
			(pts
				(arc
					(start 346.462096 -417.242244)
					(mid 346.484414 -417.296126)
					(end 346.538296 -417.318444)
				)
				(arc
					(start 346.733876 -417.318444)
					(mid 346.755752 -417.315312)
					(end 346.775786 -417.305998)
				)
				(arc
					(start 347.06941 -417.113466)
					(mid 347.111066 -417.101064)
					(end 347.152722 -417.113466)
				)
				(arc
					(start 347.447616 -417.305998)
					(mid 347.46754 -417.315234)
					(end 347.489272 -417.318444)
				)
				(arc
					(start 347.683836 -417.318444)
					(mid 347.737718 -417.296126)
					(end 347.760036 -417.242244)
				)
				(arc
					(start 347.760036 -416.556444)
					(mid 347.737718 -416.502562)
					(end 347.683836 -416.480244)
				)
				(arc
					(start 347.489272 -416.480244)
					(mid 347.467528 -416.483412)
					(end 347.447616 -416.49269)
				)
				(arc
					(start 347.151452 -416.685476)
					(mid 347.109768 -416.697698)
					(end 347.06814 -416.685222)
				)
				(arc
					(start 346.774516 -416.49269)
					(mid 346.754592 -416.483454)
					(end 346.73286 -416.480244)
				)
				(arc
					(start 346.538296 -416.480244)
					(mid 346.484414 -416.502562)
					(end 346.462096 -416.556444)
				)
			)
		)
	)
	(zone
		(layers "In1.Cu" "In2.Cu")
		(hatch none 0.5)
		(connect_pads
			(clearance 0)
		)
		(min_thickness 0.25)
		(keepout
			(tracks not_allowed)
			(vias allowed)
			(pads allowed)
			(copperpour not_allowed)
			(footprints allowed)
		)
		(placement
			(enabled no)
			(sheetname "")
		)
		(fill yes
			(thermal_gap 0.5)
			(thermal_bridge_width 0.5)
			(island_removal_mode 0)
		)
		(polygon
			(pts
				(arc
					(start 48.114204 -243.235226)
					(mid 47.453804 -243.235226)
					(end 48.114204 -243.235226)
				)
			)
		)
	)
	(zone
		(layers "In1.Cu" "In2.Cu")
		(hatch none 0.5)
		(connect_pads
			(clearance 0)
		)
		(min_thickness 0.25)
		(keepout
			(tracks not_allowed)
			(vias allowed)
			(pads allowed)
			(copperpour not_allowed)
			(footprints allowed)
		)
		(placement
			(enabled no)
			(sheetname "")
		)
		(fill yes
			(thermal_gap 0.5)
			(thermal_bridge_width 0.5)
			(island_removal_mode 0)
		)
		(polygon
			(pts
				(arc
					(start 199.0344 -231.335326)
					(mid 198.374 -231.335326)
					(end 199.0344 -231.335326)
				)
			)
		)
	)
	(zone
		(layers "In1.Cu" "In2.Cu")
		(hatch none 0.5)
		(connect_pads
			(clearance 0)
		)
		(min_thickness 0.25)
		(keepout
			(tracks not_allowed)
			(vias allowed)
			(pads allowed)
			(copperpour not_allowed)
			(footprints allowed)
		)
		(placement
			(enabled no)
			(sheetname "")
		)
		(fill yes
			(thermal_gap 0.5)
			(thermal_bridge_width 0.5)
			(island_removal_mode 0)
		)
		(polygon
			(pts
				(arc
					(start 37.126164 -301.88535)
					(mid 36.465764 -301.88535)
					(end 37.126164 -301.88535)
				)
			)
		)
	)
	(zone
		(layers "In1.Cu" "In2.Cu")
		(hatch none 0.5)
		(connect_pads
			(clearance 0)
		)
		(min_thickness 0.25)
		(keepout
			(tracks not_allowed)
			(vias allowed)
			(pads allowed)
			(copperpour not_allowed)
			(footprints allowed)
		)
		(placement
			(enabled no)
			(sheetname "")
		)
		(fill yes
			(thermal_gap 0.5)
			(thermal_bridge_width 0.5)
			(island_removal_mode 0)
		)
		(polygon
			(pts
				(arc
					(start 424.342306 -301.885096)
					(mid 423.681906 -301.885096)
					(end 424.342306 -301.885096)
				)
			)
		)
	)
	(zone
		(layers "In1.Cu" "In2.Cu")
		(hatch none 0.5)
		(connect_pads
			(clearance 0)
		)
		(min_thickness 0.25)
		(keepout
			(tracks not_allowed)
			(vias allowed)
			(pads allowed)
			(copperpour not_allowed)
			(footprints allowed)
		)
		(placement
			(enabled no)
			(sheetname "")
		)
		(fill yes
			(thermal_gap 0.5)
			(thermal_bridge_width 0.5)
			(island_removal_mode 0)
		)
		(polygon
			(pts
				(arc
					(start 172.30217 -213.485222)
					(mid 171.64177 -213.485222)
					(end 172.30217 -213.485222)
				)
			)
		)
	)
	(zone
		(layers "In1.Cu" "In2.Cu")
		(hatch none 0.5)
		(connect_pads
			(clearance 0)
		)
		(min_thickness 0.25)
		(keepout
			(tracks not_allowed)
			(vias allowed)
			(pads allowed)
			(copperpour not_allowed)
			(footprints allowed)
		)
		(placement
			(enabled no)
			(sheetname "")
		)
		(fill yes
			(thermal_gap 0.5)
			(thermal_bridge_width 0.5)
			(island_removal_mode 0)
		)
		(polygon
			(pts
				(arc
					(start 420.242238 -237.285022)
					(mid 419.581838 -237.285022)
					(end 420.242238 -237.285022)
				)
			)
		)
	)
	(zone
		(layers "In1.Cu" "In2.Cu")
		(hatch none 0.5)
		(connect_pads
			(clearance 0)
		)
		(min_thickness 0.25)
		(keepout
			(tracks not_allowed)
			(vias allowed)
			(pads allowed)
			(copperpour not_allowed)
			(footprints allowed)
		)
		(placement
			(enabled no)
			(sheetname "")
		)
		(fill yes
			(thermal_gap 0.5)
			(thermal_bridge_width 0.5)
			(island_removal_mode 0)
		)
		(polygon
			(pts
				(arc
					(start 14.938248 -101.256846)
					(mid 14.960566 -101.202964)
					(end 15.014448 -101.180646)
				)
				(arc
					(start 15.61592 -101.180646)
					(mid 15.669802 -101.202964)
					(end 15.69212 -101.256846)
				)
				(arc
					(start 15.69212 -101.841046)
					(mid 15.669802 -101.894928)
					(end 15.61592 -101.917246)
				)
				(arc
					(start 15.014448 -101.917246)
					(mid 14.960566 -101.894928)
					(end 14.938248 -101.841046)
				)
			)
		)
	)
	(zone
		(layers "In1.Cu" "In2.Cu")
		(hatch none 0.5)
		(connect_pads
			(clearance 0)
		)
		(min_thickness 0.25)
		(keepout
			(tracks not_allowed)
			(vias allowed)
			(pads allowed)
			(copperpour not_allowed)
			(footprints allowed)
		)
		(placement
			(enabled no)
			(sheetname "")
		)
		(fill yes
			(thermal_gap 0.5)
			(thermal_bridge_width 0.5)
			(island_removal_mode 0)
		)
		(polygon
			(pts
				(arc
					(start 442.8744 -218.585034)
					(mid 442.214 -218.585034)
					(end 442.8744 -218.585034)
				)
			)
		)
	)
	(zone
		(layers "In1.Cu" "In2.Cu")
		(hatch none 0.5)
		(connect_pads
			(clearance 0)
		)
		(min_thickness 0.25)
		(keepout
			(tracks not_allowed)
			(vias allowed)
			(pads allowed)
			(copperpour not_allowed)
			(footprints allowed)
		)
		(placement
			(enabled no)
			(sheetname "")
		)
		(fill yes
			(thermal_gap 0.5)
			(thermal_bridge_width 0.5)
			(island_removal_mode 0)
		)
		(polygon
			(pts
				(arc
					(start 194.934332 -239.835436)
					(mid 194.273932 -239.835436)
					(end 194.934332 -239.835436)
				)
			)
		)
	)
	(zone
		(layers "In1.Cu" "In2.Cu")
		(hatch none 0.5)
		(connect_pads
			(clearance 0)
		)
		(min_thickness 0.25)
		(keepout
			(tracks not_allowed)
			(vias allowed)
			(pads allowed)
			(copperpour not_allowed)
			(footprints allowed)
		)
		(placement
			(enabled no)
			(sheetname "")
		)
		(fill yes
			(thermal_gap 0.5)
			(thermal_bridge_width 0.5)
			(island_removal_mode 0)
		)
		(polygon
			(pts
				(arc
					(start 179.846224 -305.285394)
					(mid 179.185824 -305.285394)
					(end 179.846224 -305.285394)
				)
			)
		)
	)
	(zone
		(layers "In1.Cu" "In2.Cu")
		(hatch none 0.5)
		(connect_pads
			(clearance 0)
		)
		(min_thickness 0.25)
		(keepout
			(tracks not_allowed)
			(vias allowed)
			(pads allowed)
			(copperpour not_allowed)
			(footprints allowed)
		)
		(placement
			(enabled no)
			(sheetname "")
		)
		(fill yes
			(thermal_gap 0.5)
			(thermal_bridge_width 0.5)
			(island_removal_mode 0)
		)
		(polygon
			(pts
				(arc
					(start 194.934332 -254.285242)
					(mid 194.273932 -254.285242)
					(end 194.934332 -254.285242)
				)
			)
		)
	)
	(zone
		(layers "In1.Cu" "In2.Cu")
		(hatch none 0.5)
		(connect_pads
			(clearance 0)
		)
		(min_thickness 0.25)
		(keepout
			(tracks not_allowed)
			(vias allowed)
			(pads allowed)
			(copperpour not_allowed)
			(footprints allowed)
		)
		(placement
			(enabled no)
			(sheetname "")
		)
		(fill yes
			(thermal_gap 0.5)
			(thermal_bridge_width 0.5)
			(island_removal_mode 0)
		)
		(polygon
			(pts
				(arc
					(start 273.422364 -280.634948)
					(mid 272.761964 -280.634948)
					(end 273.422364 -280.634948)
				)
			)
		)
	)
	(zone
		(layers "In1.Cu" "In2.Cu")
		(hatch none 0.5)
		(connect_pads
			(clearance 0)
		)
		(min_thickness 0.25)
		(keepout
			(tracks not_allowed)
			(vias allowed)
			(pads allowed)
			(copperpour not_allowed)
			(footprints allowed)
		)
		(placement
			(enabled no)
			(sheetname "")
		)
		(fill yes
			(thermal_gap 0.5)
			(thermal_bridge_width 0.5)
			(island_removal_mode 0)
		)
		(polygon
			(pts
				(arc
					(start 296.054272 -243.234972)
					(mid 295.393872 -243.234972)
					(end 296.054272 -243.234972)
				)
			)
		)
	)
	(zone
		(layers "In1.Cu" "In2.Cu")
		(hatch none 0.5)
		(connect_pads
			(clearance 0)
		)
		(min_thickness 0.25)
		(keepout
			(tracks not_allowed)
			(vias allowed)
			(pads allowed)
			(copperpour not_allowed)
			(footprints allowed)
		)
		(placement
			(enabled no)
			(sheetname "")
		)
		(fill yes
			(thermal_gap 0.5)
			(thermal_bridge_width 0.5)
			(island_removal_mode 0)
		)
		(polygon
			(pts
				(arc
					(start 17.938242 -265.335258)
					(mid 17.277842 -265.335258)
					(end 17.938242 -265.335258)
				)
			)
		)
	)
	(zone
		(layers "In1.Cu" "In2.Cu")
		(hatch none 0.5)
		(connect_pads
			(clearance 0)
		)
		(min_thickness 0.25)
		(keepout
			(tracks not_allowed)
			(vias allowed)
			(pads allowed)
			(copperpour not_allowed)
			(footprints allowed)
		)
		(placement
			(enabled no)
			(sheetname "")
		)
		(fill yes
			(thermal_gap 0.5)
			(thermal_bridge_width 0.5)
			(island_removal_mode 0)
		)
		(polygon
			(pts
				(arc
					(start 292.610286 -312.935112)
					(mid 291.949886 -312.935112)
					(end 292.610286 -312.935112)
				)
			)
		)
	)
	(zone
		(layers "In1.Cu" "In2.Cu")
		(hatch none 0.5)
		(connect_pads
			(clearance 0)
		)
		(min_thickness 0.25)
		(keepout
			(tracks not_allowed)
			(vias allowed)
			(pads allowed)
			(copperpour not_allowed)
			(footprints allowed)
		)
		(placement
			(enabled no)
			(sheetname "")
		)
		(fill yes
			(thermal_gap 0.5)
			(thermal_bridge_width 0.5)
			(island_removal_mode 0)
		)
		(polygon
			(pts
				(arc
					(start 44.670218 -266.185396)
					(mid 44.009818 -266.185396)
					(end 44.670218 -266.185396)
				)
			)
		)
	)
	(zone
		(layers "In1.Cu" "In2.Cu")
		(hatch none 0.5)
		(connect_pads
			(clearance 0)
		)
		(min_thickness 0.25)
		(keepout
			(tracks not_allowed)
			(vias allowed)
			(pads allowed)
			(copperpour not_allowed)
			(footprints allowed)
		)
		(placement
			(enabled no)
			(sheetname "")
		)
		(fill yes
			(thermal_gap 0.5)
			(thermal_bridge_width 0.5)
			(island_removal_mode 0)
		)
		(polygon
			(pts
				(arc
					(start 52.214272 -284.885384)
					(mid 51.553872 -284.885384)
					(end 52.214272 -284.885384)
				)
			)
		)
	)
	(zone
		(layers "In1.Cu" "In2.Cu")
		(hatch none 0.5)
		(connect_pads
			(clearance 0)
		)
		(min_thickness 0.25)
		(keepout
			(tracks not_allowed)
			(vias allowed)
			(pads allowed)
			(copperpour not_allowed)
			(footprints allowed)
		)
		(placement
			(enabled no)
			(sheetname "")
		)
		(fill yes
			(thermal_gap 0.5)
			(thermal_bridge_width 0.5)
			(island_removal_mode 0)
		)
		(polygon
			(pts
				(arc
					(start 446.974468 -285.735014)
					(mid 446.314068 -285.735014)
					(end 446.974468 -285.735014)
				)
			)
		)
	)
	(zone
		(layers "In1.Cu" "In2.Cu")
		(hatch none 0.5)
		(connect_pads
			(clearance 0)
		)
		(min_thickness 0.25)
		(keepout
			(tracks not_allowed)
			(vias allowed)
			(pads allowed)
			(copperpour not_allowed)
			(footprints allowed)
		)
		(placement
			(enabled no)
			(sheetname "")
		)
		(fill yes
			(thermal_gap 0.5)
			(thermal_bridge_width 0.5)
			(island_removal_mode 0)
		)
		(polygon
			(pts
				(arc
					(start 187.390278 -233.885232)
					(mid 186.729878 -233.885232)
					(end 187.390278 -233.885232)
				)
			)
		)
	)
	(zone
		(layers "In1.Cu" "In2.Cu")
		(hatch none 0.5)
		(connect_pads
			(clearance 0)
		)
		(min_thickness 0.25)
		(keepout
			(tracks not_allowed)
			(vias allowed)
			(pads allowed)
			(copperpour not_allowed)
			(footprints allowed)
		)
		(placement
			(enabled no)
			(sheetname "")
		)
		(fill yes
			(thermal_gap 0.5)
			(thermal_bridge_width 0.5)
			(island_removal_mode 0)
		)
		(polygon
			(pts
				(arc
					(start 277.522432 -221.985078)
					(mid 276.862032 -221.985078)
					(end 277.522432 -221.985078)
				)
			)
		)
	)
	(zone
		(layers "In1.Cu" "In2.Cu")
		(hatch none 0.5)
		(connect_pads
			(clearance 0)
		)
		(min_thickness 0.25)
		(keepout
			(tracks not_allowed)
			(vias allowed)
			(pads allowed)
			(copperpour not_allowed)
			(footprints allowed)
		)
		(placement
			(enabled no)
			(sheetname "")
		)
		(fill yes
			(thermal_gap 0.5)
			(thermal_bridge_width 0.5)
			(island_removal_mode 0)
		)
		(polygon
			(pts
				(arc
					(start 292.610286 -267.885164)
					(mid 291.949886 -267.885164)
					(end 292.610286 -267.885164)
				)
			)
		)
	)
	(zone
		(layers "In1.Cu" "In2.Cu")
		(hatch none 0.5)
		(connect_pads
			(clearance 0)
		)
		(min_thickness 0.25)
		(keepout
			(tracks not_allowed)
			(vias allowed)
			(pads allowed)
			(copperpour not_allowed)
			(footprints allowed)
		)
		(placement
			(enabled no)
			(sheetname "")
		)
		(fill yes
			(thermal_gap 0.5)
			(thermal_bridge_width 0.5)
			(island_removal_mode 0)
		)
		(polygon
			(pts
				(arc
					(start 296.054272 -295.085008)
					(mid 295.393872 -295.085008)
					(end 296.054272 -295.085008)
				)
			)
		)
	)
	(zone
		(layers "In1.Cu" "In2.Cu")
		(hatch none 0.5)
		(connect_pads
			(clearance 0)
		)
		(min_thickness 0.25)
		(keepout
			(tracks not_allowed)
			(vias allowed)
			(pads allowed)
			(copperpour not_allowed)
			(footprints allowed)
		)
		(placement
			(enabled no)
			(sheetname "")
		)
		(fill yes
			(thermal_gap 0.5)
			(thermal_bridge_width 0.5)
			(island_removal_mode 0)
		)
		(polygon
			(pts
				(arc
					(start 22.03831 -220.28531)
					(mid 21.37791 -220.28531)
					(end 22.03831 -220.28531)
				)
			)
		)
	)
	(zone
		(layers "In1.Cu" "In2.Cu")
		(hatch none 0.5)
		(connect_pads
			(clearance 0)
		)
		(min_thickness 0.25)
		(keepout
			(tracks not_allowed)
			(vias allowed)
			(pads allowed)
			(copperpour not_allowed)
			(footprints allowed)
		)
		(placement
			(enabled no)
			(sheetname "")
		)
		(fill yes
			(thermal_gap 0.5)
			(thermal_bridge_width 0.5)
			(island_removal_mode 0)
		)
		(polygon
			(pts
				(arc
					(start 269.978378 -229.63505)
					(mid 269.317978 -229.63505)
					(end 269.978378 -229.63505)
				)
			)
		)
	)
	(zone
		(layers "In1.Cu" "In2.Cu")
		(hatch none 0.5)
		(connect_pads
			(clearance 0)
		)
		(min_thickness 0.25)
		(keepout
			(tracks not_allowed)
			(vias allowed)
			(pads allowed)
			(copperpour not_allowed)
			(footprints allowed)
		)
		(placement
			(enabled no)
			(sheetname "")
		)
		(fill yes
			(thermal_gap 0.5)
			(thermal_bridge_width 0.5)
			(island_removal_mode 0)
		)
		(polygon
			(pts
				(arc
					(start 446.974468 -206.685134)
					(mid 446.314068 -206.685134)
					(end 446.974468 -206.685134)
				)
			)
		)
	)
	(zone
		(layers "In1.Cu" "In2.Cu")
		(hatch none 0.5)
		(connect_pads
			(clearance 0)
		)
		(min_thickness 0.25)
		(keepout
			(tracks not_allowed)
			(vias allowed)
			(pads allowed)
			(copperpour not_allowed)
			(footprints allowed)
		)
		(placement
			(enabled no)
			(sheetname "")
		)
		(fill yes
			(thermal_gap 0.5)
			(thermal_bridge_width 0.5)
			(island_removal_mode 0)
		)
		(polygon
			(pts
				(arc
					(start 288.510218 -248.335038)
					(mid 287.849818 -248.335038)
					(end 288.510218 -248.335038)
				)
			)
		)
	)
	(zone
		(layers "In1.Cu" "In2.Cu")
		(hatch none 0.5)
		(connect_pads
			(clearance 0)
		)
		(min_thickness 0.25)
		(keepout
			(tracks not_allowed)
			(vias allowed)
			(pads allowed)
			(copperpour not_allowed)
			(footprints allowed)
		)
		(placement
			(enabled no)
			(sheetname "")
		)
		(fill yes
			(thermal_gap 0.5)
			(thermal_bridge_width 0.5)
			(island_removal_mode 0)
		)
		(polygon
			(pts
				(arc
					(start 48.114204 -316.33541)
					(mid 47.453804 -316.33541)
					(end 48.114204 -316.33541)
				)
			)
		)
	)
	(zone
		(layers "In1.Cu" "In2.Cu")
		(hatch none 0.5)
		(connect_pads
			(clearance 0)
		)
		(min_thickness 0.25)
		(keepout
			(tracks not_allowed)
			(vias allowed)
			(pads allowed)
			(copperpour not_allowed)
			(footprints allowed)
		)
		(placement
			(enabled no)
			(sheetname "")
		)
		(fill yes
			(thermal_gap 0.5)
			(thermal_bridge_width 0.5)
			(island_removal_mode 0)
		)
		(polygon
			(pts
				(arc
					(start 194.934332 -210.935316)
					(mid 194.273932 -210.935316)
					(end 194.934332 -210.935316)
				)
			)
		)
	)
	(zone
		(layers "In1.Cu" "In2.Cu")
		(hatch none 0.5)
		(connect_pads
			(clearance 0)
		)
		(min_thickness 0.25)
		(keepout
			(tracks not_allowed)
			(vias allowed)
			(pads allowed)
			(copperpour not_allowed)
			(footprints allowed)
		)
		(placement
			(enabled no)
			(sheetname "")
		)
		(fill yes
			(thermal_gap 0.5)
			(thermal_bridge_width 0.5)
			(island_removal_mode 0)
		)
		(polygon
			(pts
				(arc
					(start 29.582364 -252.58522)
					(mid 28.921964 -252.58522)
					(end 29.582364 -252.58522)
				)
			)
		)
	)
	(zone
		(layers "In1.Cu" "In2.Cu")
		(hatch none 0.5)
		(connect_pads
			(clearance 0)
		)
		(min_thickness 0.25)
		(keepout
			(tracks not_allowed)
			(vias allowed)
			(pads allowed)
			(copperpour not_allowed)
			(footprints allowed)
		)
		(placement
			(enabled no)
			(sheetname "")
		)
		(fill yes
			(thermal_gap 0.5)
			(thermal_bridge_width 0.5)
			(island_removal_mode 0)
		)
		(polygon
			(pts
				(arc
					(start 52.214272 -244.08511)
					(mid 51.553872 -244.08511)
					(end 52.214272 -244.08511)
				)
			)
		)
	)
	(zone
		(layers "In1.Cu" "In2.Cu")
		(hatch none 0.5)
		(connect_pads
			(clearance 0)
		)
		(min_thickness 0.25)
		(keepout
			(tracks not_allowed)
			(vias allowed)
			(pads allowed)
			(copperpour not_allowed)
			(footprints allowed)
		)
		(placement
			(enabled no)
			(sheetname "")
		)
		(fill yes
			(thermal_gap 0.5)
			(thermal_bridge_width 0.5)
			(island_removal_mode 0)
		)
		(polygon
			(pts
				(arc
					(start 334.209136 -417.242244)
					(mid 334.231454 -417.296126)
					(end 334.285336 -417.318444)
				)
				(arc
					(start 334.480916 -417.318444)
					(mid 334.502792 -417.315312)
					(end 334.522826 -417.305998)
				)
				(arc
					(start 334.81645 -417.113466)
					(mid 334.858106 -417.101064)
					(end 334.899762 -417.113466)
				)
				(arc
					(start 335.194656 -417.305998)
					(mid 335.21458 -417.315234)
					(end 335.236312 -417.318444)
				)
				(arc
					(start 335.430876 -417.318444)
					(mid 335.484758 -417.296126)
					(end 335.507076 -417.242244)
				)
				(arc
					(start 335.507076 -416.556444)
					(mid 335.484758 -416.502562)
					(end 335.430876 -416.480244)
				)
				(arc
					(start 335.236312 -416.480244)
					(mid 335.214568 -416.483412)
					(end 335.194656 -416.49269)
				)
				(arc
					(start 334.898492 -416.685476)
					(mid 334.856808 -416.697698)
					(end 334.81518 -416.685222)
				)
				(arc
					(start 334.521556 -416.49269)
					(mid 334.501632 -416.483454)
					(end 334.4799 -416.480244)
				)
				(arc
					(start 334.285336 -416.480244)
					(mid 334.231454 -416.502562)
					(end 334.209136 -416.556444)
				)
			)
		)
	)
	(zone
		(layers "In1.Cu" "In2.Cu")
		(hatch none 0.5)
		(connect_pads
			(clearance 0)
		)
		(min_thickness 0.25)
		(keepout
			(tracks not_allowed)
			(vias allowed)
			(pads allowed)
			(copperpour not_allowed)
			(footprints allowed)
		)
		(placement
			(enabled no)
			(sheetname "")
		)
		(fill yes
			(thermal_gap 0.5)
			(thermal_bridge_width 0.5)
			(island_removal_mode 0)
		)
		(polygon
			(pts
				(arc
					(start 187.390278 -318.035432)
					(mid 186.729878 -318.035432)
					(end 187.390278 -318.035432)
				)
			)
		)
	)
	(zone
		(layers "In1.Cu" "In2.Cu")
		(hatch none 0.5)
		(connect_pads
			(clearance 0)
		)
		(min_thickness 0.25)
		(keepout
			(tracks not_allowed)
			(vias allowed)
			(pads allowed)
			(copperpour not_allowed)
			(footprints allowed)
		)
		(placement
			(enabled no)
			(sheetname "")
		)
		(fill yes
			(thermal_gap 0.5)
			(thermal_bridge_width 0.5)
			(island_removal_mode 0)
		)
		(polygon
			(pts
				(arc
					(start 40.57015 -285.735268)
					(mid 39.90975 -285.735268)
					(end 40.57015 -285.735268)
				)
			)
		)
	)
	(zone
		(layers "In1.Cu" "In2.Cu")
		(hatch none 0.5)
		(connect_pads
			(clearance 0)
		)
		(min_thickness 0.25)
		(keepout
			(tracks not_allowed)
			(vias allowed)
			(pads allowed)
			(copperpour not_allowed)
			(footprints allowed)
		)
		(placement
			(enabled no)
			(sheetname "")
		)
		(fill yes
			(thermal_gap 0.5)
			(thermal_bridge_width 0.5)
			(island_removal_mode 0)
		)
		(polygon
			(pts
				(arc
					(start 354.381054 -292.41115)
					(mid 354.076254 -292.71595)
					(end 354.381054 -293.02075)
				)
				(arc
					(start 355.321108 -293.02075)
					(mid 355.625908 -292.71595)
					(end 355.321108 -292.41115)
				)
			)
		)
	)
	(zone
		(layers "In1.Cu" "In2.Cu")
		(hatch none 0.5)
		(connect_pads
			(clearance 0)
		)
		(min_thickness 0.25)
		(keepout
			(tracks not_allowed)
			(vias allowed)
			(pads allowed)
			(copperpour not_allowed)
			(footprints allowed)
		)
		(placement
			(enabled no)
			(sheetname "")
		)
		(fill yes
			(thermal_gap 0.5)
			(thermal_bridge_width 0.5)
			(island_removal_mode 0)
		)
		(polygon
			(pts
				(arc
					(start 55.696104 -375.906284)
					(mid 55.716028 -375.91552)
					(end 55.73776 -375.91873)
				)
				(arc
					(start 55.932324 -375.91873)
					(mid 55.986206 -375.896412)
					(end 56.008524 -375.84253)
				)
				(arc
					(start 56.008524 -375.15673)
					(mid 55.986206 -375.102848)
					(end 55.932324 -375.08053)
				)
				(arc
					(start 55.73776 -375.08053)
					(mid 55.716016 -375.083698)
					(end 55.696104 -375.092976)
				)
				(arc
					(start 55.39994 -375.285762)
					(mid 55.358256 -375.297984)
					(end 55.316628 -375.285508)
				)
				(arc
					(start 55.023004 -375.092976)
					(mid 55.00308 -375.08374)
					(end 54.981348 -375.08053)
				)
				(arc
					(start 54.786784 -375.08053)
					(mid 54.732902 -375.102848)
					(end 54.710584 -375.15673)
				)
				(arc
					(start 54.710584 -375.84253)
					(mid 54.732902 -375.896412)
					(end 54.786784 -375.91873)
				)
				(arc
					(start 54.982618 -375.91873)
					(mid 55.004362 -375.915562)
					(end 55.024274 -375.906284)
				)
				(arc
					(start 55.317898 -375.713752)
					(mid 55.359554 -375.70135)
					(end 55.40121 -375.713752)
				)
			)
		)
	)
	(zone
		(layers "In1.Cu" "In2.Cu")
		(hatch none 0.5)
		(connect_pads
			(clearance 0)
		)
		(min_thickness 0.25)
		(keepout
			(tracks not_allowed)
			(vias allowed)
			(pads allowed)
			(copperpour not_allowed)
			(footprints allowed)
		)
		(placement
			(enabled no)
			(sheetname "")
		)
		(fill yes
			(thermal_gap 0.5)
			(thermal_bridge_width 0.5)
			(island_removal_mode 0)
		)
		(polygon
			(pts
				(arc
					(start 72.356472 -11.91768)
					(mid 72.334154 -11.971562)
					(end 72.280272 -11.99388)
				)
				(arc
					(start 71.243698 -11.99388)
					(mid 71.189816 -11.971562)
					(end 71.167498 -11.91768)
				)
				(arc
					(start 71.167498 -10.51814)
					(mid 71.189816 -10.464258)
					(end 71.243698 -10.44194)
				)
				(arc
					(start 72.280272 -10.44194)
					(mid 72.334154 -10.464258)
					(end 72.356472 -10.51814)
				)
			)
		)
	)
	(zone
		(layers "In1.Cu" "In2.Cu")
		(hatch none 0.5)
		(connect_pads
			(clearance 0)
		)
		(min_thickness 0.25)
		(keepout
			(tracks not_allowed)
			(vias allowed)
			(pads allowed)
			(copperpour not_allowed)
			(footprints allowed)
		)
		(placement
			(enabled no)
			(sheetname "")
		)
		(fill yes
			(thermal_gap 0.5)
			(thermal_bridge_width 0.5)
			(island_removal_mode 0)
		)
		(polygon
			(pts
				(arc
					(start 180.121814 -50.853848)
					(mid 180.112578 -50.873772)
					(end 180.109368 -50.895504)
				)
				(arc
					(start 180.109368 -51.090068)
					(mid 180.131686 -51.14395)
					(end 180.185568 -51.166268)
				)
				(arc
					(start 180.871368 -51.166268)
					(mid 180.92525 -51.14395)
					(end 180.947568 -51.090068)
				)
				(arc
					(start 180.947568 -50.895504)
					(mid 180.9444 -50.87376)
					(end 180.935122 -50.853848)
				)
				(arc
					(start 180.742336 -50.557684)
					(mid 180.730114 -50.516)
					(end 180.74259 -50.474372)
				)
				(arc
					(start 180.935122 -50.180748)
					(mid 180.944358 -50.160824)
					(end 180.947568 -50.139092)
				)
				(arc
					(start 180.947568 -49.944528)
					(mid 180.92525 -49.890646)
					(end 180.871368 -49.868328)
				)
				(arc
					(start 180.185568 -49.868328)
					(mid 180.131686 -49.890646)
					(end 180.109368 -49.944528)
				)
				(arc
					(start 180.109368 -50.140362)
					(mid 180.112536 -50.162106)
					(end 180.121814 -50.182018)
				)
				(arc
					(start 180.314346 -50.475642)
					(mid 180.326748 -50.517298)
					(end 180.314346 -50.558954)
				)
			)
		)
	)
	(zone
		(layers "In1.Cu" "In2.Cu")
		(hatch none 0.5)
		(connect_pads
			(clearance 0)
		)
		(min_thickness 0.25)
		(keepout
			(tracks not_allowed)
			(vias allowed)
			(pads allowed)
			(copperpour not_allowed)
			(footprints allowed)
		)
		(placement
			(enabled no)
			(sheetname "")
		)
		(fill yes
			(thermal_gap 0.5)
			(thermal_bridge_width 0.5)
			(island_removal_mode 0)
		)
		(polygon
			(pts
				(arc
					(start 183.946292 -229.635304)
					(mid 183.285892 -229.635304)
					(end 183.946292 -229.635304)
				)
			)
		)
	)
	(zone
		(layers "In1.Cu" "In2.Cu")
		(hatch none 0.5)
		(connect_pads
			(clearance 0)
		)
		(min_thickness 0.25)
		(keepout
			(tracks not_allowed)
			(vias allowed)
			(pads allowed)
			(copperpour not_allowed)
			(footprints allowed)
		)
		(placement
			(enabled no)
			(sheetname "")
		)
		(fill yes
			(thermal_gap 0.5)
			(thermal_bridge_width 0.5)
			(island_removal_mode 0)
		)
		(polygon
			(pts
				(arc
					(start 199.0344 -270.435324)
					(mid 198.374 -270.435324)
					(end 199.0344 -270.435324)
				)
			)
		)
	)
	(zone
		(layers "In1.Cu" "In2.Cu")
		(hatch none 0.5)
		(connect_pads
			(clearance 0)
		)
		(min_thickness 0.25)
		(keepout
			(tracks not_allowed)
			(vias allowed)
			(pads allowed)
			(copperpour not_allowed)
			(footprints allowed)
		)
		(placement
			(enabled no)
			(sheetname "")
		)
		(fill yes
			(thermal_gap 0.5)
			(thermal_bridge_width 0.5)
			(island_removal_mode 0)
		)
		(polygon
			(pts
				(arc
					(start 17.938242 -293.38524)
					(mid 17.277842 -293.38524)
					(end 17.938242 -293.38524)
				)
			)
		)
	)
	(zone
		(layers "In1.Cu" "In2.Cu")
		(hatch none 0.5)
		(connect_pads
			(clearance 0)
		)
		(min_thickness 0.25)
		(keepout
			(tracks not_allowed)
			(vias allowed)
			(pads allowed)
			(copperpour not_allowed)
			(footprints allowed)
		)
		(placement
			(enabled no)
			(sheetname "")
		)
		(fill yes
			(thermal_gap 0.5)
			(thermal_bridge_width 0.5)
			(island_removal_mode 0)
		)
		(polygon
			(pts
				(arc
					(start 439.430414 -234.735116)
					(mid 438.770014 -234.735116)
					(end 439.430414 -234.735116)
				)
			)
		)
	)
	(zone
		(layers "In1.Cu" "In2.Cu")
		(hatch none 0.5)
		(connect_pads
			(clearance 0)
		)
		(min_thickness 0.25)
		(keepout
			(tracks not_allowed)
			(vias allowed)
			(pads allowed)
			(copperpour not_allowed)
			(footprints allowed)
		)
		(placement
			(enabled no)
			(sheetname "")
		)
		(fill yes
			(thermal_gap 0.5)
			(thermal_bridge_width 0.5)
			(island_removal_mode 0)
		)
		(polygon
			(pts
				(arc
					(start 288.510218 -220.285056)
					(mid 287.849818 -220.285056)
					(end 288.510218 -220.285056)
				)
			)
		)
	)
	(zone
		(layers "In1.Cu" "In2.Cu")
		(hatch none 0.5)
		(connect_pads
			(clearance 0)
		)
		(min_thickness 0.25)
		(keepout
			(tracks not_allowed)
			(vias allowed)
			(pads allowed)
			(copperpour not_allowed)
			(footprints allowed)
		)
		(placement
			(enabled no)
			(sheetname "")
		)
		(fill yes
			(thermal_gap 0.5)
			(thermal_bridge_width 0.5)
			(island_removal_mode 0)
		)
		(polygon
			(pts
				(arc
					(start 172.30217 -220.28531)
					(mid 171.64177 -220.28531)
					(end 172.30217 -220.28531)
				)
			)
		)
	)
	(zone
		(layers "In1.Cu" "In2.Cu")
		(hatch none 0.5)
		(connect_pads
			(clearance 0)
		)
		(min_thickness 0.25)
		(keepout
			(tracks not_allowed)
			(vias allowed)
			(pads allowed)
			(copperpour not_allowed)
			(footprints allowed)
		)
		(placement
			(enabled no)
			(sheetname "")
		)
		(fill yes
			(thermal_gap 0.5)
			(thermal_bridge_width 0.5)
			(island_removal_mode 0)
		)
		(polygon
			(pts
				(arc
					(start 24.252428 -7.672324)
					(mid 24.274746 -7.618442)
					(end 24.328628 -7.596124)
				)
				(arc
					(start 25.365202 -7.596124)
					(mid 25.419084 -7.618442)
					(end 25.441402 -7.672324)
				)
				(arc
					(start 25.441402 -9.071864)
					(mid 25.419084 -9.125746)
					(end 25.365202 -9.148064)
				)
				(arc
					(start 24.328628 -9.148064)
					(mid 24.274746 -9.125746)
					(end 24.252428 -9.071864)
				)
			)
		)
	)
	(zone
		(layers "In1.Cu" "In2.Cu")
		(hatch none 0.5)
		(connect_pads
			(clearance 0)
		)
		(min_thickness 0.25)
		(keepout
			(tracks not_allowed)
			(vias allowed)
			(pads allowed)
			(copperpour not_allowed)
			(footprints allowed)
		)
		(placement
			(enabled no)
			(sheetname "")
		)
		(fill yes
			(thermal_gap 0.5)
			(thermal_bridge_width 0.5)
			(island_removal_mode 0)
		)
		(polygon
			(pts
				(arc
					(start 435.330346 -254.284988)
					(mid 434.669946 -254.284988)
					(end 435.330346 -254.284988)
				)
			)
		)
	)
	(zone
		(layers "In1.Cu" "In2.Cu")
		(hatch none 0.5)
		(connect_pads
			(clearance 0)
		)
		(min_thickness 0.25)
		(keepout
			(tracks not_allowed)
			(vias allowed)
			(pads allowed)
			(copperpour not_allowed)
			(footprints allowed)
		)
		(placement
			(enabled no)
			(sheetname "")
		)
		(fill yes
			(thermal_gap 0.5)
			(thermal_bridge_width 0.5)
			(island_removal_mode 0)
		)
		(polygon
			(pts
				(arc
					(start 191.490346 -275.53539)
					(mid 190.829946 -275.53539)
					(end 191.490346 -275.53539)
				)
			)
		)
	)
	(zone
		(layers "In1.Cu" "In2.Cu")
		(hatch none 0.5)
		(connect_pads
			(clearance 0)
		)
		(min_thickness 0.25)
		(keepout
			(tracks not_allowed)
			(vias allowed)
			(pads allowed)
			(copperpour not_allowed)
			(footprints allowed)
		)
		(placement
			(enabled no)
			(sheetname "")
		)
		(fill yes
			(thermal_gap 0.5)
			(thermal_bridge_width 0.5)
			(island_removal_mode 0)
		)
		(polygon
			(pts
				(arc
					(start 194.934332 -295.085262)
					(mid 194.273932 -295.085262)
					(end 194.934332 -295.085262)
				)
			)
		)
	)
	(zone
		(layers "In1.Cu" "In2.Cu")
		(hatch none 0.5)
		(connect_pads
			(clearance 0)
		)
		(min_thickness 0.25)
		(keepout
			(tracks not_allowed)
			(vias allowed)
			(pads allowed)
			(copperpour not_allowed)
			(footprints allowed)
		)
		(placement
			(enabled no)
			(sheetname "")
		)
		(fill yes
			(thermal_gap 0.5)
			(thermal_bridge_width 0.5)
			(island_removal_mode 0)
		)
		(polygon
			(pts
				(arc
					(start 17.938242 -198.185278)
					(mid 17.277842 -198.185278)
					(end 17.938242 -198.185278)
				)
			)
		)
	)
	(zone
		(layers "In1.Cu" "In2.Cu")
		(hatch none 0.5)
		(connect_pads
			(clearance 0)
		)
		(min_thickness 0.25)
		(keepout
			(tracks not_allowed)
			(vias allowed)
			(pads allowed)
			(copperpour not_allowed)
			(footprints allowed)
		)
		(placement
			(enabled no)
			(sheetname "")
		)
		(fill yes
			(thermal_gap 0.5)
			(thermal_bridge_width 0.5)
			(island_removal_mode 0)
		)
		(polygon
			(pts
				(arc
					(start 418.13099 -384.288284)
					(mid 418.150914 -384.29752)
					(end 418.172646 -384.30073)
				)
				(arc
					(start 418.36721 -384.30073)
					(mid 418.421092 -384.278412)
					(end 418.44341 -384.22453)
				)
				(arc
					(start 418.44341 -383.53873)
					(mid 418.421092 -383.484848)
					(end 418.36721 -383.46253)
				)
				(arc
					(start 418.172646 -383.46253)
					(mid 418.150902 -383.465698)
					(end 418.13099 -383.474976)
				)
				(arc
					(start 417.834826 -383.667762)
					(mid 417.793142 -383.679984)
					(end 417.751514 -383.667508)
				)
				(arc
					(start 417.45789 -383.474976)
					(mid 417.437966 -383.46574)
					(end 417.416234 -383.46253)
				)
				(arc
					(start 417.22167 -383.46253)
					(mid 417.167788 -383.484848)
					(end 417.14547 -383.53873)
				)
				(arc
					(start 417.14547 -384.22453)
					(mid 417.167788 -384.278412)
					(end 417.22167 -384.30073)
				)
				(arc
					(start 417.417504 -384.30073)
					(mid 417.439248 -384.297562)
					(end 417.45916 -384.288284)
				)
				(arc
					(start 417.752784 -384.095752)
					(mid 417.79444 -384.08335)
					(end 417.836096 -384.095752)
				)
			)
		)
	)
	(zone
		(layers "In1.Cu" "In2.Cu")
		(hatch none 0.5)
		(connect_pads
			(clearance 0)
		)
		(min_thickness 0.25)
		(keepout
			(tracks not_allowed)
			(vias allowed)
			(pads allowed)
			(copperpour not_allowed)
			(footprints allowed)
		)
		(placement
			(enabled no)
			(sheetname "")
		)
		(fill yes
			(thermal_gap 0.5)
			(thermal_bridge_width 0.5)
			(island_removal_mode 0)
		)
		(polygon
			(pts
				(arc
					(start 199.0344 -245.785386)
					(mid 198.374 -245.785386)
					(end 199.0344 -245.785386)
				)
			)
		)
	)
	(zone
		(layers "In1.Cu" "In2.Cu")
		(hatch none 0.5)
		(connect_pads
			(clearance 0)
		)
		(min_thickness 0.25)
		(keepout
			(tracks not_allowed)
			(vias allowed)
			(pads allowed)
			(copperpour not_allowed)
			(footprints allowed)
		)
		(placement
			(enabled no)
			(sheetname "")
		)
		(fill yes
			(thermal_gap 0.5)
			(thermal_bridge_width 0.5)
			(island_removal_mode 0)
		)
		(polygon
			(pts
				(arc
					(start 439.430414 -281.485086)
					(mid 438.770014 -281.485086)
					(end 439.430414 -281.485086)
				)
			)
		)
	)
	(zone
		(layers "In1.Cu" "In2.Cu")
		(hatch none 0.5)
		(connect_pads
			(clearance 0)
		)
		(min_thickness 0.25)
		(keepout
			(tracks not_allowed)
			(vias allowed)
			(pads allowed)
			(copperpour not_allowed)
			(footprints allowed)
		)
		(placement
			(enabled no)
			(sheetname "")
		)
		(fill yes
			(thermal_gap 0.5)
			(thermal_bridge_width 0.5)
			(island_removal_mode 0)
		)
		(polygon
			(pts
				(arc
					(start 280.966164 -267.035026)
					(mid 280.305764 -267.035026)
					(end 280.966164 -267.035026)
				)
			)
		)
	)
	(zone
		(layers "In1.Cu" "In2.Cu")
		(hatch none 0.5)
		(connect_pads
			(clearance 0)
		)
		(min_thickness 0.25)
		(keepout
			(tracks not_allowed)
			(vias allowed)
			(pads allowed)
			(copperpour not_allowed)
			(footprints allowed)
		)
		(placement
			(enabled no)
			(sheetname "")
		)
		(fill yes
			(thermal_gap 0.5)
			(thermal_bridge_width 0.5)
			(island_removal_mode 0)
		)
		(polygon
			(pts
				(arc
					(start 48.114204 -291.685218)
					(mid 47.453804 -291.685218)
					(end 48.114204 -291.685218)
				)
			)
		)
	)
	(zone
		(layers "In1.Cu" "In2.Cu")
		(hatch none 0.5)
		(connect_pads
			(clearance 0)
		)
		(min_thickness 0.25)
		(keepout
			(tracks not_allowed)
			(vias allowed)
			(pads allowed)
			(copperpour not_allowed)
			(footprints allowed)
		)
		(placement
			(enabled no)
			(sheetname "")
		)
		(fill yes
			(thermal_gap 0.5)
			(thermal_bridge_width 0.5)
			(island_removal_mode 0)
		)
		(polygon
			(pts
				(arc
					(start 288.510218 -299.33519)
					(mid 287.849818 -299.33519)
					(end 288.510218 -299.33519)
				)
			)
		)
	)
	(zone
		(layers "In1.Cu" "In2.Cu")
		(hatch none 0.5)
		(connect_pads
			(clearance 0)
		)
		(min_thickness 0.25)
		(keepout
			(tracks not_allowed)
			(vias allowed)
			(pads allowed)
			(copperpour not_allowed)
			(footprints allowed)
		)
		(placement
			(enabled no)
			(sheetname "")
		)
		(fill yes
			(thermal_gap 0.5)
			(thermal_bridge_width 0.5)
			(island_removal_mode 0)
		)
		(polygon
			(pts
				(arc
					(start 194.934332 -238.985298)
					(mid 194.273932 -238.985298)
					(end 194.934332 -238.985298)
				)
			)
		)
	)
	(zone
		(layers "In1.Cu" "In2.Cu")
		(hatch none 0.5)
		(connect_pads
			(clearance 0)
		)
		(min_thickness 0.25)
		(keepout
			(tracks not_allowed)
			(vias allowed)
			(pads allowed)
			(copperpour not_allowed)
			(footprints allowed)
		)
		(placement
			(enabled no)
			(sheetname "")
		)
		(fill yes
			(thermal_gap 0.5)
			(thermal_bridge_width 0.5)
			(island_removal_mode 0)
		)
		(polygon
			(pts
				(arc
					(start 37.126164 -247.485408)
					(mid 36.465764 -247.485408)
					(end 37.126164 -247.485408)
				)
			)
		)
	)
	(zone
		(layers "In1.Cu" "In2.Cu")
		(hatch none 0.5)
		(connect_pads
			(clearance 0)
		)
		(min_thickness 0.25)
		(keepout
			(tracks not_allowed)
			(vias allowed)
			(pads allowed)
			(copperpour not_allowed)
			(footprints allowed)
		)
		(placement
			(enabled no)
			(sheetname "")
		)
		(fill yes
			(thermal_gap 0.5)
			(thermal_bridge_width 0.5)
			(island_removal_mode 0)
		)
		(polygon
			(pts
				(arc
					(start 22.03831 -261.08533)
					(mid 21.37791 -261.08533)
					(end 22.03831 -261.08533)
				)
			)
		)
	)
	(zone
		(layers "In1.Cu" "In2.Cu")
		(hatch none 0.5)
		(connect_pads
			(clearance 0)
		)
		(min_thickness 0.25)
		(keepout
			(tracks not_allowed)
			(vias allowed)
			(pads allowed)
			(copperpour not_allowed)
			(footprints allowed)
		)
		(placement
			(enabled no)
			(sheetname "")
		)
		(fill yes
			(thermal_gap 0.5)
			(thermal_bridge_width 0.5)
			(island_removal_mode 0)
		)
		(polygon
			(pts
				(arc
					(start 446.974468 -279.785064)
					(mid 446.314068 -279.785064)
					(end 446.974468 -279.785064)
				)
			)
		)
	)
	(zone
		(layers "In1.Cu" "In2.Cu")
		(hatch none 0.5)
		(connect_pads
			(clearance 0)
		)
		(min_thickness 0.25)
		(keepout
			(tracks not_allowed)
			(vias allowed)
			(pads allowed)
			(copperpour not_allowed)
			(footprints allowed)
		)
		(placement
			(enabled no)
			(sheetname "")
		)
		(fill yes
			(thermal_gap 0.5)
			(thermal_bridge_width 0.5)
			(island_removal_mode 0)
		)
		(polygon
			(pts
				(arc
					(start 420.242238 -318.035178)
					(mid 419.581838 -318.035178)
					(end 420.242238 -318.035178)
				)
			)
		)
	)
	(zone
		(layers "In1.Cu" "In2.Cu")
		(hatch none 0.5)
		(connect_pads
			(clearance 0)
		)
		(min_thickness 0.25)
		(keepout
			(tracks not_allowed)
			(vias allowed)
			(pads allowed)
			(copperpour not_allowed)
			(footprints allowed)
		)
		(placement
			(enabled no)
			(sheetname "")
		)
		(fill yes
			(thermal_gap 0.5)
			(thermal_bridge_width 0.5)
			(island_removal_mode 0)
		)
		(polygon
			(pts
				(arc
					(start 33.026096 -199.8853)
					(mid 32.365696 -199.8853)
					(end 33.026096 -199.8853)
				)
			)
		)
	)
	(zone
		(layers "In1.Cu" "In2.Cu")
		(hatch none 0.5)
		(connect_pads
			(clearance 0)
		)
		(min_thickness 0.25)
		(keepout
			(tracks not_allowed)
			(vias allowed)
			(pads allowed)
			(copperpour not_allowed)
			(footprints allowed)
		)
		(placement
			(enabled no)
			(sheetname "")
		)
		(fill yes
			(thermal_gap 0.5)
			(thermal_bridge_width 0.5)
			(island_removal_mode 0)
		)
		(polygon
			(pts
				(arc
					(start 296.054272 -251.735082)
					(mid 295.393872 -251.735082)
					(end 296.054272 -251.735082)
				)
			)
		)
	)
	(zone
		(layers "In1.Cu" "In2.Cu")
		(hatch none 0.5)
		(connect_pads
			(clearance 0)
		)
		(min_thickness 0.25)
		(keepout
			(tracks not_allowed)
			(vias allowed)
			(pads allowed)
			(copperpour not_allowed)
			(footprints allowed)
		)
		(placement
			(enabled no)
			(sheetname "")
		)
		(fill yes
			(thermal_gap 0.5)
			(thermal_bridge_width 0.5)
			(island_removal_mode 0)
		)
		(polygon
			(pts
				(arc
					(start 273.422364 -198.185024)
					(mid 272.761964 -198.185024)
					(end 273.422364 -198.185024)
				)
			)
		)
	)
	(zone
		(layers "In1.Cu" "In2.Cu")
		(hatch none 0.5)
		(connect_pads
			(clearance 0)
		)
		(min_thickness 0.25)
		(keepout
			(tracks not_allowed)
			(vias allowed)
			(pads allowed)
			(copperpour not_allowed)
			(footprints allowed)
		)
		(placement
			(enabled no)
			(sheetname "")
		)
		(fill yes
			(thermal_gap 0.5)
			(thermal_bridge_width 0.5)
			(island_removal_mode 0)
		)
		(polygon
			(pts
				(arc
					(start 170.17238 -12.952222)
					(mid 170.194698 -12.89834)
					(end 170.24858 -12.876022)
				)
				(arc
					(start 171.285154 -12.876022)
					(mid 171.339036 -12.89834)
					(end 171.361354 -12.952222)
				)
				(arc
					(start 171.361354 -14.351762)
					(mid 171.339036 -14.405644)
					(end 171.285154 -14.427962)
				)
				(arc
					(start 170.24858 -14.427962)
					(mid 170.194698 -14.405644)
					(end 170.17238 -14.351762)
				)
			)
		)
	)
	(zone
		(layers "In1.Cu" "In2.Cu")
		(hatch none 0.5)
		(connect_pads
			(clearance 0)
		)
		(min_thickness 0.25)
		(keepout
			(tracks not_allowed)
			(vias allowed)
			(pads allowed)
			(copperpour not_allowed)
			(footprints allowed)
		)
		(placement
			(enabled no)
			(sheetname "")
		)
		(fill yes
			(thermal_gap 0.5)
			(thermal_bridge_width 0.5)
			(island_removal_mode 0)
		)
		(polygon
			(pts
				(arc
					(start 285.066232 -206.685134)
					(mid 284.405832 -206.685134)
					(end 285.066232 -206.685134)
				)
			)
		)
	)
	(zone
		(layers "In1.Cu" "In2.Cu")
		(hatch none 0.5)
		(connect_pads
			(clearance 0)
		)
		(min_thickness 0.25)
		(keepout
			(tracks not_allowed)
			(vias allowed)
			(pads allowed)
			(copperpour not_allowed)
			(footprints allowed)
		)
		(placement
			(enabled no)
			(sheetname "")
		)
		(fill yes
			(thermal_gap 0.5)
			(thermal_bridge_width 0.5)
			(island_removal_mode 0)
		)
		(polygon
			(pts
				(arc
					(start 424.342306 -311.23509)
					(mid 423.681906 -311.23509)
					(end 424.342306 -311.23509)
				)
			)
		)
	)
	(zone
		(layers "In1.Cu" "In2.Cu")
		(hatch none 0.5)
		(connect_pads
			(clearance 0)
		)
		(min_thickness 0.25)
		(keepout
			(tracks not_allowed)
			(vias allowed)
			(pads allowed)
			(copperpour not_allowed)
			(footprints allowed)
		)
		(placement
			(enabled no)
			(sheetname "")
		)
		(fill yes
			(thermal_gap 0.5)
			(thermal_bridge_width 0.5)
			(island_removal_mode 0)
		)
		(polygon
			(pts
				(arc
					(start 17.938242 -205.83525)
					(mid 17.277842 -205.83525)
					(end 17.938242 -205.83525)
				)
			)
		)
	)
	(zone
		(layers "In1.Cu" "In2.Cu")
		(hatch none 0.5)
		(connect_pads
			(clearance 0)
		)
		(min_thickness 0.25)
		(keepout
			(tracks not_allowed)
			(vias allowed)
			(pads allowed)
			(copperpour not_allowed)
			(footprints allowed)
		)
		(placement
			(enabled no)
			(sheetname "")
		)
		(fill yes
			(thermal_gap 0.5)
			(thermal_bridge_width 0.5)
			(island_removal_mode 0)
		)
		(polygon
			(pts
				(arc
					(start 44.670218 -262.785352)
					(mid 44.009818 -262.785352)
					(end 44.670218 -262.785352)
				)
			)
		)
	)
	(zone
		(layers "In1.Cu" "In2.Cu")
		(hatch none 0.5)
		(connect_pads
			(clearance 0)
		)
		(min_thickness 0.25)
		(keepout
			(tracks not_allowed)
			(vias allowed)
			(pads allowed)
			(copperpour not_allowed)
			(footprints allowed)
		)
		(placement
			(enabled no)
			(sheetname "")
		)
		(fill yes
			(thermal_gap 0.5)
			(thermal_bridge_width 0.5)
			(island_removal_mode 0)
		)
		(polygon
			(pts
				(arc
					(start 52.214272 -200.735438)
					(mid 51.553872 -200.735438)
					(end 52.214272 -200.735438)
				)
			)
		)
	)
	(zone
		(layers "In1.Cu" "In2.Cu")
		(hatch none 0.5)
		(connect_pads
			(clearance 0)
		)
		(min_thickness 0.25)
		(keepout
			(tracks not_allowed)
			(vias allowed)
			(pads allowed)
			(copperpour not_allowed)
			(footprints allowed)
		)
		(placement
			(enabled no)
			(sheetname "")
		)
		(fill yes
			(thermal_gap 0.5)
			(thermal_bridge_width 0.5)
			(island_removal_mode 0)
		)
		(polygon
			(pts
				(arc
					(start 176.402238 -272.135346)
					(mid 175.741838 -272.135346)
					(end 176.402238 -272.135346)
				)
			)
		)
	)
	(zone
		(layers "In1.Cu" "In2.Cu")
		(hatch none 0.5)
		(connect_pads
			(clearance 0)
		)
		(min_thickness 0.25)
		(keepout
			(tracks not_allowed)
			(vias allowed)
			(pads allowed)
			(copperpour not_allowed)
			(footprints allowed)
		)
		(placement
			(enabled no)
			(sheetname "")
		)
		(fill yes
			(thermal_gap 0.5)
			(thermal_bridge_width 0.5)
			(island_removal_mode 0)
		)
		(polygon
			(pts
				(arc
					(start 194.934332 -313.78525)
					(mid 194.273932 -313.78525)
					(end 194.934332 -313.78525)
				)
			)
		)
	)
	(zone
		(layers "In1.Cu" "In2.Cu")
		(hatch none 0.5)
		(connect_pads
			(clearance 0)
		)
		(min_thickness 0.25)
		(keepout
			(tracks not_allowed)
			(vias allowed)
			(pads allowed)
			(copperpour not_allowed)
			(footprints allowed)
		)
		(placement
			(enabled no)
			(sheetname "")
		)
		(fill yes
			(thermal_gap 0.5)
			(thermal_bridge_width 0.5)
			(island_removal_mode 0)
		)
		(polygon
			(pts
				(arc
					(start 296.054272 -246.635016)
					(mid 295.393872 -246.635016)
					(end 296.054272 -246.635016)
				)
			)
		)
	)
	(zone
		(layers "In1.Cu" "In2.Cu")
		(hatch none 0.5)
		(connect_pads
			(clearance 0)
		)
		(min_thickness 0.25)
		(keepout
			(tracks not_allowed)
			(vias allowed)
			(pads allowed)
			(copperpour not_allowed)
			(footprints allowed)
		)
		(placement
			(enabled no)
			(sheetname "")
		)
		(fill yes
			(thermal_gap 0.5)
			(thermal_bridge_width 0.5)
			(island_removal_mode 0)
		)
		(polygon
			(pts
				(arc
					(start 431.88636 -216.035128)
					(mid 431.22596 -216.035128)
					(end 431.88636 -216.035128)
				)
			)
		)
	)
	(zone
		(layers "In1.Cu" "In2.Cu")
		(hatch none 0.5)
		(connect_pads
			(clearance 0)
		)
		(min_thickness 0.25)
		(keepout
			(tracks not_allowed)
			(vias allowed)
			(pads allowed)
			(copperpour not_allowed)
			(footprints allowed)
		)
		(placement
			(enabled no)
			(sheetname "")
		)
		(fill yes
			(thermal_gap 0.5)
			(thermal_bridge_width 0.5)
			(island_removal_mode 0)
		)
		(polygon
			(pts
				(arc
					(start 373.690642 -381.824484)
					(mid 373.710566 -381.83372)
					(end 373.732298 -381.83693)
				)
				(arc
					(start 373.926862 -381.83693)
					(mid 373.980744 -381.814612)
					(end 374.003062 -381.76073)
				)
				(arc
					(start 374.003062 -381.07493)
					(mid 373.980744 -381.021048)
					(end 373.926862 -380.99873)
				)
				(arc
					(start 373.732298 -380.99873)
					(mid 373.710554 -381.001898)
					(end 373.690642 -381.011176)
				)
				(arc
					(start 373.394478 -381.203962)
					(mid 373.352794 -381.216184)
					(end 373.311166 -381.203708)
				)
				(arc
					(start 373.017542 -381.011176)
					(mid 372.997618 -381.00194)
					(end 372.975886 -380.99873)
				)
				(arc
					(start 372.781322 -380.99873)
					(mid 372.72744 -381.021048)
					(end 372.705122 -381.07493)
				)
				(arc
					(start 372.705122 -381.76073)
					(mid 372.72744 -381.814612)
					(end 372.781322 -381.83693)
				)
				(arc
					(start 372.977156 -381.83693)
					(mid 372.9989 -381.833762)
					(end 373.018812 -381.824484)
				)
				(arc
					(start 373.312436 -381.631952)
					(mid 373.354092 -381.61955)
					(end 373.395748 -381.631952)
				)
			)
		)
	)
	(zone
		(layers "In1.Cu" "In2.Cu")
		(hatch none 0.5)
		(connect_pads
			(clearance 0)
		)
		(min_thickness 0.25)
		(keepout
			(tracks not_allowed)
			(vias allowed)
			(pads allowed)
			(copperpour not_allowed)
			(footprints allowed)
		)
		(placement
			(enabled no)
			(sheetname "")
		)
		(fill yes
			(thermal_gap 0.5)
			(thermal_bridge_width 0.5)
			(island_removal_mode 0)
		)
		(polygon
			(pts
				(arc
					(start 202.478132 -209.235294)
					(mid 201.817732 -209.235294)
					(end 202.478132 -209.235294)
				)
			)
		)
	)
	(zone
		(layers "In1.Cu" "In2.Cu")
		(hatch none 0.5)
		(connect_pads
			(clearance 0)
		)
		(min_thickness 0.25)
		(keepout
			(tracks not_allowed)
			(vias allowed)
			(pads allowed)
			(copperpour not_allowed)
			(footprints allowed)
		)
		(placement
			(enabled no)
			(sheetname "")
		)
		(fill yes
			(thermal_gap 0.5)
			(thermal_bridge_width 0.5)
			(island_removal_mode 0)
		)
		(polygon
			(pts
				(arc
					(start 29.582364 -254.285242)
					(mid 28.921964 -254.285242)
					(end 29.582364 -254.285242)
				)
			)
		)
	)
	(zone
		(layers "In1.Cu" "In2.Cu")
		(hatch none 0.5)
		(connect_pads
			(clearance 0)
		)
		(min_thickness 0.25)
		(keepout
			(tracks not_allowed)
			(vias allowed)
			(pads allowed)
			(copperpour not_allowed)
			(footprints allowed)
		)
		(placement
			(enabled no)
			(sheetname "")
		)
		(fill yes
			(thermal_gap 0.5)
			(thermal_bridge_width 0.5)
			(island_removal_mode 0)
		)
		(polygon
			(pts
				(arc
					(start 33.026096 -310.385206)
					(mid 32.365696 -310.385206)
					(end 33.026096 -310.385206)
				)
			)
		)
	)
	(zone
		(layers "In1.Cu" "In2.Cu")
		(hatch none 0.5)
		(connect_pads
			(clearance 0)
		)
		(min_thickness 0.25)
		(keepout
			(tracks not_allowed)
			(vias allowed)
			(pads allowed)
			(copperpour not_allowed)
			(footprints allowed)
		)
		(placement
			(enabled no)
			(sheetname "")
		)
		(fill yes
			(thermal_gap 0.5)
			(thermal_bridge_width 0.5)
			(island_removal_mode 0)
		)
		(polygon
			(pts
				(arc
					(start 172.30217 -274.685252)
					(mid 171.64177 -274.685252)
					(end 172.30217 -274.685252)
				)
			)
		)
	)
	(zone
		(layers "In1.Cu" "In2.Cu")
		(hatch none 0.5)
		(connect_pads
			(clearance 0)
		)
		(min_thickness 0.25)
		(keepout
			(tracks not_allowed)
			(vias allowed)
			(pads allowed)
			(copperpour not_allowed)
			(footprints allowed)
		)
		(placement
			(enabled no)
			(sheetname "")
		)
		(fill yes
			(thermal_gap 0.5)
			(thermal_bridge_width 0.5)
			(island_removal_mode 0)
		)
		(polygon
			(pts
				(arc
					(start 273.422364 -268.735048)
					(mid 272.761964 -268.735048)
					(end 273.422364 -268.735048)
				)
			)
		)
	)
	(zone
		(layers "In1.Cu" "In2.Cu")
		(hatch none 0.5)
		(connect_pads
			(clearance 0)
		)
		(min_thickness 0.25)
		(keepout
			(tracks not_allowed)
			(vias allowed)
			(pads allowed)
			(copperpour not_allowed)
			(footprints allowed)
		)
		(placement
			(enabled no)
			(sheetname "")
		)
		(fill yes
			(thermal_gap 0.5)
			(thermal_bridge_width 0.5)
			(island_removal_mode 0)
		)
		(polygon
			(pts
				(arc
					(start 427.786292 -251.735082)
					(mid 427.125892 -251.735082)
					(end 427.786292 -251.735082)
				)
			)
		)
	)
	(zone
		(layers "In1.Cu" "In2.Cu")
		(hatch none 0.5)
		(connect_pads
			(clearance 0)
		)
		(min_thickness 0.25)
		(keepout
			(tracks not_allowed)
			(vias allowed)
			(pads allowed)
			(copperpour not_allowed)
			(footprints allowed)
		)
		(placement
			(enabled no)
			(sheetname "")
		)
		(fill yes
			(thermal_gap 0.5)
			(thermal_bridge_width 0.5)
			(island_removal_mode 0)
		)
		(polygon
			(pts
				(arc
					(start 44.670218 -309.535322)
					(mid 44.009818 -309.535322)
					(end 44.670218 -309.535322)
				)
			)
		)
	)
	(zone
		(layers "In1.Cu" "In2.Cu")
		(hatch none 0.5)
		(connect_pads
			(clearance 0)
		)
		(min_thickness 0.25)
		(keepout
			(tracks not_allowed)
			(vias allowed)
			(pads allowed)
			(copperpour not_allowed)
			(footprints allowed)
		)
		(placement
			(enabled no)
			(sheetname "")
		)
		(fill yes
			(thermal_gap 0.5)
			(thermal_bridge_width 0.5)
			(island_removal_mode 0)
		)
		(polygon
			(pts
				(arc
					(start 273.422364 -204.134974)
					(mid 272.761964 -204.134974)
					(end 273.422364 -204.134974)
				)
			)
		)
	)
	(zone
		(layers "In1.Cu" "In2.Cu")
		(hatch none 0.5)
		(connect_pads
			(clearance 0)
		)
		(min_thickness 0.25)
		(keepout
			(tracks not_allowed)
			(vias allowed)
			(pads allowed)
			(copperpour not_allowed)
			(footprints allowed)
		)
		(placement
			(enabled no)
			(sheetname "")
		)
		(fill yes
			(thermal_gap 0.5)
			(thermal_bridge_width 0.5)
			(island_removal_mode 0)
		)
		(polygon
			(pts
				(arc
					(start 202.478132 -213.485222)
					(mid 201.817732 -213.485222)
					(end 202.478132 -213.485222)
				)
			)
		)
	)
	(zone
		(layers "In1.Cu" "In2.Cu")
		(hatch none 0.5)
		(connect_pads
			(clearance 0)
		)
		(min_thickness 0.25)
		(keepout
			(tracks not_allowed)
			(vias allowed)
			(pads allowed)
			(copperpour not_allowed)
			(footprints allowed)
		)
		(placement
			(enabled no)
			(sheetname "")
		)
		(fill yes
			(thermal_gap 0.5)
			(thermal_bridge_width 0.5)
			(island_removal_mode 0)
		)
		(polygon
			(pts
				(arc
					(start 202.478132 -221.135194)
					(mid 201.817732 -221.135194)
					(end 202.478132 -221.135194)
				)
			)
		)
	)
	(zone
		(layers "In1.Cu" "In2.Cu")
		(hatch none 0.5)
		(connect_pads
			(clearance 0)
		)
		(min_thickness 0.25)
		(keepout
			(tracks not_allowed)
			(vias allowed)
			(pads allowed)
			(copperpour not_allowed)
			(footprints allowed)
		)
		(placement
			(enabled no)
			(sheetname "")
		)
		(fill yes
			(thermal_gap 0.5)
			(thermal_bridge_width 0.5)
			(island_removal_mode 0)
		)
		(polygon
			(pts
				(arc
					(start 176.402238 -199.035416)
					(mid 175.741838 -199.035416)
					(end 176.402238 -199.035416)
				)
			)
		)
	)
	(zone
		(layers "In1.Cu" "In2.Cu")
		(hatch none 0.5)
		(connect_pads
			(clearance 0)
		)
		(min_thickness 0.25)
		(keepout
			(tracks not_allowed)
			(vias allowed)
			(pads allowed)
			(copperpour not_allowed)
			(footprints allowed)
		)
		(placement
			(enabled no)
			(sheetname "")
		)
		(fill yes
			(thermal_gap 0.5)
			(thermal_bridge_width 0.5)
			(island_removal_mode 0)
		)
		(polygon
			(pts
				(arc
					(start 277.522432 -217.73515)
					(mid 276.862032 -217.73515)
					(end 277.522432 -217.73515)
				)
			)
		)
	)
	(zone
		(layers "In1.Cu" "In2.Cu")
		(hatch none 0.5)
		(connect_pads
			(clearance 0)
		)
		(min_thickness 0.25)
		(keepout
			(tracks not_allowed)
			(vias allowed)
			(pads allowed)
			(copperpour not_allowed)
			(footprints allowed)
		)
		(placement
			(enabled no)
			(sheetname "")
		)
		(fill yes
			(thermal_gap 0.5)
			(thermal_bridge_width 0.5)
			(island_removal_mode 0)
		)
		(polygon
			(pts
				(arc
					(start 277.522432 -220.285056)
					(mid 276.862032 -220.285056)
					(end 277.522432 -220.285056)
				)
			)
		)
	)
	(zone
		(layers "In1.Cu" "In2.Cu")
		(hatch none 0.5)
		(connect_pads
			(clearance 0)
		)
		(min_thickness 0.25)
		(keepout
			(tracks not_allowed)
			(vias allowed)
			(pads allowed)
			(copperpour not_allowed)
			(footprints allowed)
		)
		(placement
			(enabled no)
			(sheetname "")
		)
		(fill yes
			(thermal_gap 0.5)
			(thermal_bridge_width 0.5)
			(island_removal_mode 0)
		)
		(polygon
			(pts
				(arc
					(start 269.978378 -303.585118)
					(mid 269.317978 -303.585118)
					(end 269.978378 -303.585118)
				)
			)
		)
	)
	(zone
		(layers "In1.Cu" "In2.Cu")
		(hatch none 0.5)
		(connect_pads
			(clearance 0)
		)
		(min_thickness 0.25)
		(keepout
			(tracks not_allowed)
			(vias allowed)
			(pads allowed)
			(copperpour not_allowed)
			(footprints allowed)
		)
		(placement
			(enabled no)
			(sheetname "")
		)
		(fill yes
			(thermal_gap 0.5)
			(thermal_bridge_width 0.5)
			(island_removal_mode 0)
		)
		(polygon
			(pts
				(arc
					(start 280.966164 -202.434952)
					(mid 280.305764 -202.434952)
					(end 280.966164 -202.434952)
				)
			)
		)
	)
	(zone
		(layers "In1.Cu" "In2.Cu")
		(hatch none 0.5)
		(connect_pads
			(clearance 0)
		)
		(min_thickness 0.25)
		(keepout
			(tracks not_allowed)
			(vias allowed)
			(pads allowed)
			(copperpour not_allowed)
			(footprints allowed)
		)
		(placement
			(enabled no)
			(sheetname "")
		)
		(fill yes
			(thermal_gap 0.5)
			(thermal_bridge_width 0.5)
			(island_removal_mode 0)
		)
		(polygon
			(pts
				(arc
					(start 176.402238 -197.335394)
					(mid 175.741838 -197.335394)
					(end 176.402238 -197.335394)
				)
			)
		)
	)
	(zone
		(layers "In1.Cu" "In2.Cu")
		(hatch none 0.5)
		(connect_pads
			(clearance 0)
		)
		(min_thickness 0.25)
		(keepout
			(tracks not_allowed)
			(vias allowed)
			(pads allowed)
			(copperpour not_allowed)
			(footprints allowed)
		)
		(placement
			(enabled no)
			(sheetname "")
		)
		(fill yes
			(thermal_gap 0.5)
			(thermal_bridge_width 0.5)
			(island_removal_mode 0)
		)
		(polygon
			(pts
				(arc
					(start 179.846224 -211.7852)
					(mid 179.185824 -211.7852)
					(end 179.846224 -211.7852)
				)
			)
		)
	)
	(zone
		(layers "In1.Cu" "In2.Cu")
		(hatch none 0.5)
		(connect_pads
			(clearance 0)
		)
		(min_thickness 0.25)
		(keepout
			(tracks not_allowed)
			(vias allowed)
			(pads allowed)
			(copperpour not_allowed)
			(footprints allowed)
		)
		(placement
			(enabled no)
			(sheetname "")
		)
		(fill yes
			(thermal_gap 0.5)
			(thermal_bridge_width 0.5)
			(island_removal_mode 0)
		)
		(polygon
			(pts
				(arc
					(start 176.402238 -231.335326)
					(mid 175.741838 -231.335326)
					(end 176.402238 -231.335326)
				)
			)
		)
	)
	(zone
		(layers "In1.Cu" "In2.Cu")
		(hatch none 0.5)
		(connect_pads
			(clearance 0)
		)
		(min_thickness 0.25)
		(keepout
			(tracks not_allowed)
			(vias allowed)
			(pads allowed)
			(copperpour not_allowed)
			(footprints allowed)
		)
		(placement
			(enabled no)
			(sheetname "")
		)
		(fill yes
			(thermal_gap 0.5)
			(thermal_bridge_width 0.5)
			(island_removal_mode 0)
		)
		(polygon
			(pts
				(arc
					(start 288.510218 -285.735014)
					(mid 287.849818 -285.735014)
					(end 288.510218 -285.735014)
				)
			)
		)
	)
	(zone
		(layers "In1.Cu" "In2.Cu")
		(hatch none 0.5)
		(connect_pads
			(clearance 0)
		)
		(min_thickness 0.25)
		(keepout
			(tracks not_allowed)
			(vias allowed)
			(pads allowed)
			(copperpour not_allowed)
			(footprints allowed)
		)
		(placement
			(enabled no)
			(sheetname "")
		)
		(fill yes
			(thermal_gap 0.5)
			(thermal_bridge_width 0.5)
			(island_removal_mode 0)
		)
		(polygon
			(pts
				(arc
					(start 277.522432 -216.035128)
					(mid 276.862032 -216.035128)
					(end 277.522432 -216.035128)
				)
			)
		)
	)
	(zone
		(layers "In1.Cu" "In2.Cu")
		(hatch none 0.5)
		(connect_pads
			(clearance 0)
		)
		(min_thickness 0.25)
		(keepout
			(tracks not_allowed)
			(vias allowed)
			(pads allowed)
			(copperpour not_allowed)
			(footprints allowed)
		)
		(placement
			(enabled no)
			(sheetname "")
		)
		(fill yes
			(thermal_gap 0.5)
			(thermal_bridge_width 0.5)
			(island_removal_mode 0)
		)
		(polygon
			(pts
				(arc
					(start 37.126164 -270.435324)
					(mid 36.465764 -270.435324)
					(end 37.126164 -270.435324)
				)
			)
		)
	)
	(zone
		(layers "In1.Cu" "In2.Cu")
		(hatch none 0.5)
		(connect_pads
			(clearance 0)
		)
		(min_thickness 0.25)
		(keepout
			(tracks not_allowed)
			(vias allowed)
			(pads allowed)
			(copperpour not_allowed)
			(footprints allowed)
		)
		(placement
			(enabled no)
			(sheetname "")
		)
		(fill yes
			(thermal_gap 0.5)
			(thermal_bridge_width 0.5)
			(island_removal_mode 0)
		)
		(polygon
			(pts
				(arc
					(start 277.522432 -201.585068)
					(mid 276.862032 -201.585068)
					(end 277.522432 -201.585068)
				)
			)
		)
	)
	(zone
		(layers "In1.Cu" "In2.Cu")
		(hatch none 0.5)
		(connect_pads
			(clearance 0)
		)
		(min_thickness 0.25)
		(keepout
			(tracks not_allowed)
			(vias allowed)
			(pads allowed)
			(copperpour not_allowed)
			(footprints allowed)
		)
		(placement
			(enabled no)
			(sheetname "")
		)
		(fill yes
			(thermal_gap 0.5)
			(thermal_bridge_width 0.5)
			(island_removal_mode 0)
		)
		(polygon
			(pts
				(arc
					(start 191.490346 -261.08533)
					(mid 190.829946 -261.08533)
					(end 191.490346 -261.08533)
				)
			)
		)
	)
	(zone
		(layers "In1.Cu" "In2.Cu")
		(hatch none 0.5)
		(connect_pads
			(clearance 0)
		)
		(min_thickness 0.25)
		(keepout
			(tracks not_allowed)
			(vias allowed)
			(pads allowed)
			(copperpour not_allowed)
			(footprints allowed)
		)
		(placement
			(enabled no)
			(sheetname "")
		)
		(fill yes
			(thermal_gap 0.5)
			(thermal_bridge_width 0.5)
			(island_removal_mode 0)
		)
		(polygon
			(pts
				(arc
					(start 269.978378 -312.935112)
					(mid 269.317978 -312.935112)
					(end 269.978378 -312.935112)
				)
			)
		)
	)
	(zone
		(layers "In1.Cu" "In2.Cu")
		(hatch none 0.5)
		(connect_pads
			(clearance 0)
		)
		(min_thickness 0.25)
		(keepout
			(tracks not_allowed)
			(vias allowed)
			(pads allowed)
			(copperpour not_allowed)
			(footprints allowed)
		)
		(placement
			(enabled no)
			(sheetname "")
		)
		(fill yes
			(thermal_gap 0.5)
			(thermal_bridge_width 0.5)
			(island_removal_mode 0)
		)
		(polygon
			(pts
				(arc
					(start 199.0344 -261.08533)
					(mid 198.374 -261.08533)
					(end 199.0344 -261.08533)
				)
			)
		)
	)
	(zone
		(layers "In1.Cu" "In2.Cu")
		(hatch none 0.5)
		(connect_pads
			(clearance 0)
		)
		(min_thickness 0.25)
		(keepout
			(tracks not_allowed)
			(vias allowed)
			(pads allowed)
			(copperpour not_allowed)
			(footprints allowed)
		)
		(placement
			(enabled no)
			(sheetname "")
		)
		(fill yes
			(thermal_gap 0.5)
			(thermal_bridge_width 0.5)
			(island_removal_mode 0)
		)
		(polygon
			(pts
				(arc
					(start 199.0344 -225.385376)
					(mid 198.374 -225.385376)
					(end 199.0344 -225.385376)
				)
			)
		)
	)
	(zone
		(layers "In1.Cu" "In2.Cu")
		(hatch none 0.5)
		(connect_pads
			(clearance 0)
		)
		(min_thickness 0.25)
		(keepout
			(tracks not_allowed)
			(vias allowed)
			(pads allowed)
			(copperpour not_allowed)
			(footprints allowed)
		)
		(placement
			(enabled no)
			(sheetname "")
		)
		(fill yes
			(thermal_gap 0.5)
			(thermal_bridge_width 0.5)
			(island_removal_mode 0)
		)
		(polygon
			(pts
				(arc
					(start 296.054272 -237.285022)
					(mid 295.393872 -237.285022)
					(end 296.054272 -237.285022)
				)
			)
		)
	)
	(zone
		(layers "In1.Cu" "In2.Cu")
		(hatch none 0.5)
		(connect_pads
			(clearance 0)
		)
		(min_thickness 0.25)
		(keepout
			(tracks not_allowed)
			(vias allowed)
			(pads allowed)
			(copperpour not_allowed)
			(footprints allowed)
		)
		(placement
			(enabled no)
			(sheetname "")
		)
		(fill yes
			(thermal_gap 0.5)
			(thermal_bridge_width 0.5)
			(island_removal_mode 0)
		)
		(polygon
			(pts
				(arc
					(start 419.83279 -381.824484)
					(mid 419.852714 -381.83372)
					(end 419.874446 -381.83693)
				)
				(arc
					(start 420.06901 -381.83693)
					(mid 420.122892 -381.814612)
					(end 420.14521 -381.76073)
				)
				(arc
					(start 420.14521 -381.07493)
					(mid 420.122892 -381.021048)
					(end 420.06901 -380.99873)
				)
				(arc
					(start 419.874446 -380.99873)
					(mid 419.852702 -381.001898)
					(end 419.83279 -381.011176)
				)
				(arc
					(start 419.536626 -381.203962)
					(mid 419.494942 -381.216184)
					(end 419.453314 -381.203708)
				)
				(arc
					(start 419.15969 -381.011176)
					(mid 419.139766 -381.00194)
					(end 419.118034 -380.99873)
				)
				(arc
					(start 418.92347 -380.99873)
					(mid 418.869588 -381.021048)
					(end 418.84727 -381.07493)
				)
				(arc
					(start 418.84727 -381.76073)
					(mid 418.869588 -381.814612)
					(end 418.92347 -381.83693)
				)
				(arc
					(start 419.119304 -381.83693)
					(mid 419.141048 -381.833762)
					(end 419.16096 -381.824484)
				)
				(arc
					(start 419.454584 -381.631952)
					(mid 419.49624 -381.61955)
					(end 419.537896 -381.631952)
				)
			)
		)
	)
	(zone
		(layers "In1.Cu" "In2.Cu")
		(hatch none 0.5)
		(connect_pads
			(clearance 0)
		)
		(min_thickness 0.25)
		(keepout
			(tracks not_allowed)
			(vias allowed)
			(pads allowed)
			(copperpour not_allowed)
			(footprints allowed)
		)
		(placement
			(enabled no)
			(sheetname "")
		)
		(fill yes
			(thermal_gap 0.5)
			(thermal_bridge_width 0.5)
			(island_removal_mode 0)
		)
		(polygon
			(pts
				(arc
					(start 179.846224 -202.435206)
					(mid 179.185824 -202.435206)
					(end 179.846224 -202.435206)
				)
			)
		)
	)
	(zone
		(layers "In1.Cu" "In2.Cu")
		(hatch none 0.5)
		(connect_pads
			(clearance 0)
		)
		(min_thickness 0.25)
		(keepout
			(tracks not_allowed)
			(vias allowed)
			(pads allowed)
			(copperpour not_allowed)
			(footprints allowed)
		)
		(placement
			(enabled no)
			(sheetname "")
		)
		(fill yes
			(thermal_gap 0.5)
			(thermal_bridge_width 0.5)
			(island_removal_mode 0)
		)
		(polygon
			(pts
				(arc
					(start 194.934332 -265.335258)
					(mid 194.273932 -265.335258)
					(end 194.934332 -265.335258)
				)
			)
		)
	)
	(zone
		(layers "In1.Cu" "In2.Cu")
		(hatch none 0.5)
		(connect_pads
			(clearance 0)
		)
		(min_thickness 0.25)
		(keepout
			(tracks not_allowed)
			(vias allowed)
			(pads allowed)
			(copperpour not_allowed)
			(footprints allowed)
		)
		(placement
			(enabled no)
			(sheetname "")
		)
		(fill yes
			(thermal_gap 0.5)
			(thermal_bridge_width 0.5)
			(island_removal_mode 0)
		)
		(polygon
			(pts
				(arc
					(start 176.402238 -244.085364)
					(mid 175.741838 -244.085364)
					(end 176.402238 -244.085364)
				)
			)
		)
	)
	(zone
		(layers "In1.Cu" "In2.Cu")
		(hatch none 0.5)
		(connect_pads
			(clearance 0)
		)
		(min_thickness 0.25)
		(keepout
			(tracks not_allowed)
			(vias allowed)
			(pads allowed)
			(copperpour not_allowed)
			(footprints allowed)
		)
		(placement
			(enabled no)
			(sheetname "")
		)
		(fill yes
			(thermal_gap 0.5)
			(thermal_bridge_width 0.5)
			(island_removal_mode 0)
		)
		(polygon
			(pts
				(arc
					(start 420.242238 -239.835182)
					(mid 419.581838 -239.835182)
					(end 420.242238 -239.835182)
				)
			)
		)
	)
	(zone
		(layers "In1.Cu" "In2.Cu")
		(hatch none 0.5)
		(connect_pads
			(clearance 0)
		)
		(min_thickness 0.25)
		(keepout
			(tracks not_allowed)
			(vias allowed)
			(pads allowed)
			(copperpour not_allowed)
			(footprints allowed)
		)
		(placement
			(enabled no)
			(sheetname "")
		)
		(fill yes
			(thermal_gap 0.5)
			(thermal_bridge_width 0.5)
			(island_removal_mode 0)
		)
		(polygon
			(pts
				(arc
					(start 17.938242 -244.935248)
					(mid 17.277842 -244.935248)
					(end 17.938242 -244.935248)
				)
			)
		)
	)
	(zone
		(layers "In1.Cu" "In2.Cu")
		(hatch none 0.5)
		(connect_pads
			(clearance 0)
		)
		(min_thickness 0.25)
		(keepout
			(tracks not_allowed)
			(vias allowed)
			(pads allowed)
			(copperpour not_allowed)
			(footprints allowed)
		)
		(placement
			(enabled no)
			(sheetname "")
		)
		(fill yes
			(thermal_gap 0.5)
			(thermal_bridge_width 0.5)
			(island_removal_mode 0)
		)
		(polygon
			(pts
				(arc
					(start 14.418564 -421.805354)
					(mid 14.433443 -421.769433)
					(end 14.469364 -421.754554)
				)
				(arc
					(start 14.977364 -421.754554)
					(mid 15.013285 -421.769433)
					(end 15.028164 -421.805354)
				)
				(arc
					(start 15.028164 -422.46169)
					(mid 15.013285 -422.497611)
					(end 14.977364 -422.51249)
				)
				(arc
					(start 14.469364 -422.51249)
					(mid 14.433443 -422.497611)
					(end 14.418564 -422.46169)
				)
			)
		)
	)
	(zone
		(layers "In1.Cu" "In2.Cu")
		(hatch none 0.5)
		(connect_pads
			(clearance 0)
		)
		(min_thickness 0.25)
		(keepout
			(tracks not_allowed)
			(vias allowed)
			(pads allowed)
			(copperpour not_allowed)
			(footprints allowed)
		)
		(placement
			(enabled no)
			(sheetname "")
		)
		(fill yes
			(thermal_gap 0.5)
			(thermal_bridge_width 0.5)
			(island_removal_mode 0)
		)
		(polygon
			(pts
				(arc
					(start 435.330346 -274.684998)
					(mid 434.669946 -274.684998)
					(end 435.330346 -274.684998)
				)
			)
		)
	)
	(zone
		(layers "In1.Cu" "In2.Cu")
		(hatch none 0.5)
		(connect_pads
			(clearance 0)
		)
		(min_thickness 0.25)
		(keepout
			(tracks not_allowed)
			(vias allowed)
			(pads allowed)
			(copperpour not_allowed)
			(footprints allowed)
		)
		(placement
			(enabled no)
			(sheetname "")
		)
		(fill yes
			(thermal_gap 0.5)
			(thermal_bridge_width 0.5)
			(island_removal_mode 0)
		)
		(polygon
			(pts
				(arc
					(start 285.066232 -220.285056)
					(mid 284.405832 -220.285056)
					(end 285.066232 -220.285056)
				)
			)
		)
	)
	(zone
		(layers "In1.Cu" "In2.Cu")
		(hatch none 0.5)
		(connect_pads
			(clearance 0)
		)
		(min_thickness 0.25)
		(keepout
			(tracks not_allowed)
			(vias allowed)
			(pads allowed)
			(copperpour not_allowed)
			(footprints allowed)
		)
		(placement
			(enabled no)
			(sheetname "")
		)
		(fill yes
			(thermal_gap 0.5)
			(thermal_bridge_width 0.5)
			(island_removal_mode 0)
		)
		(polygon
			(pts
				(arc
					(start 427.786292 -239.835182)
					(mid 427.125892 -239.835182)
					(end 427.786292 -239.835182)
				)
			)
		)
	)
	(zone
		(layers "In1.Cu" "In2.Cu")
		(hatch none 0.5)
		(connect_pads
			(clearance 0)
		)
		(min_thickness 0.25)
		(keepout
			(tracks not_allowed)
			(vias allowed)
			(pads allowed)
			(copperpour not_allowed)
			(footprints allowed)
		)
		(placement
			(enabled no)
			(sheetname "")
		)
		(fill yes
			(thermal_gap 0.5)
			(thermal_bridge_width 0.5)
			(island_removal_mode 0)
		)
		(polygon
			(pts
				(arc
					(start 33.026096 -265.335258)
					(mid 32.365696 -265.335258)
					(end 33.026096 -265.335258)
				)
			)
		)
	)
	(zone
		(layers "In1.Cu" "In2.Cu")
		(hatch none 0.5)
		(connect_pads
			(clearance 0)
		)
		(min_thickness 0.25)
		(keepout
			(tracks not_allowed)
			(vias allowed)
			(pads allowed)
			(copperpour not_allowed)
			(footprints allowed)
		)
		(placement
			(enabled no)
			(sheetname "")
		)
		(fill yes
			(thermal_gap 0.5)
			(thermal_bridge_width 0.5)
			(island_removal_mode 0)
		)
		(polygon
			(pts
				(arc
					(start 435.330346 -215.18499)
					(mid 434.669946 -215.18499)
					(end 435.330346 -215.18499)
				)
			)
		)
	)
	(zone
		(layers "In1.Cu" "In2.Cu")
		(hatch none 0.5)
		(connect_pads
			(clearance 0)
		)
		(min_thickness 0.25)
		(keepout
			(tracks not_allowed)
			(vias allowed)
			(pads allowed)
			(copperpour not_allowed)
			(footprints allowed)
		)
		(placement
			(enabled no)
			(sheetname "")
		)
		(fill yes
			(thermal_gap 0.5)
			(thermal_bridge_width 0.5)
			(island_removal_mode 0)
		)
		(polygon
			(pts
				(arc
					(start 44.670218 -252.58522)
					(mid 44.009818 -252.58522)
					(end 44.670218 -252.58522)
				)
			)
		)
	)
	(zone
		(layers "In1.Cu" "In2.Cu")
		(hatch none 0.5)
		(connect_pads
			(clearance 0)
		)
		(min_thickness 0.25)
		(keepout
			(tracks not_allowed)
			(vias allowed)
			(pads allowed)
			(copperpour not_allowed)
			(footprints allowed)
		)
		(placement
			(enabled no)
			(sheetname "")
		)
		(fill yes
			(thermal_gap 0.5)
			(thermal_bridge_width 0.5)
			(island_removal_mode 0)
		)
		(polygon
			(pts
				(arc
					(start 307.698394 -244.08511)
					(mid 307.037994 -244.08511)
					(end 307.698394 -244.08511)
				)
			)
		)
	)
	(zone
		(layers "In1.Cu" "In2.Cu")
		(hatch none 0.5)
		(connect_pads
			(clearance 0)
		)
		(min_thickness 0.25)
		(keepout
			(tracks not_allowed)
			(vias allowed)
			(pads allowed)
			(copperpour not_allowed)
			(footprints allowed)
		)
		(placement
			(enabled no)
			(sheetname "")
		)
		(fill yes
			(thermal_gap 0.5)
			(thermal_bridge_width 0.5)
			(island_removal_mode 0)
		)
		(polygon
			(pts
				(arc
					(start 435.330346 -286.585152)
					(mid 434.669946 -286.585152)
					(end 435.330346 -286.585152)
				)
			)
		)
	)
	(zone
		(layers "In1.Cu" "In2.Cu")
		(hatch none 0.5)
		(connect_pads
			(clearance 0)
		)
		(min_thickness 0.25)
		(keepout
			(tracks not_allowed)
			(vias allowed)
			(pads allowed)
			(copperpour not_allowed)
			(footprints allowed)
		)
		(placement
			(enabled no)
			(sheetname "")
		)
		(fill yes
			(thermal_gap 0.5)
			(thermal_bridge_width 0.5)
			(island_removal_mode 0)
		)
		(polygon
			(pts
				(arc
					(start 49.972468 -7.672324)
					(mid 49.994786 -7.618442)
					(end 50.048668 -7.596124)
				)
				(arc
					(start 51.085242 -7.596124)
					(mid 51.139124 -7.618442)
					(end 51.161442 -7.672324)
				)
				(arc
					(start 51.161442 -9.071864)
					(mid 51.139124 -9.125746)
					(end 51.085242 -9.148064)
				)
				(arc
					(start 50.048668 -9.148064)
					(mid 49.994786 -9.125746)
					(end 49.972468 -9.071864)
				)
			)
		)
	)
	(zone
		(layers "In1.Cu" "In2.Cu")
		(hatch none 0.5)
		(connect_pads
			(clearance 0)
		)
		(min_thickness 0.25)
		(keepout
			(tracks not_allowed)
			(vias allowed)
			(pads allowed)
			(copperpour not_allowed)
			(footprints allowed)
		)
		(placement
			(enabled no)
			(sheetname "")
		)
		(fill yes
			(thermal_gap 0.5)
			(thermal_bridge_width 0.5)
			(island_removal_mode 0)
		)
		(polygon
			(pts
				(arc
					(start 29.582364 -210.935316)
					(mid 28.921964 -210.935316)
					(end 29.582364 -210.935316)
				)
			)
		)
	)
	(zone
		(layers "In1.Cu" "In2.Cu")
		(hatch none 0.5)
		(connect_pads
			(clearance 0)
		)
		(min_thickness 0.25)
		(keepout
			(tracks not_allowed)
			(vias allowed)
			(pads allowed)
			(copperpour not_allowed)
			(footprints allowed)
		)
		(placement
			(enabled no)
			(sheetname "")
		)
		(fill yes
			(thermal_gap 0.5)
			(thermal_bridge_width 0.5)
			(island_removal_mode 0)
		)
		(polygon
			(pts
				(arc
					(start 37.126164 -238.985298)
					(mid 36.465764 -238.985298)
					(end 37.126164 -238.985298)
				)
			)
		)
	)
	(zone
		(layers "In1.Cu" "In2.Cu")
		(hatch none 0.5)
		(connect_pads
			(clearance 0)
		)
		(min_thickness 0.25)
		(keepout
			(tracks not_allowed)
			(vias allowed)
			(pads allowed)
			(copperpour not_allowed)
			(footprints allowed)
		)
		(placement
			(enabled no)
			(sheetname "")
		)
		(fill yes
			(thermal_gap 0.5)
			(thermal_bridge_width 0.5)
			(island_removal_mode 0)
		)
		(polygon
			(pts
				(arc
					(start 59.758326 -244.08511)
					(mid 59.097926 -244.08511)
					(end 59.758326 -244.08511)
				)
			)
		)
	)
	(zone
		(layers "In1.Cu" "In2.Cu")
		(hatch none 0.5)
		(connect_pads
			(clearance 0)
		)
		(min_thickness 0.25)
		(keepout
			(tracks not_allowed)
			(vias allowed)
			(pads allowed)
			(copperpour not_allowed)
			(footprints allowed)
		)
		(placement
			(enabled no)
			(sheetname "")
		)
		(fill yes
			(thermal_gap 0.5)
			(thermal_bridge_width 0.5)
			(island_removal_mode 0)
		)
		(polygon
			(pts
				(arc
					(start 435.330346 -241.53495)
					(mid 434.669946 -241.53495)
					(end 435.330346 -241.53495)
				)
			)
		)
	)
	(zone
		(layers "In1.Cu" "In2.Cu")
		(hatch none 0.5)
		(connect_pads
			(clearance 0)
		)
		(min_thickness 0.25)
		(keepout
			(tracks not_allowed)
			(vias allowed)
			(pads allowed)
			(copperpour not_allowed)
			(footprints allowed)
		)
		(placement
			(enabled no)
			(sheetname "")
		)
		(fill yes
			(thermal_gap 0.5)
			(thermal_bridge_width 0.5)
			(island_removal_mode 0)
		)
		(polygon
			(pts
				(arc
					(start 454.518268 -212.635084)
					(mid 453.857868 -212.635084)
					(end 454.518268 -212.635084)
				)
			)
		)
	)
	(zone
		(layers "In1.Cu" "In2.Cu")
		(hatch none 0.5)
		(connect_pads
			(clearance 0)
		)
		(min_thickness 0.25)
		(keepout
			(tracks not_allowed)
			(vias allowed)
			(pads allowed)
			(copperpour not_allowed)
			(footprints allowed)
		)
		(placement
			(enabled no)
			(sheetname "")
		)
		(fill yes
			(thermal_gap 0.5)
			(thermal_bridge_width 0.5)
			(island_removal_mode 0)
		)
		(polygon
			(pts
				(arc
					(start 442.8744 -220.285056)
					(mid 442.214 -220.285056)
					(end 442.8744 -220.285056)
				)
			)
		)
	)
	(zone
		(layers "In1.Cu" "In2.Cu")
		(hatch none 0.5)
		(connect_pads
			(clearance 0)
		)
		(min_thickness 0.25)
		(keepout
			(tracks not_allowed)
			(vias allowed)
			(pads allowed)
			(copperpour not_allowed)
			(footprints allowed)
		)
		(placement
			(enabled no)
			(sheetname "")
		)
		(fill yes
			(thermal_gap 0.5)
			(thermal_bridge_width 0.5)
			(island_removal_mode 0)
		)
		(polygon
			(pts
				(arc
					(start 450.4182 -285.735014)
					(mid 449.7578 -285.735014)
					(end 450.4182 -285.735014)
				)
			)
		)
	)
	(zone
		(layers "In1.Cu" "In2.Cu")
		(hatch none 0.5)
		(connect_pads
			(clearance 0)
		)
		(min_thickness 0.25)
		(keepout
			(tracks not_allowed)
			(vias allowed)
			(pads allowed)
			(copperpour not_allowed)
			(footprints allowed)
		)
		(placement
			(enabled no)
			(sheetname "")
		)
		(fill yes
			(thermal_gap 0.5)
			(thermal_bridge_width 0.5)
			(island_removal_mode 0)
		)
		(polygon
			(pts
				(arc
					(start 424.342306 -219.435172)
					(mid 423.681906 -219.435172)
					(end 424.342306 -219.435172)
				)
			)
		)
	)
	(zone
		(layers "In1.Cu" "In2.Cu")
		(hatch none 0.5)
		(connect_pads
			(clearance 0)
		)
		(min_thickness 0.25)
		(keepout
			(tracks not_allowed)
			(vias allowed)
			(pads allowed)
			(copperpour not_allowed)
			(footprints allowed)
		)
		(placement
			(enabled no)
			(sheetname "")
		)
		(fill yes
			(thermal_gap 0.5)
			(thermal_bridge_width 0.5)
			(island_removal_mode 0)
		)
		(polygon
			(pts
				(arc
					(start 172.30217 -308.685438)
					(mid 171.64177 -308.685438)
					(end 172.30217 -308.685438)
				)
			)
		)
	)
	(zone
		(layers "In1.Cu" "In2.Cu")
		(hatch none 0.5)
		(connect_pads
			(clearance 0)
		)
		(min_thickness 0.25)
		(keepout
			(tracks not_allowed)
			(vias allowed)
			(pads allowed)
			(copperpour not_allowed)
			(footprints allowed)
		)
		(placement
			(enabled no)
			(sheetname "")
		)
		(fill yes
			(thermal_gap 0.5)
			(thermal_bridge_width 0.5)
			(island_removal_mode 0)
		)
		(polygon
			(pts
				(arc
					(start 191.490346 -200.735438)
					(mid 190.829946 -200.735438)
					(end 191.490346 -200.735438)
				)
			)
		)
	)
	(zone
		(layers "In1.Cu" "In2.Cu")
		(hatch none 0.5)
		(connect_pads
			(clearance 0)
		)
		(min_thickness 0.25)
		(keepout
			(tracks not_allowed)
			(vias allowed)
			(pads allowed)
			(copperpour not_allowed)
			(footprints allowed)
		)
		(placement
			(enabled no)
			(sheetname "")
		)
		(fill yes
			(thermal_gap 0.5)
			(thermal_bridge_width 0.5)
			(island_removal_mode 0)
		)
		(polygon
			(pts
				(arc
					(start 277.522432 -309.535068)
					(mid 276.862032 -309.535068)
					(end 277.522432 -309.535068)
				)
			)
		)
	)
	(zone
		(layers "In1.Cu" "In2.Cu")
		(hatch none 0.5)
		(connect_pads
			(clearance 0)
		)
		(min_thickness 0.25)
		(keepout
			(tracks not_allowed)
			(vias allowed)
			(pads allowed)
			(copperpour not_allowed)
			(footprints allowed)
		)
		(placement
			(enabled no)
			(sheetname "")
		)
		(fill yes
			(thermal_gap 0.5)
			(thermal_bridge_width 0.5)
			(island_removal_mode 0)
		)
		(polygon
			(pts
				(arc
					(start 427.786292 -312.084974)
					(mid 427.125892 -312.084974)
					(end 427.786292 -312.084974)
				)
			)
		)
	)
	(zone
		(layers "In1.Cu" "In2.Cu")
		(hatch none 0.5)
		(connect_pads
			(clearance 0)
		)
		(min_thickness 0.25)
		(keepout
			(tracks not_allowed)
			(vias allowed)
			(pads allowed)
			(copperpour not_allowed)
			(footprints allowed)
		)
		(placement
			(enabled no)
			(sheetname "")
		)
		(fill yes
			(thermal_gap 0.5)
			(thermal_bridge_width 0.5)
			(island_removal_mode 0)
		)
		(polygon
			(pts
				(arc
					(start 280.966164 -209.23504)
					(mid 280.305764 -209.23504)
					(end 280.966164 -209.23504)
				)
			)
		)
	)
	(zone
		(layers "In1.Cu" "In2.Cu")
		(hatch none 0.5)
		(connect_pads
			(clearance 0)
		)
		(min_thickness 0.25)
		(keepout
			(tracks not_allowed)
			(vias allowed)
			(pads allowed)
			(copperpour not_allowed)
			(footprints allowed)
		)
		(placement
			(enabled no)
			(sheetname "")
		)
		(fill yes
			(thermal_gap 0.5)
			(thermal_bridge_width 0.5)
			(island_removal_mode 0)
		)
		(polygon
			(pts
				(arc
					(start 431.88636 -214.335106)
					(mid 431.22596 -214.335106)
					(end 431.88636 -214.335106)
				)
			)
		)
	)
	(zone
		(layers "In1.Cu" "In2.Cu")
		(hatch none 0.5)
		(connect_pads
			(clearance 0)
		)
		(min_thickness 0.25)
		(keepout
			(tracks not_allowed)
			(vias allowed)
			(pads allowed)
			(copperpour not_allowed)
			(footprints allowed)
		)
		(placement
			(enabled no)
			(sheetname "")
		)
		(fill yes
			(thermal_gap 0.5)
			(thermal_bridge_width 0.5)
			(island_removal_mode 0)
		)
		(polygon
			(pts
				(arc
					(start 269.978378 -275.535136)
					(mid 269.317978 -275.535136)
					(end 269.978378 -275.535136)
				)
			)
		)
	)
	(zone
		(layers "In1.Cu" "In2.Cu")
		(hatch none 0.5)
		(connect_pads
			(clearance 0)
		)
		(min_thickness 0.25)
		(keepout
			(tracks not_allowed)
			(vias allowed)
			(pads allowed)
			(copperpour not_allowed)
			(footprints allowed)
		)
		(placement
			(enabled no)
			(sheetname "")
		)
		(fill yes
			(thermal_gap 0.5)
			(thermal_bridge_width 0.5)
			(island_removal_mode 0)
		)
		(polygon
			(pts
				(arc
					(start 292.610286 -261.085076)
					(mid 291.949886 -261.085076)
					(end 292.610286 -261.085076)
				)
			)
		)
	)
	(zone
		(layers "In1.Cu" "In2.Cu")
		(hatch none 0.5)
		(connect_pads
			(clearance 0)
		)
		(min_thickness 0.25)
		(keepout
			(tracks not_allowed)
			(vias allowed)
			(pads allowed)
			(copperpour not_allowed)
			(footprints allowed)
		)
		(placement
			(enabled no)
			(sheetname "")
		)
		(fill yes
			(thermal_gap 0.5)
			(thermal_bridge_width 0.5)
			(island_removal_mode 0)
		)
		(polygon
			(pts
				(arc
					(start 435.330346 -285.735014)
					(mid 434.669946 -285.735014)
					(end 435.330346 -285.735014)
				)
			)
		)
	)
	(zone
		(layers "In1.Cu" "In2.Cu")
		(hatch none 0.5)
		(connect_pads
			(clearance 0)
		)
		(min_thickness 0.25)
		(keepout
			(tracks not_allowed)
			(vias allowed)
			(pads allowed)
			(copperpour not_allowed)
			(footprints allowed)
		)
		(placement
			(enabled no)
			(sheetname "")
		)
		(fill yes
			(thermal_gap 0.5)
			(thermal_bridge_width 0.5)
			(island_removal_mode 0)
		)
		(polygon
			(pts
				(arc
					(start 26.052272 -7.672324)
					(mid 26.07459 -7.618442)
					(end 26.128472 -7.596124)
				)
				(arc
					(start 27.165046 -7.596124)
					(mid 27.218928 -7.618442)
					(end 27.241246 -7.672324)
				)
				(arc
					(start 27.241246 -9.071864)
					(mid 27.218928 -9.125746)
					(end 27.165046 -9.148064)
				)
				(arc
					(start 26.128472 -9.148064)
					(mid 26.07459 -9.125746)
					(end 26.052272 -9.071864)
				)
			)
		)
	)
	(zone
		(layers "In1.Cu" "In2.Cu")
		(hatch none 0.5)
		(connect_pads
			(clearance 0)
		)
		(min_thickness 0.25)
		(keepout
			(tracks not_allowed)
			(vias allowed)
			(pads allowed)
			(copperpour not_allowed)
			(footprints allowed)
		)
		(placement
			(enabled no)
			(sheetname "")
		)
		(fill yes
			(thermal_gap 0.5)
			(thermal_bridge_width 0.5)
			(island_removal_mode 0)
		)
		(polygon
			(pts
				(arc
					(start 427.786292 -211.784946)
					(mid 427.125892 -211.784946)
					(end 427.786292 -211.784946)
				)
			)
		)
	)
	(zone
		(layers "In1.Cu" "In2.Cu")
		(hatch none 0.5)
		(connect_pads
			(clearance 0)
		)
		(min_thickness 0.25)
		(keepout
			(tracks not_allowed)
			(vias allowed)
			(pads allowed)
			(copperpour not_allowed)
			(footprints allowed)
		)
		(placement
			(enabled no)
			(sheetname "")
		)
		(fill yes
			(thermal_gap 0.5)
			(thermal_bridge_width 0.5)
			(island_removal_mode 0)
		)
		(polygon
			(pts
				(arc
					(start 288.510218 -210.935062)
					(mid 287.849818 -210.935062)
					(end 288.510218 -210.935062)
				)
			)
		)
	)
	(zone
		(layers "In1.Cu" "In2.Cu")
		(hatch none 0.5)
		(connect_pads
			(clearance 0)
		)
		(min_thickness 0.25)
		(keepout
			(tracks not_allowed)
			(vias allowed)
			(pads allowed)
			(copperpour not_allowed)
			(footprints allowed)
		)
		(placement
			(enabled no)
			(sheetname "")
		)
		(fill yes
			(thermal_gap 0.5)
			(thermal_bridge_width 0.5)
			(island_removal_mode 0)
		)
		(polygon
			(pts
				(arc
					(start 450.4182 -248.335038)
					(mid 449.7578 -248.335038)
					(end 450.4182 -248.335038)
				)
			)
		)
	)
	(zone
		(layers "In1.Cu" "In2.Cu")
		(hatch none 0.5)
		(connect_pads
			(clearance 0)
		)
		(min_thickness 0.25)
		(keepout
			(tracks not_allowed)
			(vias allowed)
			(pads allowed)
			(copperpour not_allowed)
			(footprints allowed)
		)
		(placement
			(enabled no)
			(sheetname "")
		)
		(fill yes
			(thermal_gap 0.5)
			(thermal_bridge_width 0.5)
			(island_removal_mode 0)
		)
		(polygon
			(pts
				(arc
					(start 176.402238 -225.385376)
					(mid 175.741838 -225.385376)
					(end 176.402238 -225.385376)
				)
			)
		)
	)
	(zone
		(layers "In1.Cu" "In2.Cu")
		(hatch none 0.5)
		(connect_pads
			(clearance 0)
		)
		(min_thickness 0.25)
		(keepout
			(tracks not_allowed)
			(vias allowed)
			(pads allowed)
			(copperpour not_allowed)
			(footprints allowed)
		)
		(placement
			(enabled no)
			(sheetname "")
		)
		(fill yes
			(thermal_gap 0.5)
			(thermal_bridge_width 0.5)
			(island_removal_mode 0)
		)
		(polygon
			(pts
				(arc
					(start 44.670218 -197.335394)
					(mid 44.009818 -197.335394)
					(end 44.670218 -197.335394)
				)
			)
		)
	)
	(zone
		(layers "In1.Cu" "In2.Cu")
		(hatch none 0.5)
		(connect_pads
			(clearance 0)
		)
		(min_thickness 0.25)
		(keepout
			(tracks not_allowed)
			(vias allowed)
			(pads allowed)
			(copperpour not_allowed)
			(footprints allowed)
		)
		(placement
			(enabled no)
			(sheetname "")
		)
		(fill yes
			(thermal_gap 0.5)
			(thermal_bridge_width 0.5)
			(island_removal_mode 0)
		)
		(polygon
			(pts
				(arc
					(start 450.4182 -316.335156)
					(mid 449.7578 -316.335156)
					(end 450.4182 -316.335156)
				)
			)
		)
	)
	(zone
		(layers "In1.Cu" "In2.Cu")
		(hatch none 0.5)
		(connect_pads
			(clearance 0)
		)
		(min_thickness 0.25)
		(keepout
			(tracks not_allowed)
			(vias allowed)
			(pads allowed)
			(copperpour not_allowed)
			(footprints allowed)
		)
		(placement
			(enabled no)
			(sheetname "")
		)
		(fill yes
			(thermal_gap 0.5)
			(thermal_bridge_width 0.5)
			(island_removal_mode 0)
		)
		(polygon
			(pts
				(arc
					(start 48.114204 -272.98523)
					(mid 47.453804 -272.98523)
					(end 48.114204 -272.98523)
				)
			)
		)
	)
	(zone
		(layers "In1.Cu" "In2.Cu")
		(hatch none 0.5)
		(connect_pads
			(clearance 0)
		)
		(min_thickness 0.25)
		(keepout
			(tracks not_allowed)
			(vias allowed)
			(pads allowed)
			(copperpour not_allowed)
			(footprints allowed)
		)
		(placement
			(enabled no)
			(sheetname "")
		)
		(fill yes
			(thermal_gap 0.5)
			(thermal_bridge_width 0.5)
			(island_removal_mode 0)
		)
		(polygon
			(pts
				(arc
					(start 454.518268 -199.035162)
					(mid 453.857868 -199.035162)
					(end 454.518268 -199.035162)
				)
			)
		)
	)
	(zone
		(layers "In1.Cu" "In2.Cu")
		(hatch none 0.5)
		(connect_pads
			(clearance 0)
		)
		(min_thickness 0.25)
		(keepout
			(tracks not_allowed)
			(vias allowed)
			(pads allowed)
			(copperpour not_allowed)
			(footprints allowed)
		)
		(placement
			(enabled no)
			(sheetname "")
		)
		(fill yes
			(thermal_gap 0.5)
			(thermal_bridge_width 0.5)
			(island_removal_mode 0)
		)
		(polygon
			(pts
				(arc
					(start 37.126164 -227.085398)
					(mid 36.465764 -227.085398)
					(end 37.126164 -227.085398)
				)
			)
		)
	)
	(zone
		(layers "In1.Cu" "In2.Cu")
		(hatch none 0.5)
		(connect_pads
			(clearance 0)
		)
		(min_thickness 0.25)
		(keepout
			(tracks not_allowed)
			(vias allowed)
			(pads allowed)
			(copperpour not_allowed)
			(footprints allowed)
		)
		(placement
			(enabled no)
			(sheetname "")
		)
		(fill yes
			(thermal_gap 0.5)
			(thermal_bridge_width 0.5)
			(island_removal_mode 0)
		)
		(polygon
			(pts
				(arc
					(start 280.966164 -226.235006)
					(mid 280.305764 -226.235006)
					(end 280.966164 -226.235006)
				)
			)
		)
	)
	(zone
		(layers "In1.Cu" "In2.Cu")
		(hatch none 0.5)
		(connect_pads
			(clearance 0)
		)
		(min_thickness 0.25)
		(keepout
			(tracks not_allowed)
			(vias allowed)
			(pads allowed)
			(copperpour not_allowed)
			(footprints allowed)
		)
		(placement
			(enabled no)
			(sheetname "")
		)
		(fill yes
			(thermal_gap 0.5)
			(thermal_bridge_width 0.5)
			(island_removal_mode 0)
		)
		(polygon
			(pts
				(arc
					(start 29.582364 -296.785284)
					(mid 28.921964 -296.785284)
					(end 29.582364 -296.785284)
				)
			)
		)
	)
	(zone
		(layers "In1.Cu" "In2.Cu")
		(hatch none 0.5)
		(connect_pads
			(clearance 0)
		)
		(min_thickness 0.25)
		(keepout
			(tracks not_allowed)
			(vias allowed)
			(pads allowed)
			(copperpour not_allowed)
			(footprints allowed)
		)
		(placement
			(enabled no)
			(sheetname "")
		)
		(fill yes
			(thermal_gap 0.5)
			(thermal_bridge_width 0.5)
			(island_removal_mode 0)
		)
		(polygon
			(pts
				(arc
					(start 187.390278 -310.385206)
					(mid 186.729878 -310.385206)
					(end 187.390278 -310.385206)
				)
			)
		)
	)
	(zone
		(layers "In1.Cu" "In2.Cu")
		(hatch none 0.5)
		(connect_pads
			(clearance 0)
		)
		(min_thickness 0.25)
		(keepout
			(tracks not_allowed)
			(vias allowed)
			(pads allowed)
			(copperpour not_allowed)
			(footprints allowed)
		)
		(placement
			(enabled no)
			(sheetname "")
		)
		(fill yes
			(thermal_gap 0.5)
			(thermal_bridge_width 0.5)
			(island_removal_mode 0)
		)
		(polygon
			(pts
				(arc
					(start 194.934332 -305.285394)
					(mid 194.273932 -305.285394)
					(end 194.934332 -305.285394)
				)
			)
		)
	)
	(zone
		(layers "In1.Cu" "In2.Cu")
		(hatch none 0.5)
		(connect_pads
			(clearance 0)
		)
		(min_thickness 0.25)
		(keepout
			(tracks not_allowed)
			(vias allowed)
			(pads allowed)
			(copperpour not_allowed)
			(footprints allowed)
		)
		(placement
			(enabled no)
			(sheetname "")
		)
		(fill yes
			(thermal_gap 0.5)
			(thermal_bridge_width 0.5)
			(island_removal_mode 0)
		)
		(polygon
			(pts
				(arc
					(start 187.390278 -280.635202)
					(mid 186.729878 -280.635202)
					(end 187.390278 -280.635202)
				)
			)
		)
	)
	(zone
		(layers "In1.Cu" "In2.Cu")
		(hatch none 0.5)
		(connect_pads
			(clearance 0)
		)
		(min_thickness 0.25)
		(keepout
			(tracks not_allowed)
			(vias allowed)
			(pads allowed)
			(copperpour not_allowed)
			(footprints allowed)
		)
		(placement
			(enabled no)
			(sheetname "")
		)
		(fill yes
			(thermal_gap 0.5)
			(thermal_bridge_width 0.5)
			(island_removal_mode 0)
		)
		(polygon
			(pts
				(arc
					(start 199.0344 -290.835334)
					(mid 198.374 -290.835334)
					(end 199.0344 -290.835334)
				)
			)
		)
	)
	(zone
		(layers "In1.Cu" "In2.Cu")
		(hatch none 0.5)
		(connect_pads
			(clearance 0)
		)
		(min_thickness 0.25)
		(keepout
			(tracks not_allowed)
			(vias allowed)
			(pads allowed)
			(copperpour not_allowed)
			(footprints allowed)
		)
		(placement
			(enabled no)
			(sheetname "")
		)
		(fill yes
			(thermal_gap 0.5)
			(thermal_bridge_width 0.5)
			(island_removal_mode 0)
		)
		(polygon
			(pts
				(arc
					(start 22.03831 -204.985366)
					(mid 21.37791 -204.985366)
					(end 22.03831 -204.985366)
				)
			)
		)
	)
	(zone
		(layers "In1.Cu" "In2.Cu")
		(hatch none 0.5)
		(connect_pads
			(clearance 0)
		)
		(min_thickness 0.25)
		(keepout
			(tracks not_allowed)
			(vias allowed)
			(pads allowed)
			(copperpour not_allowed)
			(footprints allowed)
		)
		(placement
			(enabled no)
			(sheetname "")
		)
		(fill yes
			(thermal_gap 0.5)
			(thermal_bridge_width 0.5)
			(island_removal_mode 0)
		)
		(polygon
			(pts
				(arc
					(start 176.402238 -210.935316)
					(mid 175.741838 -210.935316)
					(end 176.402238 -210.935316)
				)
			)
		)
	)
	(zone
		(layers "In1.Cu" "In2.Cu")
		(hatch none 0.5)
		(connect_pads
			(clearance 0)
		)
		(min_thickness 0.25)
		(keepout
			(tracks not_allowed)
			(vias allowed)
			(pads allowed)
			(copperpour not_allowed)
			(footprints allowed)
		)
		(placement
			(enabled no)
			(sheetname "")
		)
		(fill yes
			(thermal_gap 0.5)
			(thermal_bridge_width 0.5)
			(island_removal_mode 0)
		)
		(polygon
			(pts
				(arc
					(start 446.974468 -244.08511)
					(mid 446.314068 -244.08511)
					(end 446.974468 -244.08511)
				)
			)
		)
	)
	(zone
		(layers "In1.Cu" "In2.Cu")
		(hatch none 0.5)
		(connect_pads
			(clearance 0)
		)
		(min_thickness 0.25)
		(keepout
			(tracks not_allowed)
			(vias allowed)
			(pads allowed)
			(copperpour not_allowed)
			(footprints allowed)
		)
		(placement
			(enabled no)
			(sheetname "")
		)
		(fill yes
			(thermal_gap 0.5)
			(thermal_bridge_width 0.5)
			(island_removal_mode 0)
		)
		(polygon
			(pts
				(arc
					(start 454.518268 -204.985112)
					(mid 453.857868 -204.985112)
					(end 454.518268 -204.985112)
				)
			)
		)
	)
	(zone
		(layers "In1.Cu" "In2.Cu")
		(hatch none 0.5)
		(connect_pads
			(clearance 0)
		)
		(min_thickness 0.25)
		(keepout
			(tracks not_allowed)
			(vias allowed)
			(pads allowed)
			(copperpour not_allowed)
			(footprints allowed)
		)
		(placement
			(enabled no)
			(sheetname "")
		)
		(fill yes
			(thermal_gap 0.5)
			(thermal_bridge_width 0.5)
			(island_removal_mode 0)
		)
		(polygon
			(pts
				(arc
					(start 285.066232 -317.18504)
					(mid 284.405832 -317.18504)
					(end 285.066232 -317.18504)
				)
			)
		)
	)
	(zone
		(layers "In1.Cu" "In2.Cu")
		(hatch none 0.5)
		(connect_pads
			(clearance 0)
		)
		(min_thickness 0.25)
		(keepout
			(tracks not_allowed)
			(vias allowed)
			(pads allowed)
			(copperpour not_allowed)
			(footprints allowed)
		)
		(placement
			(enabled no)
			(sheetname "")
		)
		(fill yes
			(thermal_gap 0.5)
			(thermal_bridge_width 0.5)
			(island_removal_mode 0)
		)
		(polygon
			(pts
				(arc
					(start 22.03831 -228.78542)
					(mid 21.37791 -228.78542)
					(end 22.03831 -228.78542)
				)
			)
		)
	)
	(zone
		(layers "In1.Cu" "In2.Cu")
		(hatch none 0.5)
		(connect_pads
			(clearance 0)
		)
		(min_thickness 0.25)
		(keepout
			(tracks not_allowed)
			(vias allowed)
			(pads allowed)
			(copperpour not_allowed)
			(footprints allowed)
		)
		(placement
			(enabled no)
			(sheetname "")
		)
		(fill yes
			(thermal_gap 0.5)
			(thermal_bridge_width 0.5)
			(island_removal_mode 0)
		)
		(polygon
			(pts
				(arc
					(start 191.490346 -292.535356)
					(mid 190.829946 -292.535356)
					(end 191.490346 -292.535356)
				)
			)
		)
	)
	(zone
		(layers "In1.Cu" "In2.Cu")
		(hatch none 0.5)
		(connect_pads
			(clearance 0)
		)
		(min_thickness 0.25)
		(keepout
			(tracks not_allowed)
			(vias allowed)
			(pads allowed)
			(copperpour not_allowed)
			(footprints allowed)
		)
		(placement
			(enabled no)
			(sheetname "")
		)
		(fill yes
			(thermal_gap 0.5)
			(thermal_bridge_width 0.5)
			(island_removal_mode 0)
		)
		(polygon
			(pts
				(arc
					(start 300.15434 -244.08511)
					(mid 299.49394 -244.08511)
					(end 300.15434 -244.08511)
				)
			)
		)
	)
	(zone
		(layers "In1.Cu" "In2.Cu")
		(hatch none 0.5)
		(connect_pads
			(clearance 0)
		)
		(min_thickness 0.25)
		(keepout
			(tracks not_allowed)
			(vias allowed)
			(pads allowed)
			(copperpour not_allowed)
			(footprints allowed)
		)
		(placement
			(enabled no)
			(sheetname "")
		)
		(fill yes
			(thermal_gap 0.5)
			(thermal_bridge_width 0.5)
			(island_removal_mode 0)
		)
		(polygon
			(pts
				(arc
					(start 194.934332 -278.935434)
					(mid 194.273932 -278.935434)
					(end 194.934332 -278.935434)
				)
			)
		)
	)
	(zone
		(layers "In1.Cu" "In2.Cu")
		(hatch none 0.5)
		(connect_pads
			(clearance 0)
		)
		(min_thickness 0.25)
		(keepout
			(tracks not_allowed)
			(vias allowed)
			(pads allowed)
			(copperpour not_allowed)
			(footprints allowed)
		)
		(placement
			(enabled no)
			(sheetname "")
		)
		(fill yes
			(thermal_gap 0.5)
			(thermal_bridge_width 0.5)
			(island_removal_mode 0)
		)
		(polygon
			(pts
				(arc
					(start 235.862876 -50.148744)
					(mid 235.885194 -50.094862)
					(end 235.939076 -50.072544)
				)
				(arc
					(start 237.15853 -50.072544)
					(mid 237.212412 -50.094862)
					(end 237.23473 -50.148744)
				)
				(arc
					(start 237.23473 -51.180746)
					(mid 237.212412 -51.234628)
					(end 237.15853 -51.256946)
				)
				(arc
					(start 235.939076 -51.256946)
					(mid 235.885194 -51.234628)
					(end 235.862876 -51.180746)
				)
			)
		)
	)
	(zone
		(layers "In1.Cu" "In2.Cu")
		(hatch none 0.5)
		(connect_pads
			(clearance 0)
		)
		(min_thickness 0.25)
		(keepout
			(tracks not_allowed)
			(vias allowed)
			(pads allowed)
			(copperpour not_allowed)
			(footprints allowed)
		)
		(placement
			(enabled no)
			(sheetname "")
		)
		(fill yes
			(thermal_gap 0.5)
			(thermal_bridge_width 0.5)
			(island_removal_mode 0)
		)
		(polygon
			(pts
				(arc
					(start 40.57015 -209.235294)
					(mid 39.90975 -209.235294)
					(end 40.57015 -209.235294)
				)
			)
		)
	)
	(zone
		(layers "In1.Cu" "In2.Cu")
		(hatch none 0.5)
		(connect_pads
			(clearance 0)
		)
		(min_thickness 0.25)
		(keepout
			(tracks not_allowed)
			(vias allowed)
			(pads allowed)
			(copperpour not_allowed)
			(footprints allowed)
		)
		(placement
			(enabled no)
			(sheetname "")
		)
		(fill yes
			(thermal_gap 0.5)
			(thermal_bridge_width 0.5)
			(island_removal_mode 0)
		)
		(polygon
			(pts
				(arc
					(start 183.946292 -261.08533)
					(mid 183.285892 -261.08533)
					(end 183.946292 -261.08533)
				)
			)
		)
	)
	(zone
		(layers "In1.Cu" "In2.Cu")
		(hatch none 0.5)
		(connect_pads
			(clearance 0)
		)
		(min_thickness 0.25)
		(keepout
			(tracks not_allowed)
			(vias allowed)
			(pads allowed)
			(copperpour not_allowed)
			(footprints allowed)
		)
		(placement
			(enabled no)
			(sheetname "")
		)
		(fill yes
			(thermal_gap 0.5)
			(thermal_bridge_width 0.5)
			(island_removal_mode 0)
		)
		(polygon
			(pts
				(arc
					(start 25.482296 -209.235294)
					(mid 24.821896 -209.235294)
					(end 25.482296 -209.235294)
				)
			)
		)
	)
	(zone
		(layers "In1.Cu" "In2.Cu")
		(hatch none 0.5)
		(connect_pads
			(clearance 0)
		)
		(min_thickness 0.25)
		(keepout
			(tracks not_allowed)
			(vias allowed)
			(pads allowed)
			(copperpour not_allowed)
			(footprints allowed)
		)
		(placement
			(enabled no)
			(sheetname "")
		)
		(fill yes
			(thermal_gap 0.5)
			(thermal_bridge_width 0.5)
			(island_removal_mode 0)
		)
		(polygon
			(pts
				(arc
					(start 277.522432 -203.28509)
					(mid 276.862032 -203.28509)
					(end 277.522432 -203.28509)
				)
			)
		)
	)
	(zone
		(layers "In1.Cu" "In2.Cu")
		(hatch none 0.5)
		(connect_pads
			(clearance 0)
		)
		(min_thickness 0.25)
		(keepout
			(tracks not_allowed)
			(vias allowed)
			(pads allowed)
			(copperpour not_allowed)
			(footprints allowed)
		)
		(placement
			(enabled no)
			(sheetname "")
		)
		(fill yes
			(thermal_gap 0.5)
			(thermal_bridge_width 0.5)
			(island_removal_mode 0)
		)
		(polygon
			(pts
				(arc
					(start 446.974468 -281.485086)
					(mid 446.314068 -281.485086)
					(end 446.974468 -281.485086)
				)
			)
		)
	)
	(zone
		(layers "In1.Cu" "In2.Cu")
		(hatch none 0.5)
		(connect_pads
			(clearance 0)
		)
		(min_thickness 0.25)
		(keepout
			(tracks not_allowed)
			(vias allowed)
			(pads allowed)
			(copperpour not_allowed)
			(footprints allowed)
		)
		(placement
			(enabled no)
			(sheetname "")
		)
		(fill yes
			(thermal_gap 0.5)
			(thermal_bridge_width 0.5)
			(island_removal_mode 0)
		)
		(polygon
			(pts
				(arc
					(start 199.0344 -262.785352)
					(mid 198.374 -262.785352)
					(end 199.0344 -262.785352)
				)
			)
		)
	)
	(zone
		(layers "In1.Cu" "In2.Cu")
		(hatch none 0.5)
		(connect_pads
			(clearance 0)
		)
		(min_thickness 0.25)
		(keepout
			(tracks not_allowed)
			(vias allowed)
			(pads allowed)
			(copperpour not_allowed)
			(footprints allowed)
		)
		(placement
			(enabled no)
			(sheetname "")
		)
		(fill yes
			(thermal_gap 0.5)
			(thermal_bridge_width 0.5)
			(island_removal_mode 0)
		)
		(polygon
			(pts
				(arc
					(start 202.478132 -224.535238)
					(mid 201.817732 -224.535238)
					(end 202.478132 -224.535238)
				)
			)
		)
	)
	(zone
		(layers "In1.Cu" "In2.Cu")
		(hatch none 0.5)
		(connect_pads
			(clearance 0)
		)
		(min_thickness 0.25)
		(keepout
			(tracks not_allowed)
			(vias allowed)
			(pads allowed)
			(copperpour not_allowed)
			(footprints allowed)
		)
		(placement
			(enabled no)
			(sheetname "")
		)
		(fill yes
			(thermal_gap 0.5)
			(thermal_bridge_width 0.5)
			(island_removal_mode 0)
		)
		(polygon
			(pts
				(arc
					(start 288.510218 -267.035026)
					(mid 287.849818 -267.035026)
					(end 288.510218 -267.035026)
				)
			)
		)
	)
	(zone
		(layers "In1.Cu" "In2.Cu")
		(hatch none 0.5)
		(connect_pads
			(clearance 0)
		)
		(min_thickness 0.25)
		(keepout
			(tracks not_allowed)
			(vias allowed)
			(pads allowed)
			(copperpour not_allowed)
			(footprints allowed)
		)
		(placement
			(enabled no)
			(sheetname "")
		)
		(fill yes
			(thermal_gap 0.5)
			(thermal_bridge_width 0.5)
			(island_removal_mode 0)
		)
		(polygon
			(pts
				(arc
					(start 277.522432 -313.784996)
					(mid 276.862032 -313.784996)
					(end 277.522432 -313.784996)
				)
			)
		)
	)
	(zone
		(layers "In1.Cu" "In2.Cu")
		(hatch none 0.5)
		(connect_pads
			(clearance 0)
		)
		(min_thickness 0.25)
		(keepout
			(tracks not_allowed)
			(vias allowed)
			(pads allowed)
			(copperpour not_allowed)
			(footprints allowed)
		)
		(placement
			(enabled no)
			(sheetname "")
		)
		(fill yes
			(thermal_gap 0.5)
			(thermal_bridge_width 0.5)
			(island_removal_mode 0)
		)
		(polygon
			(pts
				(arc
					(start 183.946292 -304.435256)
					(mid 183.285892 -304.435256)
					(end 183.946292 -304.435256)
				)
			)
		)
	)
	(zone
		(layers "In1.Cu" "In2.Cu")
		(hatch none 0.5)
		(connect_pads
			(clearance 0)
		)
		(min_thickness 0.25)
		(keepout
			(tracks not_allowed)
			(vias allowed)
			(pads allowed)
			(copperpour not_allowed)
			(footprints allowed)
		)
		(placement
			(enabled no)
			(sheetname "")
		)
		(fill yes
			(thermal_gap 0.5)
			(thermal_bridge_width 0.5)
			(island_removal_mode 0)
		)
		(polygon
			(pts
				(arc
					(start 439.430414 -220.285056)
					(mid 438.770014 -220.285056)
					(end 439.430414 -220.285056)
				)
			)
		)
	)
	(zone
		(layers "In1.Cu" "In2.Cu")
		(hatch none 0.5)
		(connect_pads
			(clearance 0)
		)
		(min_thickness 0.25)
		(keepout
			(tracks not_allowed)
			(vias allowed)
			(pads allowed)
			(copperpour not_allowed)
			(footprints allowed)
		)
		(placement
			(enabled no)
			(sheetname "")
		)
		(fill yes
			(thermal_gap 0.5)
			(thermal_bridge_width 0.5)
			(island_removal_mode 0)
		)
		(polygon
			(pts
				(arc
					(start 454.518268 -234.735116)
					(mid 453.857868 -234.735116)
					(end 454.518268 -234.735116)
				)
			)
		)
	)
	(zone
		(layers "In1.Cu" "In2.Cu")
		(hatch none 0.5)
		(connect_pads
			(clearance 0)
		)
		(min_thickness 0.25)
		(keepout
			(tracks not_allowed)
			(vias allowed)
			(pads allowed)
			(copperpour not_allowed)
			(footprints allowed)
		)
		(placement
			(enabled no)
			(sheetname "")
		)
		(fill yes
			(thermal_gap 0.5)
			(thermal_bridge_width 0.5)
			(island_removal_mode 0)
		)
		(polygon
			(pts
				(arc
					(start 450.4182 -312.084974)
					(mid 449.7578 -312.084974)
					(end 450.4182 -312.084974)
				)
			)
		)
	)
	(zone
		(layers "In1.Cu" "In2.Cu")
		(hatch none 0.5)
		(connect_pads
			(clearance 0)
		)
		(min_thickness 0.25)
		(keepout
			(tracks not_allowed)
			(vias allowed)
			(pads allowed)
			(copperpour not_allowed)
			(footprints allowed)
		)
		(placement
			(enabled no)
			(sheetname "")
		)
		(fill yes
			(thermal_gap 0.5)
			(thermal_bridge_width 0.5)
			(island_removal_mode 0)
		)
		(polygon
			(pts
				(arc
					(start 183.946292 -270.435324)
					(mid 183.285892 -270.435324)
					(end 183.946292 -270.435324)
				)
			)
		)
	)
	(zone
		(layers "In1.Cu" "In2.Cu")
		(hatch none 0.5)
		(connect_pads
			(clearance 0)
		)
		(min_thickness 0.25)
		(keepout
			(tracks not_allowed)
			(vias allowed)
			(pads allowed)
			(copperpour not_allowed)
			(footprints allowed)
		)
		(placement
			(enabled no)
			(sheetname "")
		)
		(fill yes
			(thermal_gap 0.5)
			(thermal_bridge_width 0.5)
			(island_removal_mode 0)
		)
		(polygon
			(pts
				(arc
					(start 17.938242 -232.18521)
					(mid 17.277842 -232.18521)
					(end 17.938242 -232.18521)
				)
			)
		)
	)
	(zone
		(layers "In1.Cu" "In2.Cu")
		(hatch none 0.5)
		(connect_pads
			(clearance 0)
		)
		(min_thickness 0.25)
		(keepout
			(tracks not_allowed)
			(vias allowed)
			(pads allowed)
			(copperpour not_allowed)
			(footprints allowed)
		)
		(placement
			(enabled no)
			(sheetname "")
		)
		(fill yes
			(thermal_gap 0.5)
			(thermal_bridge_width 0.5)
			(island_removal_mode 0)
		)
		(polygon
			(pts
				(arc
					(start 439.430414 -249.185176)
					(mid 438.770014 -249.185176)
					(end 439.430414 -249.185176)
				)
			)
		)
	)
	(zone
		(layers "In1.Cu" "In2.Cu")
		(hatch none 0.5)
		(connect_pads
			(clearance 0)
		)
		(min_thickness 0.25)
		(keepout
			(tracks not_allowed)
			(vias allowed)
			(pads allowed)
			(copperpour not_allowed)
			(footprints allowed)
		)
		(placement
			(enabled no)
			(sheetname "")
		)
		(fill yes
			(thermal_gap 0.5)
			(thermal_bridge_width 0.5)
			(island_removal_mode 0)
		)
		(polygon
			(pts
				(arc
					(start 179.846224 -295.085262)
					(mid 179.185824 -295.085262)
					(end 179.846224 -295.085262)
				)
			)
		)
	)
	(zone
		(layers "In1.Cu" "In2.Cu")
		(hatch none 0.5)
		(connect_pads
			(clearance 0)
		)
		(min_thickness 0.25)
		(keepout
			(tracks not_allowed)
			(vias allowed)
			(pads allowed)
			(copperpour not_allowed)
			(footprints allowed)
		)
		(placement
			(enabled no)
			(sheetname "")
		)
		(fill yes
			(thermal_gap 0.5)
			(thermal_bridge_width 0.5)
			(island_removal_mode 0)
		)
		(polygon
			(pts
				(arc
					(start 48.114204 -213.485222)
					(mid 47.453804 -213.485222)
					(end 48.114204 -213.485222)
				)
			)
		)
	)
	(zone
		(layers "In1.Cu" "In2.Cu")
		(hatch none 0.5)
		(connect_pads
			(clearance 0)
		)
		(min_thickness 0.25)
		(keepout
			(tracks not_allowed)
			(vias allowed)
			(pads allowed)
			(copperpour not_allowed)
			(footprints allowed)
		)
		(placement
			(enabled no)
			(sheetname "")
		)
		(fill yes
			(thermal_gap 0.5)
			(thermal_bridge_width 0.5)
			(island_removal_mode 0)
		)
		(polygon
			(pts
				(arc
					(start 25.482296 -310.385206)
					(mid 24.821896 -310.385206)
					(end 25.482296 -310.385206)
				)
			)
		)
	)
	(zone
		(layers "In1.Cu" "In2.Cu")
		(hatch none 0.5)
		(connect_pads
			(clearance 0)
		)
		(min_thickness 0.25)
		(keepout
			(tracks not_allowed)
			(vias allowed)
			(pads allowed)
			(copperpour not_allowed)
			(footprints allowed)
		)
		(placement
			(enabled no)
			(sheetname "")
		)
		(fill yes
			(thermal_gap 0.5)
			(thermal_bridge_width 0.5)
			(island_removal_mode 0)
		)
		(polygon
			(pts
				(arc
					(start 40.57015 -268.735302)
					(mid 39.90975 -268.735302)
					(end 40.57015 -268.735302)
				)
			)
		)
	)
	(zone
		(layers "In1.Cu" "In2.Cu")
		(hatch none 0.5)
		(connect_pads
			(clearance 0)
		)
		(min_thickness 0.25)
		(keepout
			(tracks not_allowed)
			(vias allowed)
			(pads allowed)
			(copperpour not_allowed)
			(footprints allowed)
		)
		(placement
			(enabled no)
			(sheetname "")
		)
		(fill yes
			(thermal_gap 0.5)
			(thermal_bridge_width 0.5)
			(island_removal_mode 0)
		)
		(polygon
			(pts
				(arc
					(start 33.026096 -301.035212)
					(mid 32.365696 -301.035212)
					(end 33.026096 -301.035212)
				)
			)
		)
	)
	(zone
		(layers "In1.Cu" "In2.Cu")
		(hatch none 0.5)
		(connect_pads
			(clearance 0)
		)
		(min_thickness 0.25)
		(keepout
			(tracks not_allowed)
			(vias allowed)
			(pads allowed)
			(copperpour not_allowed)
			(footprints allowed)
		)
		(placement
			(enabled no)
			(sheetname "")
		)
		(fill yes
			(thermal_gap 0.5)
			(thermal_bridge_width 0.5)
			(island_removal_mode 0)
		)
		(polygon
			(pts
				(arc
					(start 177.832258 -53.058822)
					(mid 177.88614 -53.08114)
					(end 177.908458 -53.135022)
				)
				(arc
					(start 177.908458 -53.965094)
					(mid 177.88614 -54.018976)
					(end 177.832258 -54.041294)
				)
				(arc
					(start 176.384458 -54.041294)
					(mid 176.330576 -54.018976)
					(end 176.308258 -53.965094)
				)
				(arc
					(start 176.308258 -53.135022)
					(mid 176.330576 -53.08114)
					(end 176.384458 -53.058822)
				)
			)
		)
	)
	(zone
		(layers "In1.Cu" "In2.Cu")
		(hatch none 0.5)
		(connect_pads
			(clearance 0)
		)
		(min_thickness 0.25)
		(keepout
			(tracks not_allowed)
			(vias allowed)
			(pads allowed)
			(copperpour not_allowed)
			(footprints allowed)
		)
		(placement
			(enabled no)
			(sheetname "")
		)
		(fill yes
			(thermal_gap 0.5)
			(thermal_bridge_width 0.5)
			(island_removal_mode 0)
		)
		(polygon
			(pts
				(arc
					(start 424.342306 -309.535068)
					(mid 423.681906 -309.535068)
					(end 424.342306 -309.535068)
				)
			)
		)
	)
	(zone
		(layers "In1.Cu" "In2.Cu")
		(hatch none 0.5)
		(connect_pads
			(clearance 0)
		)
		(min_thickness 0.25)
		(keepout
			(tracks not_allowed)
			(vias allowed)
			(pads allowed)
			(copperpour not_allowed)
			(footprints allowed)
		)
		(placement
			(enabled no)
			(sheetname "")
		)
		(fill yes
			(thermal_gap 0.5)
			(thermal_bridge_width 0.5)
			(island_removal_mode 0)
		)
		(polygon
			(pts
				(arc
					(start 292.610286 -204.985112)
					(mid 291.949886 -204.985112)
					(end 292.610286 -204.985112)
				)
			)
		)
	)
	(zone
		(layers "In1.Cu" "In2.Cu")
		(hatch none 0.5)
		(connect_pads
			(clearance 0)
		)
		(min_thickness 0.25)
		(keepout
			(tracks not_allowed)
			(vias allowed)
			(pads allowed)
			(copperpour not_allowed)
			(footprints allowed)
		)
		(placement
			(enabled no)
			(sheetname "")
		)
		(fill yes
			(thermal_gap 0.5)
			(thermal_bridge_width 0.5)
			(island_removal_mode 0)
		)
		(polygon
			(pts
				(arc
					(start 52.214272 -244.085364)
					(mid 51.553872 -244.085364)
					(end 52.214272 -244.085364)
				)
			)
		)
	)
	(zone
		(layers "In1.Cu" "In2.Cu")
		(hatch none 0.5)
		(connect_pads
			(clearance 0)
		)
		(min_thickness 0.25)
		(keepout
			(tracks not_allowed)
			(vias allowed)
			(pads allowed)
			(copperpour not_allowed)
			(footprints allowed)
		)
		(placement
			(enabled no)
			(sheetname "")
		)
		(fill yes
			(thermal_gap 0.5)
			(thermal_bridge_width 0.5)
			(island_removal_mode 0)
		)
		(polygon
			(pts
				(arc
					(start 442.8744 -313.784996)
					(mid 442.214 -313.784996)
					(end 442.8744 -313.784996)
				)
			)
		)
	)
	(zone
		(layers "In1.Cu" "In2.Cu")
		(hatch none 0.5)
		(connect_pads
			(clearance 0)
		)
		(min_thickness 0.25)
		(keepout
			(tracks not_allowed)
			(vias allowed)
			(pads allowed)
			(copperpour not_allowed)
			(footprints allowed)
		)
		(placement
			(enabled no)
			(sheetname "")
		)
		(fill yes
			(thermal_gap 0.5)
			(thermal_bridge_width 0.5)
			(island_removal_mode 0)
		)
		(polygon
			(pts
				(arc
					(start 435.330346 -222.834962)
					(mid 434.669946 -222.834962)
					(end 435.330346 -222.834962)
				)
			)
		)
	)
	(zone
		(layers "In1.Cu" "In2.Cu")
		(hatch none 0.5)
		(connect_pads
			(clearance 0)
		)
		(min_thickness 0.25)
		(keepout
			(tracks not_allowed)
			(vias allowed)
			(pads allowed)
			(copperpour not_allowed)
			(footprints allowed)
		)
		(placement
			(enabled no)
			(sheetname "")
		)
		(fill yes
			(thermal_gap 0.5)
			(thermal_bridge_width 0.5)
			(island_removal_mode 0)
		)
		(polygon
			(pts
				(arc
					(start 431.88636 -236.435138)
					(mid 431.22596 -236.435138)
					(end 431.88636 -236.435138)
				)
			)
		)
	)
	(zone
		(layers "In1.Cu" "In2.Cu")
		(hatch none 0.5)
		(connect_pads
			(clearance 0)
		)
		(min_thickness 0.25)
		(keepout
			(tracks not_allowed)
			(vias allowed)
			(pads allowed)
			(copperpour not_allowed)
			(footprints allowed)
		)
		(placement
			(enabled no)
			(sheetname "")
		)
		(fill yes
			(thermal_gap 0.5)
			(thermal_bridge_width 0.5)
			(island_removal_mode 0)
		)
		(polygon
			(pts
				(arc
					(start 431.88636 -231.335072)
					(mid 431.22596 -231.335072)
					(end 431.88636 -231.335072)
				)
			)
		)
	)
	(zone
		(layers "In1.Cu" "In2.Cu")
		(hatch none 0.5)
		(connect_pads
			(clearance 0)
		)
		(min_thickness 0.25)
		(keepout
			(tracks not_allowed)
			(vias allowed)
			(pads allowed)
			(copperpour not_allowed)
			(footprints allowed)
		)
		(placement
			(enabled no)
			(sheetname "")
		)
		(fill yes
			(thermal_gap 0.5)
			(thermal_bridge_width 0.5)
			(island_removal_mode 0)
		)
		(polygon
			(pts
				(arc
					(start 194.934332 -286.585406)
					(mid 194.273932 -286.585406)
					(end 194.934332 -286.585406)
				)
			)
		)
	)
	(zone
		(layers "In1.Cu" "In2.Cu")
		(hatch none 0.5)
		(connect_pads
			(clearance 0)
		)
		(min_thickness 0.25)
		(keepout
			(tracks not_allowed)
			(vias allowed)
			(pads allowed)
			(copperpour not_allowed)
			(footprints allowed)
		)
		(placement
			(enabled no)
			(sheetname "")
		)
		(fill yes
			(thermal_gap 0.5)
			(thermal_bridge_width 0.5)
			(island_removal_mode 0)
		)
		(polygon
			(pts
				(arc
					(start 296.054272 -239.835182)
					(mid 295.393872 -239.835182)
					(end 296.054272 -239.835182)
				)
			)
		)
	)
	(zone
		(layers "In1.Cu" "In2.Cu")
		(hatch none 0.5)
		(connect_pads
			(clearance 0)
		)
		(min_thickness 0.25)
		(keepout
			(tracks not_allowed)
			(vias allowed)
			(pads allowed)
			(copperpour not_allowed)
			(footprints allowed)
		)
		(placement
			(enabled no)
			(sheetname "")
		)
		(fill yes
			(thermal_gap 0.5)
			(thermal_bridge_width 0.5)
			(island_removal_mode 0)
		)
		(polygon
			(pts
				(arc
					(start 199.0344 -294.235378)
					(mid 198.374 -294.235378)
					(end 199.0344 -294.235378)
				)
			)
		)
	)
	(zone
		(layers "In1.Cu" "In2.Cu")
		(hatch none 0.5)
		(connect_pads
			(clearance 0)
		)
		(min_thickness 0.25)
		(keepout
			(tracks not_allowed)
			(vias allowed)
			(pads allowed)
			(copperpour not_allowed)
			(footprints allowed)
		)
		(placement
			(enabled no)
			(sheetname "")
		)
		(fill yes
			(thermal_gap 0.5)
			(thermal_bridge_width 0.5)
			(island_removal_mode 0)
		)
		(polygon
			(pts
				(arc
					(start 22.03831 -233.035348)
					(mid 21.37791 -233.035348)
					(end 22.03831 -233.035348)
				)
			)
		)
	)
	(zone
		(layers "In1.Cu" "In2.Cu")
		(hatch none 0.5)
		(connect_pads
			(clearance 0)
		)
		(min_thickness 0.25)
		(keepout
			(tracks not_allowed)
			(vias allowed)
			(pads allowed)
			(copperpour not_allowed)
			(footprints allowed)
		)
		(placement
			(enabled no)
			(sheetname "")
		)
		(fill yes
			(thermal_gap 0.5)
			(thermal_bridge_width 0.5)
			(island_removal_mode 0)
		)
		(polygon
			(pts
				(arc
					(start 269.978378 -238.13516)
					(mid 269.317978 -238.13516)
					(end 269.978378 -238.13516)
				)
			)
		)
	)
	(zone
		(layers "In1.Cu" "In2.Cu")
		(hatch none 0.5)
		(connect_pads
			(clearance 0)
		)
		(min_thickness 0.25)
		(keepout
			(tracks not_allowed)
			(vias allowed)
			(pads allowed)
			(copperpour not_allowed)
			(footprints allowed)
		)
		(placement
			(enabled no)
			(sheetname "")
		)
		(fill yes
			(thermal_gap 0.5)
			(thermal_bridge_width 0.5)
			(island_removal_mode 0)
		)
		(polygon
			(pts
				(arc
					(start 273.422364 -318.035178)
					(mid 272.761964 -318.035178)
					(end 273.422364 -318.035178)
				)
			)
		)
	)
	(zone
		(layers "In1.Cu" "In2.Cu")
		(hatch none 0.5)
		(connect_pads
			(clearance 0)
		)
		(min_thickness 0.25)
		(keepout
			(tracks not_allowed)
			(vias allowed)
			(pads allowed)
			(copperpour not_allowed)
			(footprints allowed)
		)
		(placement
			(enabled no)
			(sheetname "")
		)
		(fill yes
			(thermal_gap 0.5)
			(thermal_bridge_width 0.5)
			(island_removal_mode 0)
		)
		(polygon
			(pts
				(arc
					(start 62.503304 -375.906284)
					(mid 62.523228 -375.91552)
					(end 62.54496 -375.91873)
				)
				(arc
					(start 62.739524 -375.91873)
					(mid 62.793406 -375.896412)
					(end 62.815724 -375.84253)
				)
				(arc
					(start 62.815724 -375.15673)
					(mid 62.793406 -375.102848)
					(end 62.739524 -375.08053)
				)
				(arc
					(start 62.54496 -375.08053)
					(mid 62.523216 -375.083698)
					(end 62.503304 -375.092976)
				)
				(arc
					(start 62.20714 -375.285762)
					(mid 62.165456 -375.297984)
					(end 62.123828 -375.285508)
				)
				(arc
					(start 61.830204 -375.092976)
					(mid 61.81028 -375.08374)
					(end 61.788548 -375.08053)
				)
				(arc
					(start 61.593984 -375.08053)
					(mid 61.540102 -375.102848)
					(end 61.517784 -375.15673)
				)
				(arc
					(start 61.517784 -375.84253)
					(mid 61.540102 -375.896412)
					(end 61.593984 -375.91873)
				)
				(arc
					(start 61.789818 -375.91873)
					(mid 61.811562 -375.915562)
					(end 61.831474 -375.906284)
				)
				(arc
					(start 62.125098 -375.713752)
					(mid 62.166754 -375.70135)
					(end 62.20841 -375.713752)
				)
			)
		)
	)
	(zone
		(layers "In1.Cu" "In2.Cu")
		(hatch none 0.5)
		(connect_pads
			(clearance 0)
		)
		(min_thickness 0.25)
		(keepout
			(tracks not_allowed)
			(vias allowed)
			(pads allowed)
			(copperpour not_allowed)
			(footprints allowed)
		)
		(placement
			(enabled no)
			(sheetname "")
		)
		(fill yes
			(thermal_gap 0.5)
			(thermal_bridge_width 0.5)
			(island_removal_mode 0)
		)
		(polygon
			(pts
				(arc
					(start 187.390278 -291.685218)
					(mid 186.729878 -291.685218)
					(end 187.390278 -291.685218)
				)
			)
		)
	)
	(zone
		(layers "In1.Cu" "In2.Cu")
		(hatch none 0.5)
		(connect_pads
			(clearance 0)
		)
		(min_thickness 0.25)
		(keepout
			(tracks not_allowed)
			(vias allowed)
			(pads allowed)
			(copperpour not_allowed)
			(footprints allowed)
		)
		(placement
			(enabled no)
			(sheetname "")
		)
		(fill yes
			(thermal_gap 0.5)
			(thermal_bridge_width 0.5)
			(island_removal_mode 0)
		)
		(polygon
			(pts
				(arc
					(start 25.482296 -304.435256)
					(mid 24.821896 -304.435256)
					(end 25.482296 -304.435256)
				)
			)
		)
	)
	(zone
		(layers "In1.Cu" "In2.Cu")
		(hatch none 0.5)
		(connect_pads
			(clearance 0)
		)
		(min_thickness 0.25)
		(keepout
			(tracks not_allowed)
			(vias allowed)
			(pads allowed)
			(copperpour not_allowed)
			(footprints allowed)
		)
		(placement
			(enabled no)
			(sheetname "")
		)
		(fill yes
			(thermal_gap 0.5)
			(thermal_bridge_width 0.5)
			(island_removal_mode 0)
		)
		(polygon
			(pts
				(arc
					(start 296.054272 -297.635168)
					(mid 295.393872 -297.635168)
					(end 296.054272 -297.635168)
				)
			)
		)
	)
	(zone
		(layers "In1.Cu" "In2.Cu")
		(hatch none 0.5)
		(connect_pads
			(clearance 0)
		)
		(min_thickness 0.25)
		(keepout
			(tracks not_allowed)
			(vias allowed)
			(pads allowed)
			(copperpour not_allowed)
			(footprints allowed)
		)
		(placement
			(enabled no)
			(sheetname "")
		)
		(fill yes
			(thermal_gap 0.5)
			(thermal_bridge_width 0.5)
			(island_removal_mode 0)
		)
		(polygon
			(pts
				(arc
					(start 435.330346 -310.384952)
					(mid 434.669946 -310.384952)
					(end 435.330346 -310.384952)
				)
			)
		)
	)
	(zone
		(layers "In1.Cu" "In2.Cu")
		(hatch none 0.5)
		(connect_pads
			(clearance 0)
		)
		(min_thickness 0.25)
		(keepout
			(tracks not_allowed)
			(vias allowed)
			(pads allowed)
			(copperpour not_allowed)
			(footprints allowed)
		)
		(placement
			(enabled no)
			(sheetname "")
		)
		(fill yes
			(thermal_gap 0.5)
			(thermal_bridge_width 0.5)
			(island_removal_mode 0)
		)
		(polygon
			(pts
				(arc
					(start 450.4182 -268.735048)
					(mid 449.7578 -268.735048)
					(end 450.4182 -268.735048)
				)
			)
		)
	)
	(zone
		(layers "In1.Cu" "In2.Cu")
		(hatch none 0.5)
		(connect_pads
			(clearance 0)
		)
		(min_thickness 0.25)
		(keepout
			(tracks not_allowed)
			(vias allowed)
			(pads allowed)
			(copperpour not_allowed)
			(footprints allowed)
		)
		(placement
			(enabled no)
			(sheetname "")
		)
		(fill yes
			(thermal_gap 0.5)
			(thermal_bridge_width 0.5)
			(island_removal_mode 0)
		)
		(polygon
			(pts
				(arc
					(start 172.30217 -313.78525)
					(mid 171.64177 -313.78525)
					(end 172.30217 -313.78525)
				)
			)
		)
	)
	(zone
		(layers "In1.Cu" "In2.Cu")
		(hatch none 0.5)
		(connect_pads
			(clearance 0)
		)
		(min_thickness 0.25)
		(keepout
			(tracks not_allowed)
			(vias allowed)
			(pads allowed)
			(copperpour not_allowed)
			(footprints allowed)
		)
		(placement
			(enabled no)
			(sheetname "")
		)
		(fill yes
			(thermal_gap 0.5)
			(thermal_bridge_width 0.5)
			(island_removal_mode 0)
		)
		(polygon
			(pts
				(arc
					(start 29.582364 -292.535356)
					(mid 28.921964 -292.535356)
					(end 29.582364 -292.535356)
				)
			)
		)
	)
	(zone
		(layers "In1.Cu" "In2.Cu")
		(hatch none 0.5)
		(connect_pads
			(clearance 0)
		)
		(min_thickness 0.25)
		(keepout
			(tracks not_allowed)
			(vias allowed)
			(pads allowed)
			(copperpour not_allowed)
			(footprints allowed)
		)
		(placement
			(enabled no)
			(sheetname "")
		)
		(fill yes
			(thermal_gap 0.5)
			(thermal_bridge_width 0.5)
			(island_removal_mode 0)
		)
		(polygon
			(pts
				(arc
					(start 50.590704 -373.442484)
					(mid 50.610628 -373.45172)
					(end 50.63236 -373.45493)
				)
				(arc
					(start 50.826924 -373.45493)
					(mid 50.880806 -373.432612)
					(end 50.903124 -373.37873)
				)
				(arc
					(start 50.903124 -372.69293)
					(mid 50.880806 -372.639048)
					(end 50.826924 -372.61673)
				)
				(arc
					(start 50.63236 -372.61673)
					(mid 50.610616 -372.619898)
					(end 50.590704 -372.629176)
				)
				(arc
					(start 50.29454 -372.821962)
					(mid 50.252856 -372.834184)
					(end 50.211228 -372.821708)
				)
				(arc
					(start 49.917604 -372.629176)
					(mid 49.89768 -372.61994)
					(end 49.875948 -372.61673)
				)
				(arc
					(start 49.681384 -372.61673)
					(mid 49.627502 -372.639048)
					(end 49.605184 -372.69293)
				)
				(arc
					(start 49.605184 -373.37873)
					(mid 49.627502 -373.432612)
					(end 49.681384 -373.45493)
				)
				(arc
					(start 49.877218 -373.45493)
					(mid 49.898962 -373.451762)
					(end 49.918874 -373.442484)
				)
				(arc
					(start 50.212498 -373.249952)
					(mid 50.254154 -373.23755)
					(end 50.29581 -373.249952)
				)
			)
		)
	)
	(zone
		(layers "In1.Cu" "In2.Cu")
		(hatch none 0.5)
		(connect_pads
			(clearance 0)
		)
		(min_thickness 0.25)
		(keepout
			(tracks not_allowed)
			(vias allowed)
			(pads allowed)
			(copperpour not_allowed)
			(footprints allowed)
		)
		(placement
			(enabled no)
			(sheetname "")
		)
		(fill yes
			(thermal_gap 0.5)
			(thermal_bridge_width 0.5)
			(island_removal_mode 0)
		)
		(polygon
			(pts
				(arc
					(start 277.522432 -267.885164)
					(mid 276.862032 -267.885164)
					(end 277.522432 -267.885164)
				)
			)
		)
	)
	(zone
		(layers "In1.Cu" "In2.Cu")
		(hatch none 0.5)
		(connect_pads
			(clearance 0)
		)
		(min_thickness 0.25)
		(keepout
			(tracks not_allowed)
			(vias allowed)
			(pads allowed)
			(copperpour not_allowed)
			(footprints allowed)
		)
		(placement
			(enabled no)
			(sheetname "")
		)
		(fill yes
			(thermal_gap 0.5)
			(thermal_bridge_width 0.5)
			(island_removal_mode 0)
		)
		(polygon
			(pts
				(arc
					(start 288.510218 -291.684964)
					(mid 287.849818 -291.684964)
					(end 288.510218 -291.684964)
				)
			)
		)
	)
	(zone
		(layers "In1.Cu" "In2.Cu")
		(hatch none 0.5)
		(connect_pads
			(clearance 0)
		)
		(min_thickness 0.25)
		(keepout
			(tracks not_allowed)
			(vias allowed)
			(pads allowed)
			(copperpour not_allowed)
			(footprints allowed)
		)
		(placement
			(enabled no)
			(sheetname "")
		)
		(fill yes
			(thermal_gap 0.5)
			(thermal_bridge_width 0.5)
			(island_removal_mode 0)
		)
		(polygon
			(pts
				(arc
					(start 183.946292 -250.885198)
					(mid 183.285892 -250.885198)
					(end 183.946292 -250.885198)
				)
			)
		)
	)
	(zone
		(layers "In1.Cu" "In2.Cu")
		(hatch none 0.5)
		(connect_pads
			(clearance 0)
		)
		(min_thickness 0.25)
		(keepout
			(tracks not_allowed)
			(vias allowed)
			(pads allowed)
			(copperpour not_allowed)
			(footprints allowed)
		)
		(placement
			(enabled no)
			(sheetname "")
		)
		(fill yes
			(thermal_gap 0.5)
			(thermal_bridge_width 0.5)
			(island_removal_mode 0)
		)
		(polygon
			(pts
				(arc
					(start 199.0344 -220.28531)
					(mid 198.374 -220.28531)
					(end 199.0344 -220.28531)
				)
			)
		)
	)
	(zone
		(layers "In1.Cu" "In2.Cu")
		(hatch none 0.5)
		(connect_pads
			(clearance 0)
		)
		(min_thickness 0.25)
		(keepout
			(tracks not_allowed)
			(vias allowed)
			(pads allowed)
			(copperpour not_allowed)
			(footprints allowed)
		)
		(placement
			(enabled no)
			(sheetname "")
		)
		(fill yes
			(thermal_gap 0.5)
			(thermal_bridge_width 0.5)
			(island_removal_mode 0)
		)
		(polygon
			(pts
				(arc
					(start 163.832794 -373.442484)
					(mid 163.852718 -373.45172)
					(end 163.87445 -373.45493)
				)
				(arc
					(start 164.069014 -373.45493)
					(mid 164.122896 -373.432612)
					(end 164.145214 -373.37873)
				)
				(arc
					(start 164.145214 -372.69293)
					(mid 164.122896 -372.639048)
					(end 164.069014 -372.61673)
				)
				(arc
					(start 163.87445 -372.61673)
					(mid 163.852706 -372.619898)
					(end 163.832794 -372.629176)
				)
				(arc
					(start 163.53663 -372.821962)
					(mid 163.494946 -372.834184)
					(end 163.453318 -372.821708)
				)
				(arc
					(start 163.159694 -372.629176)
					(mid 163.13977 -372.61994)
					(end 163.118038 -372.61673)
				)
				(arc
					(start 162.923474 -372.61673)
					(mid 162.869592 -372.639048)
					(end 162.847274 -372.69293)
				)
				(arc
					(start 162.847274 -373.37873)
					(mid 162.869592 -373.432612)
					(end 162.923474 -373.45493)
				)
				(arc
					(start 163.119308 -373.45493)
					(mid 163.141052 -373.451762)
					(end 163.160964 -373.442484)
				)
				(arc
					(start 163.454588 -373.249952)
					(mid 163.496244 -373.23755)
					(end 163.5379 -373.249952)
				)
			)
		)
	)
	(zone
		(layers "In1.Cu" "In2.Cu")
		(hatch none 0.5)
		(connect_pads
			(clearance 0)
		)
		(min_thickness 0.25)
		(keepout
			(tracks not_allowed)
			(vias allowed)
			(pads allowed)
			(copperpour not_allowed)
			(footprints allowed)
		)
		(placement
			(enabled no)
			(sheetname "")
		)
		(fill yes
			(thermal_gap 0.5)
			(thermal_bridge_width 0.5)
			(island_removal_mode 0)
		)
		(polygon
			(pts
				(arc
					(start 371.988842 -384.288284)
					(mid 372.008766 -384.29752)
					(end 372.030498 -384.30073)
				)
				(arc
					(start 372.225062 -384.30073)
					(mid 372.278944 -384.278412)
					(end 372.301262 -384.22453)
				)
				(arc
					(start 372.301262 -383.53873)
					(mid 372.278944 -383.484848)
					(end 372.225062 -383.46253)
				)
				(arc
					(start 372.030498 -383.46253)
					(mid 372.008754 -383.465698)
					(end 371.988842 -383.474976)
				)
				(arc
					(start 371.692678 -383.667762)
					(mid 371.650994 -383.679984)
					(end 371.609366 -383.667508)
				)
				(arc
					(start 371.315742 -383.474976)
					(mid 371.295818 -383.46574)
					(end 371.274086 -383.46253)
				)
				(arc
					(start 371.079522 -383.46253)
					(mid 371.02564 -383.484848)
					(end 371.003322 -383.53873)
				)
				(arc
					(start 371.003322 -384.22453)
					(mid 371.02564 -384.278412)
					(end 371.079522 -384.30073)
				)
				(arc
					(start 371.275356 -384.30073)
					(mid 371.2971 -384.297562)
					(end 371.317012 -384.288284)
				)
				(arc
					(start 371.610636 -384.095752)
					(mid 371.652292 -384.08335)
					(end 371.693948 -384.095752)
				)
			)
		)
	)
	(zone
		(layers "In1.Cu" "In2.Cu")
		(hatch none 0.5)
		(connect_pads
			(clearance 0)
		)
		(min_thickness 0.25)
		(keepout
			(tracks not_allowed)
			(vias allowed)
			(pads allowed)
			(copperpour not_allowed)
			(footprints allowed)
		)
		(placement
			(enabled no)
			(sheetname "")
		)
		(fill yes
			(thermal_gap 0.5)
			(thermal_bridge_width 0.5)
			(island_removal_mode 0)
		)
		(polygon
			(pts
				(arc
					(start 269.978378 -292.535102)
					(mid 269.317978 -292.535102)
					(end 269.978378 -292.535102)
				)
			)
		)
	)
	(zone
		(layers "In1.Cu" "In2.Cu")
		(hatch none 0.5)
		(connect_pads
			(clearance 0)
		)
		(min_thickness 0.25)
		(keepout
			(tracks not_allowed)
			(vias allowed)
			(pads allowed)
			(copperpour not_allowed)
			(footprints allowed)
		)
		(placement
			(enabled no)
			(sheetname "")
		)
		(fill yes
			(thermal_gap 0.5)
			(thermal_bridge_width 0.5)
			(island_removal_mode 0)
		)
		(polygon
			(pts
				(arc
					(start 187.390278 -312.085228)
					(mid 186.729878 -312.085228)
					(end 187.390278 -312.085228)
				)
			)
		)
	)
	(zone
		(layers "In1.Cu" "In2.Cu")
		(hatch none 0.5)
		(connect_pads
			(clearance 0)
		)
		(min_thickness 0.25)
		(keepout
			(tracks not_allowed)
			(vias allowed)
			(pads allowed)
			(copperpour not_allowed)
			(footprints allowed)
		)
		(placement
			(enabled no)
			(sheetname "")
		)
		(fill yes
			(thermal_gap 0.5)
			(thermal_bridge_width 0.5)
			(island_removal_mode 0)
		)
		(polygon
			(pts
				(arc
					(start 183.946292 -292.535356)
					(mid 183.285892 -292.535356)
					(end 183.946292 -292.535356)
				)
			)
		)
	)
	(zone
		(layers "In1.Cu" "In2.Cu")
		(hatch none 0.5)
		(connect_pads
			(clearance 0)
		)
		(min_thickness 0.25)
		(keepout
			(tracks not_allowed)
			(vias allowed)
			(pads allowed)
			(copperpour not_allowed)
			(footprints allowed)
		)
		(placement
			(enabled no)
			(sheetname "")
		)
		(fill yes
			(thermal_gap 0.5)
			(thermal_bridge_width 0.5)
			(island_removal_mode 0)
		)
		(polygon
			(pts
				(arc
					(start 172.30217 -205.83525)
					(mid 171.64177 -205.83525)
					(end 172.30217 -205.83525)
				)
			)
		)
	)
	(zone
		(layers "In1.Cu" "In2.Cu")
		(hatch none 0.5)
		(connect_pads
			(clearance 0)
		)
		(min_thickness 0.25)
		(keepout
			(tracks not_allowed)
			(vias allowed)
			(pads allowed)
			(copperpour not_allowed)
			(footprints allowed)
		)
		(placement
			(enabled no)
			(sheetname "")
		)
		(fill yes
			(thermal_gap 0.5)
			(thermal_bridge_width 0.5)
			(island_removal_mode 0)
		)
		(polygon
			(pts
				(arc
					(start 31.452312 -7.672324)
					(mid 31.47463 -7.618442)
					(end 31.528512 -7.596124)
				)
				(arc
					(start 32.565086 -7.596124)
					(mid 32.618968 -7.618442)
					(end 32.641286 -7.672324)
				)
				(arc
					(start 32.641286 -9.071864)
					(mid 32.618968 -9.125746)
					(end 32.565086 -9.148064)
				)
				(arc
					(start 31.528512 -9.148064)
					(mid 31.47463 -9.125746)
					(end 31.452312 -9.071864)
				)
			)
		)
	)
	(zone
		(layers "In1.Cu" "In2.Cu")
		(hatch none 0.5)
		(connect_pads
			(clearance 0)
		)
		(min_thickness 0.25)
		(keepout
			(tracks not_allowed)
			(vias allowed)
			(pads allowed)
			(copperpour not_allowed)
			(footprints allowed)
		)
		(placement
			(enabled no)
			(sheetname "")
		)
		(fill yes
			(thermal_gap 0.5)
			(thermal_bridge_width 0.5)
			(island_removal_mode 0)
		)
		(polygon
			(pts
				(arc
					(start 172.30217 -233.885232)
					(mid 171.64177 -233.885232)
					(end 172.30217 -233.885232)
				)
			)
		)
	)
	(zone
		(layers "In1.Cu" "In2.Cu")
		(hatch none 0.5)
		(connect_pads
			(clearance 0)
		)
		(min_thickness 0.25)
		(keepout
			(tracks not_allowed)
			(vias allowed)
			(pads allowed)
			(copperpour not_allowed)
			(footprints allowed)
		)
		(placement
			(enabled no)
			(sheetname "")
		)
		(fill yes
			(thermal_gap 0.5)
			(thermal_bridge_width 0.5)
			(island_removal_mode 0)
		)
		(polygon
			(pts
				(arc
					(start 22.03831 -273.835368)
					(mid 21.37791 -273.835368)
					(end 22.03831 -273.835368)
				)
			)
		)
	)
	(zone
		(layers "In1.Cu" "In2.Cu")
		(hatch none 0.5)
		(connect_pads
			(clearance 0)
		)
		(min_thickness 0.25)
		(keepout
			(tracks not_allowed)
			(vias allowed)
			(pads allowed)
			(copperpour not_allowed)
			(footprints allowed)
		)
		(placement
			(enabled no)
			(sheetname "")
		)
		(fill yes
			(thermal_gap 0.5)
			(thermal_bridge_width 0.5)
			(island_removal_mode 0)
		)
		(polygon
			(pts
				(arc
					(start 450.4182 -235.585)
					(mid 449.7578 -235.585)
					(end 450.4182 -235.585)
				)
			)
		)
	)
	(zone
		(layers "In1.Cu" "In2.Cu")
		(hatch none 0.5)
		(connect_pads
			(clearance 0)
		)
		(min_thickness 0.25)
		(keepout
			(tracks not_allowed)
			(vias allowed)
			(pads allowed)
			(copperpour not_allowed)
			(footprints allowed)
		)
		(placement
			(enabled no)
			(sheetname "")
		)
		(fill yes
			(thermal_gap 0.5)
			(thermal_bridge_width 0.5)
			(island_removal_mode 0)
		)
		(polygon
			(pts
				(arc
					(start 435.330346 -297.635168)
					(mid 434.669946 -297.635168)
					(end 435.330346 -297.635168)
				)
			)
		)
	)
	(zone
		(layers "In1.Cu" "In2.Cu")
		(hatch none 0.5)
		(connect_pads
			(clearance 0)
		)
		(min_thickness 0.25)
		(keepout
			(tracks not_allowed)
			(vias allowed)
			(pads allowed)
			(copperpour not_allowed)
			(footprints allowed)
		)
		(placement
			(enabled no)
			(sheetname "")
		)
		(fill yes
			(thermal_gap 0.5)
			(thermal_bridge_width 0.5)
			(island_removal_mode 0)
		)
		(polygon
			(pts
				(arc
					(start 37.126164 -303.585372)
					(mid 36.465764 -303.585372)
					(end 37.126164 -303.585372)
				)
			)
		)
	)
	(zone
		(layers "In1.Cu" "In2.Cu")
		(hatch none 0.5)
		(connect_pads
			(clearance 0)
		)
		(min_thickness 0.25)
		(keepout
			(tracks not_allowed)
			(vias allowed)
			(pads allowed)
			(copperpour not_allowed)
			(footprints allowed)
		)
		(placement
			(enabled no)
			(sheetname "")
		)
		(fill yes
			(thermal_gap 0.5)
			(thermal_bridge_width 0.5)
			(island_removal_mode 0)
		)
		(polygon
			(pts
				(arc
					(start 183.946292 -281.48534)
					(mid 183.285892 -281.48534)
					(end 183.946292 -281.48534)
				)
			)
		)
	)
	(zone
		(layers "In1.Cu" "In2.Cu")
		(hatch none 0.5)
		(connect_pads
			(clearance 0)
		)
		(min_thickness 0.25)
		(keepout
			(tracks not_allowed)
			(vias allowed)
			(pads allowed)
			(copperpour not_allowed)
			(footprints allowed)
		)
		(placement
			(enabled no)
			(sheetname "")
		)
		(fill yes
			(thermal_gap 0.5)
			(thermal_bridge_width 0.5)
			(island_removal_mode 0)
		)
		(polygon
			(pts
				(arc
					(start 202.478132 -229.635304)
					(mid 201.817732 -229.635304)
					(end 202.478132 -229.635304)
				)
			)
		)
	)
	(zone
		(layers "In1.Cu" "In2.Cu")
		(hatch none 0.5)
		(connect_pads
			(clearance 0)
		)
		(min_thickness 0.25)
		(keepout
			(tracks not_allowed)
			(vias allowed)
			(pads allowed)
			(copperpour not_allowed)
			(footprints allowed)
		)
		(placement
			(enabled no)
			(sheetname "")
		)
		(fill yes
			(thermal_gap 0.5)
			(thermal_bridge_width 0.5)
			(island_removal_mode 0)
		)
		(polygon
			(pts
				(arc
					(start 340.335616 -417.242244)
					(mid 340.357934 -417.296126)
					(end 340.411816 -417.318444)
				)
				(arc
					(start 340.607396 -417.318444)
					(mid 340.629272 -417.315312)
					(end 340.649306 -417.305998)
				)
				(arc
					(start 340.94293 -417.113466)
					(mid 340.984586 -417.101064)
					(end 341.026242 -417.113466)
				)
				(arc
					(start 341.321136 -417.305998)
					(mid 341.34106 -417.315234)
					(end 341.362792 -417.318444)
				)
				(arc
					(start 341.557356 -417.318444)
					(mid 341.611238 -417.296126)
					(end 341.633556 -417.242244)
				)
				(arc
					(start 341.633556 -416.556444)
					(mid 341.611238 -416.502562)
					(end 341.557356 -416.480244)
				)
				(arc
					(start 341.362792 -416.480244)
					(mid 341.341048 -416.483412)
					(end 341.321136 -416.49269)
				)
				(arc
					(start 341.024972 -416.685476)
					(mid 340.983288 -416.697698)
					(end 340.94166 -416.685222)
				)
				(arc
					(start 340.648036 -416.49269)
					(mid 340.628112 -416.483454)
					(end 340.60638 -416.480244)
				)
				(arc
					(start 340.411816 -416.480244)
					(mid 340.357934 -416.502562)
					(end 340.335616 -416.556444)
				)
			)
		)
	)
	(zone
		(layers "In1.Cu" "In2.Cu")
		(hatch none 0.5)
		(connect_pads
			(clearance 0)
		)
		(min_thickness 0.25)
		(keepout
			(tracks not_allowed)
			(vias allowed)
			(pads allowed)
			(copperpour not_allowed)
			(footprints allowed)
		)
		(placement
			(enabled no)
			(sheetname "")
		)
		(fill yes
			(thermal_gap 0.5)
			(thermal_bridge_width 0.5)
			(island_removal_mode 0)
		)
		(polygon
			(pts
				(arc
					(start 424.342306 -276.38502)
					(mid 423.681906 -276.38502)
					(end 424.342306 -276.38502)
				)
			)
		)
	)
	(zone
		(layers "In1.Cu" "In2.Cu")
		(hatch none 0.5)
		(connect_pads
			(clearance 0)
		)
		(min_thickness 0.25)
		(keepout
			(tracks not_allowed)
			(vias allowed)
			(pads allowed)
			(copperpour not_allowed)
			(footprints allowed)
		)
		(placement
			(enabled no)
			(sheetname "")
		)
		(fill yes
			(thermal_gap 0.5)
			(thermal_bridge_width 0.5)
			(island_removal_mode 0)
		)
		(polygon
			(pts
				(arc
					(start 33.026096 -278.935434)
					(mid 32.365696 -278.935434)
					(end 33.026096 -278.935434)
				)
			)
		)
	)
	(zone
		(layers "In1.Cu" "In2.Cu")
		(hatch none 0.5)
		(connect_pads
			(clearance 0)
		)
		(min_thickness 0.25)
		(keepout
			(tracks not_allowed)
			(vias allowed)
			(pads allowed)
			(copperpour not_allowed)
			(footprints allowed)
		)
		(placement
			(enabled no)
			(sheetname "")
		)
		(fill yes
			(thermal_gap 0.5)
			(thermal_bridge_width 0.5)
			(island_removal_mode 0)
		)
		(polygon
			(pts
				(arc
					(start 37.126164 -304.435256)
					(mid 36.465764 -304.435256)
					(end 37.126164 -304.435256)
				)
			)
		)
	)
	(zone
		(layers "In1.Cu" "In2.Cu")
		(hatch none 0.5)
		(connect_pads
			(clearance 0)
		)
		(min_thickness 0.25)
		(keepout
			(tracks not_allowed)
			(vias allowed)
			(pads allowed)
			(copperpour not_allowed)
			(footprints allowed)
		)
		(placement
			(enabled no)
			(sheetname "")
		)
		(fill yes
			(thermal_gap 0.5)
			(thermal_bridge_width 0.5)
			(island_removal_mode 0)
		)
		(polygon
			(pts
				(arc
					(start 179.846224 -299.335444)
					(mid 179.185824 -299.335444)
					(end 179.846224 -299.335444)
				)
			)
		)
	)
	(zone
		(layers "In1.Cu" "In2.Cu")
		(hatch none 0.5)
		(connect_pads
			(clearance 0)
		)
		(min_thickness 0.25)
		(keepout
			(tracks not_allowed)
			(vias allowed)
			(pads allowed)
			(copperpour not_allowed)
			(footprints allowed)
		)
		(placement
			(enabled no)
			(sheetname "")
		)
		(fill yes
			(thermal_gap 0.5)
			(thermal_bridge_width 0.5)
			(island_removal_mode 0)
		)
		(polygon
			(pts
				(arc
					(start 44.670218 -273.835368)
					(mid 44.009818 -273.835368)
					(end 44.670218 -273.835368)
				)
			)
		)
	)
	(zone
		(layers "In1.Cu" "In2.Cu")
		(hatch none 0.5)
		(connect_pads
			(clearance 0)
		)
		(min_thickness 0.25)
		(keepout
			(tracks not_allowed)
			(vias allowed)
			(pads allowed)
			(copperpour not_allowed)
			(footprints allowed)
		)
		(placement
			(enabled no)
			(sheetname "")
		)
		(fill yes
			(thermal_gap 0.5)
			(thermal_bridge_width 0.5)
			(island_removal_mode 0)
		)
		(polygon
			(pts
				(arc
					(start 296.054272 -224.534984)
					(mid 295.393872 -224.534984)
					(end 296.054272 -224.534984)
				)
			)
		)
	)
	(zone
		(layers "In1.Cu" "In2.Cu")
		(hatch none 0.5)
		(connect_pads
			(clearance 0)
		)
		(min_thickness 0.25)
		(keepout
			(tracks not_allowed)
			(vias allowed)
			(pads allowed)
			(copperpour not_allowed)
			(footprints allowed)
		)
		(placement
			(enabled no)
			(sheetname "")
		)
		(fill yes
			(thermal_gap 0.5)
			(thermal_bridge_width 0.5)
			(island_removal_mode 0)
		)
		(polygon
			(pts
				(arc
					(start 288.510218 -204.134974)
					(mid 287.849818 -204.134974)
					(end 288.510218 -204.134974)
				)
			)
		)
	)
	(zone
		(layers "In1.Cu" "In2.Cu")
		(hatch none 0.5)
		(connect_pads
			(clearance 0)
		)
		(min_thickness 0.25)
		(keepout
			(tracks not_allowed)
			(vias allowed)
			(pads allowed)
			(copperpour not_allowed)
			(footprints allowed)
		)
		(placement
			(enabled no)
			(sheetname "")
		)
		(fill yes
			(thermal_gap 0.5)
			(thermal_bridge_width 0.5)
			(island_removal_mode 0)
		)
		(polygon
			(pts
				(arc
					(start 71.167498 -7.672324)
					(mid 71.189816 -7.618442)
					(end 71.243698 -7.596124)
				)
				(arc
					(start 72.280272 -7.596124)
					(mid 72.334154 -7.618442)
					(end 72.356472 -7.672324)
				)
				(arc
					(start 72.356472 -9.071864)
					(mid 72.334154 -9.125746)
					(end 72.280272 -9.148064)
				)
				(arc
					(start 71.243698 -9.148064)
					(mid 71.189816 -9.125746)
					(end 71.167498 -9.071864)
				)
			)
		)
	)
	(zone
		(layers "In1.Cu" "In2.Cu")
		(hatch none 0.5)
		(connect_pads
			(clearance 0)
		)
		(min_thickness 0.25)
		(keepout
			(tracks not_allowed)
			(vias allowed)
			(pads allowed)
			(copperpour not_allowed)
			(footprints allowed)
		)
		(placement
			(enabled no)
			(sheetname "")
		)
		(fill yes
			(thermal_gap 0.5)
			(thermal_bridge_width 0.5)
			(island_removal_mode 0)
		)
		(polygon
			(pts
				(arc
					(start 33.026096 -314.635388)
					(mid 32.365696 -314.635388)
					(end 33.026096 -314.635388)
				)
			)
		)
	)
	(zone
		(layers "In1.Cu" "In2.Cu")
		(hatch none 0.5)
		(connect_pads
			(clearance 0)
		)
		(min_thickness 0.25)
		(keepout
			(tracks not_allowed)
			(vias allowed)
			(pads allowed)
			(copperpour not_allowed)
			(footprints allowed)
		)
		(placement
			(enabled no)
			(sheetname "")
		)
		(fill yes
			(thermal_gap 0.5)
			(thermal_bridge_width 0.5)
			(island_removal_mode 0)
		)
		(polygon
			(pts
				(arc
					(start 172.30217 -312.085228)
					(mid 171.64177 -312.085228)
					(end 172.30217 -312.085228)
				)
			)
		)
	)
	(zone
		(layers "In1.Cu" "In2.Cu")
		(hatch none 0.5)
		(connect_pads
			(clearance 0)
		)
		(min_thickness 0.25)
		(keepout
			(tracks not_allowed)
			(vias allowed)
			(pads allowed)
			(copperpour not_allowed)
			(footprints allowed)
		)
		(placement
			(enabled no)
			(sheetname "")
		)
		(fill yes
			(thermal_gap 0.5)
			(thermal_bridge_width 0.5)
			(island_removal_mode 0)
		)
		(polygon
			(pts
				(arc
					(start 191.490346 -244.08511)
					(mid 190.829946 -244.08511)
					(end 191.490346 -244.08511)
				)
			)
		)
	)
	(zone
		(layers "In1.Cu" "In2.Cu")
		(hatch none 0.5)
		(connect_pads
			(clearance 0)
		)
		(min_thickness 0.25)
		(keepout
			(tracks not_allowed)
			(vias allowed)
			(pads allowed)
			(copperpour not_allowed)
			(footprints allowed)
		)
		(placement
			(enabled no)
			(sheetname "")
		)
		(fill yes
			(thermal_gap 0.5)
			(thermal_bridge_width 0.5)
			(island_removal_mode 0)
		)
		(polygon
			(pts
				(arc
					(start 52.292504 -370.978684)
					(mid 52.312428 -370.98792)
					(end 52.33416 -370.99113)
				)
				(arc
					(start 52.528724 -370.99113)
					(mid 52.582606 -370.968812)
					(end 52.604924 -370.91493)
				)
				(arc
					(start 52.604924 -370.22913)
					(mid 52.582606 -370.175248)
					(end 52.528724 -370.15293)
				)
				(arc
					(start 52.33416 -370.15293)
					(mid 52.312416 -370.156098)
					(end 52.292504 -370.165376)
				)
				(arc
					(start 51.99634 -370.358162)
					(mid 51.954656 -370.370384)
					(end 51.913028 -370.357908)
				)
				(arc
					(start 51.619404 -370.165376)
					(mid 51.59948 -370.15614)
					(end 51.577748 -370.15293)
				)
				(arc
					(start 51.383184 -370.15293)
					(mid 51.329302 -370.175248)
					(end 51.306984 -370.22913)
				)
				(arc
					(start 51.306984 -370.91493)
					(mid 51.329302 -370.968812)
					(end 51.383184 -370.99113)
				)
				(arc
					(start 51.579018 -370.99113)
					(mid 51.600762 -370.987962)
					(end 51.620674 -370.978684)
				)
				(arc
					(start 51.914298 -370.786152)
					(mid 51.955954 -370.77375)
					(end 51.99761 -370.786152)
				)
			)
		)
	)
	(zone
		(layers "In1.Cu" "In2.Cu")
		(hatch none 0.5)
		(connect_pads
			(clearance 0)
		)
		(min_thickness 0.25)
		(keepout
			(tracks not_allowed)
			(vias allowed)
			(pads allowed)
			(copperpour not_allowed)
			(footprints allowed)
		)
		(placement
			(enabled no)
			(sheetname "")
		)
		(fill yes
			(thermal_gap 0.5)
			(thermal_bridge_width 0.5)
			(island_removal_mode 0)
		)
		(polygon
			(pts
				(arc
					(start 435.330346 -229.63505)
					(mid 434.669946 -229.63505)
					(end 435.330346 -229.63505)
				)
			)
		)
	)
	(zone
		(layers "In1.Cu" "In2.Cu")
		(hatch none 0.5)
		(connect_pads
			(clearance 0)
		)
		(min_thickness 0.25)
		(keepout
			(tracks not_allowed)
			(vias allowed)
			(pads allowed)
			(copperpour not_allowed)
			(footprints allowed)
		)
		(placement
			(enabled no)
			(sheetname "")
		)
		(fill yes
			(thermal_gap 0.5)
			(thermal_bridge_width 0.5)
			(island_removal_mode 0)
		)
		(polygon
			(pts
				(arc
					(start 424.342306 -197.33514)
					(mid 423.681906 -197.33514)
					(end 424.342306 -197.33514)
				)
			)
		)
	)
	(zone
		(layers "In1.Cu" "In2.Cu")
		(hatch none 0.5)
		(connect_pads
			(clearance 0)
		)
		(min_thickness 0.25)
		(keepout
			(tracks not_allowed)
			(vias allowed)
			(pads allowed)
			(copperpour not_allowed)
			(footprints allowed)
		)
		(placement
			(enabled no)
			(sheetname "")
		)
		(fill yes
			(thermal_gap 0.5)
			(thermal_bridge_width 0.5)
			(island_removal_mode 0)
		)
		(polygon
			(pts
				(arc
					(start 202.478132 -202.435206)
					(mid 201.817732 -202.435206)
					(end 202.478132 -202.435206)
				)
			)
		)
	)
	(zone
		(layers "In1.Cu" "In2.Cu")
		(hatch none 0.5)
		(connect_pads
			(clearance 0)
		)
		(min_thickness 0.25)
		(keepout
			(tracks not_allowed)
			(vias allowed)
			(pads allowed)
			(copperpour not_allowed)
			(footprints allowed)
		)
		(placement
			(enabled no)
			(sheetname "")
		)
		(fill yes
			(thermal_gap 0.5)
			(thermal_bridge_width 0.5)
			(island_removal_mode 0)
		)
		(polygon
			(pts
				(arc
					(start 288.510218 -244.934994)
					(mid 287.849818 -244.934994)
					(end 288.510218 -244.934994)
				)
			)
		)
	)
	(zone
		(layers "In1.Cu" "In2.Cu")
		(hatch none 0.5)
		(connect_pads
			(clearance 0)
		)
		(min_thickness 0.25)
		(keepout
			(tracks not_allowed)
			(vias allowed)
			(pads allowed)
			(copperpour not_allowed)
			(footprints allowed)
		)
		(placement
			(enabled no)
			(sheetname "")
		)
		(fill yes
			(thermal_gap 0.5)
			(thermal_bridge_width 0.5)
			(island_removal_mode 0)
		)
		(polygon
			(pts
				(arc
					(start 168.96207 -376.861578)
					(mid 168.952834 -376.881502)
					(end 168.949624 -376.903234)
				)
				(arc
					(start 168.949624 -377.097798)
					(mid 168.971942 -377.15168)
					(end 169.025824 -377.173998)
				)
				(arc
					(start 169.711624 -377.173998)
					(mid 169.765506 -377.15168)
					(end 169.787824 -377.097798)
				)
				(arc
					(start 169.787824 -376.903234)
					(mid 169.784656 -376.88149)
					(end 169.775378 -376.861578)
				)
				(arc
					(start 169.582592 -376.565414)
					(mid 169.57037 -376.52373)
					(end 169.582846 -376.482102)
				)
				(arc
					(start 169.775378 -376.188478)
					(mid 169.784614 -376.168554)
					(end 169.787824 -376.146822)
				)
				(arc
					(start 169.787824 -375.952258)
					(mid 169.765506 -375.898376)
					(end 169.711624 -375.876058)
				)
				(arc
					(start 169.025824 -375.876058)
					(mid 168.971942 -375.898376)
					(end 168.949624 -375.952258)
				)
				(arc
					(start 168.949624 -376.148092)
					(mid 168.952792 -376.169836)
					(end 168.96207 -376.189748)
				)
				(arc
					(start 169.154602 -376.483372)
					(mid 169.167004 -376.525028)
					(end 169.154602 -376.566684)
				)
			)
		)
	)
	(zone
		(layers "In1.Cu" "In2.Cu")
		(hatch none 0.5)
		(connect_pads
			(clearance 0)
		)
		(min_thickness 0.25)
		(keepout
			(tracks not_allowed)
			(vias allowed)
			(pads allowed)
			(copperpour not_allowed)
			(footprints allowed)
		)
		(placement
			(enabled no)
			(sheetname "")
		)
		(fill yes
			(thermal_gap 0.5)
			(thermal_bridge_width 0.5)
			(island_removal_mode 0)
		)
		(polygon
			(pts
				(arc
					(start 44.670218 -220.28531)
					(mid 44.009818 -220.28531)
					(end 44.670218 -220.28531)
				)
			)
		)
	)
	(zone
		(layers "In1.Cu" "In2.Cu")
		(hatch none 0.5)
		(connect_pads
			(clearance 0)
		)
		(min_thickness 0.25)
		(keepout
			(tracks not_allowed)
			(vias allowed)
			(pads allowed)
			(copperpour not_allowed)
			(footprints allowed)
		)
		(placement
			(enabled no)
			(sheetname "")
		)
		(fill yes
			(thermal_gap 0.5)
			(thermal_bridge_width 0.5)
			(island_removal_mode 0)
		)
		(polygon
			(pts
				(arc
					(start 450.4182 -277.235158)
					(mid 449.7578 -277.235158)
					(end 450.4182 -277.235158)
				)
			)
		)
	)
	(zone
		(layers "In1.Cu" "In2.Cu")
		(hatch none 0.5)
		(connect_pads
			(clearance 0)
		)
		(min_thickness 0.25)
		(keepout
			(tracks not_allowed)
			(vias allowed)
			(pads allowed)
			(copperpour not_allowed)
			(footprints allowed)
		)
		(placement
			(enabled no)
			(sheetname "")
		)
		(fill yes
			(thermal_gap 0.5)
			(thermal_bridge_width 0.5)
			(island_removal_mode 0)
		)
		(polygon
			(pts
				(arc
					(start 288.510218 -216.885012)
					(mid 287.849818 -216.885012)
					(end 288.510218 -216.885012)
				)
			)
		)
	)
	(zone
		(layers "In1.Cu" "In2.Cu")
		(hatch none 0.5)
		(connect_pads
			(clearance 0)
		)
		(min_thickness 0.25)
		(keepout
			(tracks not_allowed)
			(vias allowed)
			(pads allowed)
			(copperpour not_allowed)
			(footprints allowed)
		)
		(placement
			(enabled no)
			(sheetname "")
		)
		(fill yes
			(thermal_gap 0.5)
			(thermal_bridge_width 0.5)
			(island_removal_mode 0)
		)
		(polygon
			(pts
				(arc
					(start 454.518268 -295.085008)
					(mid 453.857868 -295.085008)
					(end 454.518268 -295.085008)
				)
			)
		)
	)
	(zone
		(layers "In1.Cu" "In2.Cu")
		(hatch none 0.5)
		(connect_pads
			(clearance 0)
		)
		(min_thickness 0.25)
		(keepout
			(tracks not_allowed)
			(vias allowed)
			(pads allowed)
			(copperpour not_allowed)
			(footprints allowed)
		)
		(placement
			(enabled no)
			(sheetname "")
		)
		(fill yes
			(thermal_gap 0.5)
			(thermal_bridge_width 0.5)
			(island_removal_mode 0)
		)
		(polygon
			(pts
				(arc
					(start 292.610286 -242.385088)
					(mid 291.949886 -242.385088)
					(end 292.610286 -242.385088)
				)
			)
		)
	)
	(zone
		(layers "In1.Cu" "In2.Cu")
		(hatch none 0.5)
		(connect_pads
			(clearance 0)
		)
		(min_thickness 0.25)
		(keepout
			(tracks not_allowed)
			(vias allowed)
			(pads allowed)
			(copperpour not_allowed)
			(footprints allowed)
		)
		(placement
			(enabled no)
			(sheetname "")
		)
		(fill yes
			(thermal_gap 0.5)
			(thermal_bridge_width 0.5)
			(island_removal_mode 0)
		)
		(polygon
			(pts
				(arc
					(start 176.402238 -285.735268)
					(mid 175.741838 -285.735268)
					(end 176.402238 -285.735268)
				)
			)
		)
	)
	(zone
		(layers "In1.Cu" "In2.Cu")
		(hatch none 0.5)
		(connect_pads
			(clearance 0)
		)
		(min_thickness 0.25)
		(keepout
			(tracks not_allowed)
			(vias allowed)
			(pads allowed)
			(copperpour not_allowed)
			(footprints allowed)
		)
		(placement
			(enabled no)
			(sheetname "")
		)
		(fill yes
			(thermal_gap 0.5)
			(thermal_bridge_width 0.5)
			(island_removal_mode 0)
		)
		(polygon
			(pts
				(arc
					(start 431.88636 -307.835046)
					(mid 431.22596 -307.835046)
					(end 431.88636 -307.835046)
				)
			)
		)
	)
	(zone
		(layers "In1.Cu" "In2.Cu")
		(hatch none 0.5)
		(connect_pads
			(clearance 0)
		)
		(min_thickness 0.25)
		(keepout
			(tracks not_allowed)
			(vias allowed)
			(pads allowed)
			(copperpour not_allowed)
			(footprints allowed)
		)
		(placement
			(enabled no)
			(sheetname "")
		)
		(fill yes
			(thermal_gap 0.5)
			(thermal_bridge_width 0.5)
			(island_removal_mode 0)
		)
		(polygon
			(pts
				(arc
					(start 191.490346 -300.185328)
					(mid 190.829946 -300.185328)
					(end 191.490346 -300.185328)
				)
			)
		)
	)
	(zone
		(layers "In1.Cu" "In2.Cu")
		(hatch none 0.5)
		(connect_pads
			(clearance 0)
		)
		(min_thickness 0.25)
		(keepout
			(tracks not_allowed)
			(vias allowed)
			(pads allowed)
			(copperpour not_allowed)
			(footprints allowed)
		)
		(placement
			(enabled no)
			(sheetname "")
		)
		(fill yes
			(thermal_gap 0.5)
			(thermal_bridge_width 0.5)
			(island_removal_mode 0)
		)
		(polygon
			(pts
				(arc
					(start 21.841714 -11.91768)
					(mid 21.819396 -11.971562)
					(end 21.765514 -11.99388)
				)
				(arc
					(start 20.72894 -11.99388)
					(mid 20.675058 -11.971562)
					(end 20.65274 -11.91768)
				)
				(arc
					(start 20.65274 -10.51814)
					(mid 20.675058 -10.464258)
					(end 20.72894 -10.44194)
				)
				(arc
					(start 21.765514 -10.44194)
					(mid 21.819396 -10.464258)
					(end 21.841714 -10.51814)
				)
			)
		)
	)
	(zone
		(layers "In1.Cu" "In2.Cu")
		(hatch none 0.5)
		(connect_pads
			(clearance 0)
		)
		(min_thickness 0.25)
		(keepout
			(tracks not_allowed)
			(vias allowed)
			(pads allowed)
			(copperpour not_allowed)
			(footprints allowed)
		)
		(placement
			(enabled no)
			(sheetname "")
		)
		(fill yes
			(thermal_gap 0.5)
			(thermal_bridge_width 0.5)
			(island_removal_mode 0)
		)
		(polygon
			(pts
				(arc
					(start 75.088496 -382.27381)
					(mid 75.07926 -382.293734)
					(end 75.07605 -382.315466)
				)
				(arc
					(start 75.07605 -382.51003)
					(mid 75.098368 -382.563912)
					(end 75.15225 -382.58623)
				)
				(arc
					(start 75.83805 -382.58623)
					(mid 75.891932 -382.563912)
					(end 75.91425 -382.51003)
				)
				(arc
					(start 75.91425 -382.315466)
					(mid 75.911082 -382.293722)
					(end 75.901804 -382.27381)
				)
				(arc
					(start 75.709018 -381.977646)
					(mid 75.696796 -381.935962)
					(end 75.709272 -381.894334)
				)
				(arc
					(start 75.901804 -381.60071)
					(mid 75.91104 -381.580786)
					(end 75.91425 -381.559054)
				)
				(arc
					(start 75.91425 -381.36449)
					(mid 75.891932 -381.310608)
					(end 75.83805 -381.28829)
				)
				(arc
					(start 75.15225 -381.28829)
					(mid 75.098368 -381.310608)
					(end 75.07605 -381.36449)
				)
				(arc
					(start 75.07605 -381.560324)
					(mid 75.079218 -381.582068)
					(end 75.088496 -381.60198)
				)
				(arc
					(start 75.281028 -381.895604)
					(mid 75.29343 -381.93726)
					(end 75.281028 -381.978916)
				)
			)
		)
	)
	(zone
		(layers "In1.Cu" "In2.Cu")
		(hatch none 0.5)
		(connect_pads
			(clearance 0)
		)
		(min_thickness 0.25)
		(keepout
			(tracks not_allowed)
			(vias allowed)
			(pads allowed)
			(copperpour not_allowed)
			(footprints allowed)
		)
		(placement
			(enabled no)
			(sheetname "")
		)
		(fill yes
			(thermal_gap 0.5)
			(thermal_bridge_width 0.5)
			(island_removal_mode 0)
		)
		(polygon
			(pts
				(arc
					(start 52.214272 -199.035416)
					(mid 51.553872 -199.035416)
					(end 52.214272 -199.035416)
				)
			)
		)
	)
	(zone
		(layers "In1.Cu" "In2.Cu")
		(hatch none 0.5)
		(connect_pads
			(clearance 0)
		)
		(min_thickness 0.25)
		(keepout
			(tracks not_allowed)
			(vias allowed)
			(pads allowed)
			(copperpour not_allowed)
			(footprints allowed)
		)
		(placement
			(enabled no)
			(sheetname "")
		)
		(fill yes
			(thermal_gap 0.5)
			(thermal_bridge_width 0.5)
			(island_removal_mode 0)
		)
		(polygon
			(pts
				(arc
					(start 420.242238 -312.084974)
					(mid 419.581838 -312.084974)
					(end 420.242238 -312.084974)
				)
			)
		)
	)
	(zone
		(layers "In1.Cu" "In2.Cu")
		(hatch none 0.5)
		(connect_pads
			(clearance 0)
		)
		(min_thickness 0.25)
		(keepout
			(tracks not_allowed)
			(vias allowed)
			(pads allowed)
			(copperpour not_allowed)
			(footprints allowed)
		)
		(placement
			(enabled no)
			(sheetname "")
		)
		(fill yes
			(thermal_gap 0.5)
			(thermal_bridge_width 0.5)
			(island_removal_mode 0)
		)
		(polygon
			(pts
				(arc
					(start 375.392442 -379.360684)
					(mid 375.412366 -379.36992)
					(end 375.434098 -379.37313)
				)
				(arc
					(start 375.628662 -379.37313)
					(mid 375.682544 -379.350812)
					(end 375.704862 -379.29693)
				)
				(arc
					(start 375.704862 -378.61113)
					(mid 375.682544 -378.557248)
					(end 375.628662 -378.53493)
				)
				(arc
					(start 375.434098 -378.53493)
					(mid 375.412354 -378.538098)
					(end 375.392442 -378.547376)
				)
				(arc
					(start 375.096278 -378.740162)
					(mid 375.054594 -378.752384)
					(end 375.012966 -378.739908)
				)
				(arc
					(start 374.719342 -378.547376)
					(mid 374.699418 -378.53814)
					(end 374.677686 -378.53493)
				)
				(arc
					(start 374.483122 -378.53493)
					(mid 374.42924 -378.557248)
					(end 374.406922 -378.61113)
				)
				(arc
					(start 374.406922 -379.29693)
					(mid 374.42924 -379.350812)
					(end 374.483122 -379.37313)
				)
				(arc
					(start 374.678956 -379.37313)
					(mid 374.7007 -379.369962)
					(end 374.720612 -379.360684)
				)
				(arc
					(start 375.014236 -379.168152)
					(mid 375.055892 -379.15575)
					(end 375.097548 -379.168152)
				)
			)
		)
	)
	(zone
		(layers "In1.Cu" "In2.Cu")
		(hatch none 0.5)
		(connect_pads
			(clearance 0)
		)
		(min_thickness 0.25)
		(keepout
			(tracks not_allowed)
			(vias allowed)
			(pads allowed)
			(copperpour not_allowed)
			(footprints allowed)
		)
		(placement
			(enabled no)
			(sheetname "")
		)
		(fill yes
			(thermal_gap 0.5)
			(thermal_bridge_width 0.5)
			(island_removal_mode 0)
		)
		(polygon
			(pts
				(arc
					(start 172.30217 -288.285428)
					(mid 171.64177 -288.285428)
					(end 172.30217 -288.285428)
				)
			)
		)
	)
	(zone
		(layers "In1.Cu" "In2.Cu")
		(hatch none 0.5)
		(connect_pads
			(clearance 0)
		)
		(min_thickness 0.25)
		(keepout
			(tracks not_allowed)
			(vias allowed)
			(pads allowed)
			(copperpour not_allowed)
			(footprints allowed)
		)
		(placement
			(enabled no)
			(sheetname "")
		)
		(fill yes
			(thermal_gap 0.5)
			(thermal_bridge_width 0.5)
			(island_removal_mode 0)
		)
		(polygon
			(pts
				(arc
					(start 187.390278 -204.135228)
					(mid 186.729878 -204.135228)
					(end 187.390278 -204.135228)
				)
			)
		)
	)
	(zone
		(layers "In1.Cu" "In2.Cu")
		(hatch none 0.5)
		(connect_pads
			(clearance 0)
		)
		(min_thickness 0.25)
		(keepout
			(tracks not_allowed)
			(vias allowed)
			(pads allowed)
			(copperpour not_allowed)
			(footprints allowed)
		)
		(placement
			(enabled no)
			(sheetname "")
		)
		(fill yes
			(thermal_gap 0.5)
			(thermal_bridge_width 0.5)
			(island_removal_mode 0)
		)
		(polygon
			(pts
				(arc
					(start 424.342306 -227.085144)
					(mid 423.681906 -227.085144)
					(end 424.342306 -227.085144)
				)
			)
		)
	)
	(zone
		(layers "In1.Cu" "In2.Cu")
		(hatch none 0.5)
		(connect_pads
			(clearance 0)
		)
		(min_thickness 0.25)
		(keepout
			(tracks not_allowed)
			(vias allowed)
			(pads allowed)
			(copperpour not_allowed)
			(footprints allowed)
		)
		(placement
			(enabled no)
			(sheetname "")
		)
		(fill yes
			(thermal_gap 0.5)
			(thermal_bridge_width 0.5)
			(island_removal_mode 0)
		)
		(polygon
			(pts
				(arc
					(start 191.490346 -220.28531)
					(mid 190.829946 -220.28531)
					(end 191.490346 -220.28531)
				)
			)
		)
	)
	(zone
		(layers "In1.Cu" "In2.Cu")
		(hatch none 0.5)
		(connect_pads
			(clearance 0)
		)
		(min_thickness 0.25)
		(keepout
			(tracks not_allowed)
			(vias allowed)
			(pads allowed)
			(copperpour not_allowed)
			(footprints allowed)
		)
		(placement
			(enabled no)
			(sheetname "")
		)
		(fill yes
			(thermal_gap 0.5)
			(thermal_bridge_width 0.5)
			(island_removal_mode 0)
		)
		(polygon
			(pts
				(arc
					(start 17.938242 -316.33541)
					(mid 17.277842 -316.33541)
					(end 17.938242 -316.33541)
				)
			)
		)
	)
	(zone
		(layers "In1.Cu" "In2.Cu")
		(hatch none 0.5)
		(connect_pads
			(clearance 0)
		)
		(min_thickness 0.25)
		(keepout
			(tracks not_allowed)
			(vias allowed)
			(pads allowed)
			(copperpour not_allowed)
			(footprints allowed)
		)
		(placement
			(enabled no)
			(sheetname "")
		)
		(fill yes
			(thermal_gap 0.5)
			(thermal_bridge_width 0.5)
			(island_removal_mode 0)
		)
		(polygon
			(pts
				(arc
					(start 269.978378 -266.185142)
					(mid 269.317978 -266.185142)
					(end 269.978378 -266.185142)
				)
			)
		)
	)
	(zone
		(layers "In1.Cu" "In2.Cu")
		(hatch none 0.5)
		(connect_pads
			(clearance 0)
		)
		(min_thickness 0.25)
		(keepout
			(tracks not_allowed)
			(vias allowed)
			(pads allowed)
			(copperpour not_allowed)
			(footprints allowed)
		)
		(placement
			(enabled no)
			(sheetname "")
		)
		(fill yes
			(thermal_gap 0.5)
			(thermal_bridge_width 0.5)
			(island_removal_mode 0)
		)
		(polygon
			(pts
				(arc
					(start 183.946292 -307.8353)
					(mid 183.285892 -307.8353)
					(end 183.946292 -307.8353)
				)
			)
		)
	)
	(zone
		(layers "In1.Cu" "In2.Cu")
		(hatch none 0.5)
		(connect_pads
			(clearance 0)
		)
		(min_thickness 0.25)
		(keepout
			(tracks not_allowed)
			(vias allowed)
			(pads allowed)
			(copperpour not_allowed)
			(footprints allowed)
		)
		(placement
			(enabled no)
			(sheetname "")
		)
		(fill yes
			(thermal_gap 0.5)
			(thermal_bridge_width 0.5)
			(island_removal_mode 0)
		)
		(polygon
			(pts
				(arc
					(start 420.242238 -199.885046)
					(mid 419.581838 -199.885046)
					(end 420.242238 -199.885046)
				)
			)
		)
	)
	(zone
		(layers "In1.Cu" "In2.Cu")
		(hatch none 0.5)
		(connect_pads
			(clearance 0)
		)
		(min_thickness 0.25)
		(keepout
			(tracks not_allowed)
			(vias allowed)
			(pads allowed)
			(copperpour not_allowed)
			(footprints allowed)
		)
		(placement
			(enabled no)
			(sheetname "")
		)
		(fill yes
			(thermal_gap 0.5)
			(thermal_bridge_width 0.5)
			(island_removal_mode 0)
		)
		(polygon
			(pts
				(arc
					(start 108.094018 -32.669734)
					(mid 108.108897 -32.633813)
					(end 108.144818 -32.618934)
				)
				(arc
					(start 108.652818 -32.618934)
					(mid 108.688739 -32.633813)
					(end 108.703618 -32.669734)
				)
				(arc
					(start 108.703618 -33.32607)
					(mid 108.688739 -33.361991)
					(end 108.652818 -33.37687)
				)
				(arc
					(start 108.144818 -33.37687)
					(mid 108.108897 -33.361991)
					(end 108.094018 -33.32607)
				)
			)
		)
	)
	(zone
		(layers "In1.Cu" "In2.Cu")
		(hatch none 0.5)
		(connect_pads
			(clearance 0)
		)
		(min_thickness 0.25)
		(keepout
			(tracks not_allowed)
			(vias allowed)
			(pads allowed)
			(copperpour not_allowed)
			(footprints allowed)
		)
		(placement
			(enabled no)
			(sheetname "")
		)
		(fill yes
			(thermal_gap 0.5)
			(thermal_bridge_width 0.5)
			(island_removal_mode 0)
		)
		(polygon
			(pts
				(arc
					(start 439.430414 -313.784996)
					(mid 438.770014 -313.784996)
					(end 439.430414 -313.784996)
				)
			)
		)
	)
	(zone
		(layers "In1.Cu" "In2.Cu")
		(hatch none 0.5)
		(connect_pads
			(clearance 0)
		)
		(min_thickness 0.25)
		(keepout
			(tracks not_allowed)
			(vias allowed)
			(pads allowed)
			(copperpour not_allowed)
			(footprints allowed)
		)
		(placement
			(enabled no)
			(sheetname "")
		)
		(fill yes
			(thermal_gap 0.5)
			(thermal_bridge_width 0.5)
			(island_removal_mode 0)
		)
		(polygon
			(pts
				(arc
					(start 183.946292 -244.085364)
					(mid 183.285892 -244.085364)
					(end 183.946292 -244.085364)
				)
			)
		)
	)
	(zone
		(layers "In1.Cu" "In2.Cu")
		(hatch none 0.5)
		(connect_pads
			(clearance 0)
		)
		(min_thickness 0.25)
		(keepout
			(tracks not_allowed)
			(vias allowed)
			(pads allowed)
			(copperpour not_allowed)
			(footprints allowed)
		)
		(placement
			(enabled no)
			(sheetname "")
		)
		(fill yes
			(thermal_gap 0.5)
			(thermal_bridge_width 0.5)
			(island_removal_mode 0)
		)
		(polygon
			(pts
				(arc
					(start 285.066232 -238.985044)
					(mid 284.405832 -238.985044)
					(end 285.066232 -238.985044)
				)
			)
		)
	)
	(zone
		(layers "In1.Cu" "In2.Cu")
		(hatch none 0.5)
		(connect_pads
			(clearance 0)
		)
		(min_thickness 0.25)
		(keepout
			(tracks not_allowed)
			(vias allowed)
			(pads allowed)
			(copperpour not_allowed)
			(footprints allowed)
		)
		(placement
			(enabled no)
			(sheetname "")
		)
		(fill yes
			(thermal_gap 0.5)
			(thermal_bridge_width 0.5)
			(island_removal_mode 0)
		)
		(polygon
			(pts
				(arc
					(start 277.522432 -287.435036)
					(mid 276.862032 -287.435036)
					(end 277.522432 -287.435036)
				)
			)
		)
	)
	(zone
		(layers "In1.Cu" "In2.Cu")
		(hatch none 0.5)
		(connect_pads
			(clearance 0)
		)
		(min_thickness 0.25)
		(keepout
			(tracks not_allowed)
			(vias allowed)
			(pads allowed)
			(copperpour not_allowed)
			(footprints allowed)
		)
		(placement
			(enabled no)
			(sheetname "")
		)
		(fill yes
			(thermal_gap 0.5)
			(thermal_bridge_width 0.5)
			(island_removal_mode 0)
		)
		(polygon
			(pts
				(arc
					(start 29.582364 -250.885198)
					(mid 28.921964 -250.885198)
					(end 29.582364 -250.885198)
				)
			)
		)
	)
	(zone
		(layers "In1.Cu" "In2.Cu")
		(hatch none 0.5)
		(connect_pads
			(clearance 0)
		)
		(min_thickness 0.25)
		(keepout
			(tracks not_allowed)
			(vias allowed)
			(pads allowed)
			(copperpour not_allowed)
			(footprints allowed)
		)
		(placement
			(enabled no)
			(sheetname "")
		)
		(fill yes
			(thermal_gap 0.5)
			(thermal_bridge_width 0.5)
			(island_removal_mode 0)
		)
		(polygon
			(pts
				(arc
					(start 172.30217 -248.335292)
					(mid 171.64177 -248.335292)
					(end 172.30217 -248.335292)
				)
			)
		)
	)
	(zone
		(layers "In1.Cu" "In2.Cu")
		(hatch none 0.5)
		(connect_pads
			(clearance 0)
		)
		(min_thickness 0.25)
		(keepout
			(tracks not_allowed)
			(vias allowed)
			(pads allowed)
			(copperpour not_allowed)
			(footprints allowed)
		)
		(placement
			(enabled no)
			(sheetname "")
		)
		(fill yes
			(thermal_gap 0.5)
			(thermal_bridge_width 0.5)
			(island_removal_mode 0)
		)
		(polygon
			(pts
				(arc
					(start 176.402238 -273.835368)
					(mid 175.741838 -273.835368)
					(end 176.402238 -273.835368)
				)
			)
		)
	)
	(zone
		(layers "In1.Cu" "In2.Cu")
		(hatch none 0.5)
		(connect_pads
			(clearance 0)
		)
		(min_thickness 0.25)
		(keepout
			(tracks not_allowed)
			(vias allowed)
			(pads allowed)
			(copperpour not_allowed)
			(footprints allowed)
		)
		(placement
			(enabled no)
			(sheetname "")
		)
		(fill yes
			(thermal_gap 0.5)
			(thermal_bridge_width 0.5)
			(island_removal_mode 0)
		)
		(polygon
			(pts
				(arc
					(start 179.846224 -238.985298)
					(mid 179.185824 -238.985298)
					(end 179.846224 -238.985298)
				)
			)
		)
	)
	(zone
		(layers "In1.Cu" "In2.Cu")
		(hatch none 0.5)
		(connect_pads
			(clearance 0)
		)
		(min_thickness 0.25)
		(keepout
			(tracks not_allowed)
			(vias allowed)
			(pads allowed)
			(copperpour not_allowed)
			(footprints allowed)
		)
		(placement
			(enabled no)
			(sheetname "")
		)
		(fill yes
			(thermal_gap 0.5)
			(thermal_bridge_width 0.5)
			(island_removal_mode 0)
		)
		(polygon
			(pts
				(arc
					(start 183.946292 -296.785284)
					(mid 183.285892 -296.785284)
					(end 183.946292 -296.785284)
				)
			)
		)
	)
	(zone
		(layers "In1.Cu" "In2.Cu")
		(hatch none 0.5)
		(connect_pads
			(clearance 0)
		)
		(min_thickness 0.25)
		(keepout
			(tracks not_allowed)
			(vias allowed)
			(pads allowed)
			(copperpour not_allowed)
			(footprints allowed)
		)
		(placement
			(enabled no)
			(sheetname "")
		)
		(fill yes
			(thermal_gap 0.5)
			(thermal_bridge_width 0.5)
			(island_removal_mode 0)
		)
		(polygon
			(pts
				(arc
					(start 240.44783 -56.406542)
					(mid 240.438594 -56.426466)
					(end 240.435384 -56.448198)
				)
				(arc
					(start 240.435384 -56.642762)
					(mid 240.457702 -56.696644)
					(end 240.511584 -56.718962)
				)
				(arc
					(start 241.197384 -56.718962)
					(mid 241.251266 -56.696644)
					(end 241.273584 -56.642762)
				)
				(arc
					(start 241.273584 -56.448198)
					(mid 241.270416 -56.426454)
					(end 241.261138 -56.406542)
				)
				(arc
					(start 241.068352 -56.110378)
					(mid 241.05613 -56.068694)
					(end 241.068606 -56.027066)
				)
				(arc
					(start 241.261138 -55.733442)
					(mid 241.270374 -55.713518)
					(end 241.273584 -55.691786)
				)
				(arc
					(start 241.273584 -55.497222)
					(mid 241.251266 -55.44334)
					(end 241.197384 -55.421022)
				)
				(arc
					(start 240.511584 -55.421022)
					(mid 240.457702 -55.44334)
					(end 240.435384 -55.497222)
				)
				(arc
					(start 240.435384 -55.693056)
					(mid 240.438552 -55.7148)
					(end 240.44783 -55.734712)
				)
				(arc
					(start 240.640362 -56.028336)
					(mid 240.652764 -56.069992)
					(end 240.640362 -56.111648)
				)
			)
		)
	)
	(zone
		(layers "In1.Cu" "In2.Cu")
		(hatch none 0.5)
		(connect_pads
			(clearance 0)
		)
		(min_thickness 0.25)
		(keepout
			(tracks not_allowed)
			(vias allowed)
			(pads allowed)
			(copperpour not_allowed)
			(footprints allowed)
		)
		(placement
			(enabled no)
			(sheetname "")
		)
		(fill yes
			(thermal_gap 0.5)
			(thermal_bridge_width 0.5)
			(island_removal_mode 0)
		)
		(polygon
			(pts
				(arc
					(start 431.88636 -212.635084)
					(mid 431.22596 -212.635084)
					(end 431.88636 -212.635084)
				)
			)
		)
	)
	(zone
		(layers "In1.Cu" "In2.Cu")
		(hatch none 0.5)
		(connect_pads
			(clearance 0)
		)
		(min_thickness 0.25)
		(keepout
			(tracks not_allowed)
			(vias allowed)
			(pads allowed)
			(copperpour not_allowed)
			(footprints allowed)
		)
		(placement
			(enabled no)
			(sheetname "")
		)
		(fill yes
			(thermal_gap 0.5)
			(thermal_bridge_width 0.5)
			(island_removal_mode 0)
		)
		(polygon
			(pts
				(arc
					(start 446.974468 -250.884944)
					(mid 446.314068 -250.884944)
					(end 446.974468 -250.884944)
				)
			)
		)
	)
	(zone
		(layers "In1.Cu" "In2.Cu")
		(hatch none 0.5)
		(connect_pads
			(clearance 0)
		)
		(min_thickness 0.25)
		(keepout
			(tracks not_allowed)
			(vias allowed)
			(pads allowed)
			(copperpour not_allowed)
			(footprints allowed)
		)
		(placement
			(enabled no)
			(sheetname "")
		)
		(fill yes
			(thermal_gap 0.5)
			(thermal_bridge_width 0.5)
			(island_removal_mode 0)
		)
		(polygon
			(pts
				(arc
					(start 202.478132 -261.935214)
					(mid 201.817732 -261.935214)
					(end 202.478132 -261.935214)
				)
			)
		)
	)
	(zone
		(layers "In1.Cu" "In2.Cu")
		(hatch none 0.5)
		(connect_pads
			(clearance 0)
		)
		(min_thickness 0.25)
		(keepout
			(tracks not_allowed)
			(vias allowed)
			(pads allowed)
			(copperpour not_allowed)
			(footprints allowed)
		)
		(placement
			(enabled no)
			(sheetname "")
		)
		(fill yes
			(thermal_gap 0.5)
			(thermal_bridge_width 0.5)
			(island_removal_mode 0)
		)
		(polygon
			(pts
				(arc
					(start 183.946292 -295.085262)
					(mid 183.285892 -295.085262)
					(end 183.946292 -295.085262)
				)
			)
		)
	)
	(zone
		(layers "In1.Cu" "In2.Cu")
		(hatch none 0.5)
		(connect_pads
			(clearance 0)
		)
		(min_thickness 0.25)
		(keepout
			(tracks not_allowed)
			(vias allowed)
			(pads allowed)
			(copperpour not_allowed)
			(footprints allowed)
		)
		(placement
			(enabled no)
			(sheetname "")
		)
		(fill yes
			(thermal_gap 0.5)
			(thermal_bridge_width 0.5)
			(island_removal_mode 0)
		)
		(polygon
			(pts
				(arc
					(start 202.478132 -286.585406)
					(mid 201.817732 -286.585406)
					(end 202.478132 -286.585406)
				)
			)
		)
	)
	(zone
		(layers "In1.Cu" "In2.Cu")
		(hatch none 0.5)
		(connect_pads
			(clearance 0)
		)
		(min_thickness 0.25)
		(keepout
			(tracks not_allowed)
			(vias allowed)
			(pads allowed)
			(copperpour not_allowed)
			(footprints allowed)
		)
		(placement
			(enabled no)
			(sheetname "")
		)
		(fill yes
			(thermal_gap 0.5)
			(thermal_bridge_width 0.5)
			(island_removal_mode 0)
		)
		(polygon
			(pts
				(arc
					(start 424.342306 -233.035094)
					(mid 423.681906 -233.035094)
					(end 424.342306 -233.035094)
				)
			)
		)
	)
	(zone
		(layers "In1.Cu" "In2.Cu")
		(hatch none 0.5)
		(connect_pads
			(clearance 0)
		)
		(min_thickness 0.25)
		(keepout
			(tracks not_allowed)
			(vias allowed)
			(pads allowed)
			(copperpour not_allowed)
			(footprints allowed)
		)
		(placement
			(enabled no)
			(sheetname "")
		)
		(fill yes
			(thermal_gap 0.5)
			(thermal_bridge_width 0.5)
			(island_removal_mode 0)
		)
		(polygon
			(pts
				(arc
					(start 17.938242 -201.585322)
					(mid 17.277842 -201.585322)
					(end 17.938242 -201.585322)
				)
			)
		)
	)
	(zone
		(layers "In1.Cu" "In2.Cu")
		(hatch none 0.5)
		(connect_pads
			(clearance 0)
		)
		(min_thickness 0.25)
		(keepout
			(tracks not_allowed)
			(vias allowed)
			(pads allowed)
			(copperpour not_allowed)
			(footprints allowed)
		)
		(placement
			(enabled no)
			(sheetname "")
		)
		(fill yes
			(thermal_gap 0.5)
			(thermal_bridge_width 0.5)
			(island_removal_mode 0)
		)
		(polygon
			(pts
				(arc
					(start 17.938242 -277.235412)
					(mid 17.277842 -277.235412)
					(end 17.938242 -277.235412)
				)
			)
		)
	)
	(zone
		(layers "In1.Cu" "In2.Cu")
		(hatch none 0.5)
		(connect_pads
			(clearance 0)
		)
		(min_thickness 0.25)
		(keepout
			(tracks not_allowed)
			(vias allowed)
			(pads allowed)
			(copperpour not_allowed)
			(footprints allowed)
		)
		(placement
			(enabled no)
			(sheetname "")
		)
		(fill yes
			(thermal_gap 0.5)
			(thermal_bridge_width 0.5)
			(island_removal_mode 0)
		)
		(polygon
			(pts
				(arc
					(start 292.610286 -307.835046)
					(mid 291.949886 -307.835046)
					(end 292.610286 -307.835046)
				)
			)
		)
	)
	(zone
		(layers "In1.Cu" "In2.Cu")
		(hatch none 0.5)
		(connect_pads
			(clearance 0)
		)
		(min_thickness 0.25)
		(keepout
			(tracks not_allowed)
			(vias allowed)
			(pads allowed)
			(copperpour not_allowed)
			(footprints allowed)
		)
		(placement
			(enabled no)
			(sheetname "")
		)
		(fill yes
			(thermal_gap 0.5)
			(thermal_bridge_width 0.5)
			(island_removal_mode 0)
		)
		(polygon
			(pts
				(arc
					(start 202.478132 -215.185244)
					(mid 201.817732 -215.185244)
					(end 202.478132 -215.185244)
				)
			)
		)
	)
	(zone
		(layers "In1.Cu" "In2.Cu")
		(hatch none 0.5)
		(connect_pads
			(clearance 0)
		)
		(min_thickness 0.25)
		(keepout
			(tracks not_allowed)
			(vias allowed)
			(pads allowed)
			(copperpour not_allowed)
			(footprints allowed)
		)
		(placement
			(enabled no)
			(sheetname "")
		)
		(fill yes
			(thermal_gap 0.5)
			(thermal_bridge_width 0.5)
			(island_removal_mode 0)
		)
		(polygon
			(pts
				(arc
					(start 48.114204 -235.585254)
					(mid 47.453804 -235.585254)
					(end 48.114204 -235.585254)
				)
			)
		)
	)
	(zone
		(layers "In1.Cu" "In2.Cu")
		(hatch none 0.5)
		(connect_pads
			(clearance 0)
		)
		(min_thickness 0.25)
		(keepout
			(tracks not_allowed)
			(vias allowed)
			(pads allowed)
			(copperpour not_allowed)
			(footprints allowed)
		)
		(placement
			(enabled no)
			(sheetname "")
		)
		(fill yes
			(thermal_gap 0.5)
			(thermal_bridge_width 0.5)
			(island_removal_mode 0)
		)
		(polygon
			(pts
				(arc
					(start 166.572438 -12.952222)
					(mid 166.594756 -12.89834)
					(end 166.648638 -12.876022)
				)
				(arc
					(start 167.685212 -12.876022)
					(mid 167.739094 -12.89834)
					(end 167.761412 -12.952222)
				)
				(arc
					(start 167.761412 -14.351762)
					(mid 167.739094 -14.405644)
					(end 167.685212 -14.427962)
				)
				(arc
					(start 166.648638 -14.427962)
					(mid 166.594756 -14.405644)
					(end 166.572438 -14.351762)
				)
			)
		)
	)
	(zone
		(layers "In1.Cu" "In2.Cu")
		(hatch none 0.5)
		(connect_pads
			(clearance 0)
		)
		(min_thickness 0.25)
		(keepout
			(tracks not_allowed)
			(vias allowed)
			(pads allowed)
			(copperpour not_allowed)
			(footprints allowed)
		)
		(placement
			(enabled no)
			(sheetname "")
		)
		(fill yes
			(thermal_gap 0.5)
			(thermal_bridge_width 0.5)
			(island_removal_mode 0)
		)
		(polygon
			(pts
				(arc
					(start 432.861466 -11.91768)
					(mid 432.839148 -11.971562)
					(end 432.785266 -11.99388)
				)
				(arc
					(start 431.748692 -11.99388)
					(mid 431.69481 -11.971562)
					(end 431.672492 -11.91768)
				)
				(arc
					(start 431.672492 -10.51814)
					(mid 431.69481 -10.464258)
					(end 431.748692 -10.44194)
				)
				(arc
					(start 432.785266 -10.44194)
					(mid 432.839148 -10.464258)
					(end 432.861466 -10.51814)
				)
			)
		)
	)
	(zone
		(layers "In1.Cu" "In2.Cu")
		(hatch none 0.5)
		(connect_pads
			(clearance 0)
		)
		(min_thickness 0.25)
		(keepout
			(tracks not_allowed)
			(vias allowed)
			(pads allowed)
			(copperpour not_allowed)
			(footprints allowed)
		)
		(placement
			(enabled no)
			(sheetname "")
		)
		(fill yes
			(thermal_gap 0.5)
			(thermal_bridge_width 0.5)
			(island_removal_mode 0)
		)
		(polygon
			(pts
				(arc
					(start 285.066232 -240.685066)
					(mid 284.405832 -240.685066)
					(end 285.066232 -240.685066)
				)
			)
		)
	)
	(zone
		(layers "In1.Cu" "In2.Cu")
		(hatch none 0.5)
		(connect_pads
			(clearance 0)
		)
		(min_thickness 0.25)
		(keepout
			(tracks not_allowed)
			(vias allowed)
			(pads allowed)
			(copperpour not_allowed)
			(footprints allowed)
		)
		(placement
			(enabled no)
			(sheetname "")
		)
		(fill yes
			(thermal_gap 0.5)
			(thermal_bridge_width 0.5)
			(island_removal_mode 0)
		)
		(polygon
			(pts
				(arc
					(start 285.066232 -295.085008)
					(mid 284.405832 -295.085008)
					(end 285.066232 -295.085008)
				)
			)
		)
	)
	(zone
		(layers "In1.Cu" "In2.Cu")
		(hatch none 0.5)
		(connect_pads
			(clearance 0)
		)
		(min_thickness 0.25)
		(keepout
			(tracks not_allowed)
			(vias allowed)
			(pads allowed)
			(copperpour not_allowed)
			(footprints allowed)
		)
		(placement
			(enabled no)
			(sheetname "")
		)
		(fill yes
			(thermal_gap 0.5)
			(thermal_bridge_width 0.5)
			(island_removal_mode 0)
		)
		(polygon
			(pts
				(arc
					(start 176.402238 -233.035348)
					(mid 175.741838 -233.035348)
					(end 176.402238 -233.035348)
				)
			)
		)
	)
	(zone
		(layers "In1.Cu" "In2.Cu")
		(hatch none 0.5)
		(connect_pads
			(clearance 0)
		)
		(min_thickness 0.25)
		(keepout
			(tracks not_allowed)
			(vias allowed)
			(pads allowed)
			(copperpour not_allowed)
			(footprints allowed)
		)
		(placement
			(enabled no)
			(sheetname "")
		)
		(fill yes
			(thermal_gap 0.5)
			(thermal_bridge_width 0.5)
			(island_removal_mode 0)
		)
		(polygon
			(pts
				(arc
					(start 454.518268 -289.135058)
					(mid 453.857868 -289.135058)
					(end 454.518268 -289.135058)
				)
			)
		)
	)
	(zone
		(layers "In1.Cu" "In2.Cu")
		(hatch none 0.5)
		(connect_pads
			(clearance 0)
		)
		(min_thickness 0.25)
		(keepout
			(tracks not_allowed)
			(vias allowed)
			(pads allowed)
			(copperpour not_allowed)
			(footprints allowed)
		)
		(placement
			(enabled no)
			(sheetname "")
		)
		(fill yes
			(thermal_gap 0.5)
			(thermal_bridge_width 0.5)
			(island_removal_mode 0)
		)
		(polygon
			(pts
				(arc
					(start 292.610286 -269.585186)
					(mid 291.949886 -269.585186)
					(end 292.610286 -269.585186)
				)
			)
		)
	)
	(zone
		(layers "In1.Cu" "In2.Cu")
		(hatch none 0.5)
		(connect_pads
			(clearance 0)
		)
		(min_thickness 0.25)
		(keepout
			(tracks not_allowed)
			(vias allowed)
			(pads allowed)
			(copperpour not_allowed)
			(footprints allowed)
		)
		(placement
			(enabled no)
			(sheetname "")
		)
		(fill yes
			(thermal_gap 0.5)
			(thermal_bridge_width 0.5)
			(island_removal_mode 0)
		)
		(polygon
			(pts
				(arc
					(start 48.114204 -233.885232)
					(mid 47.453804 -233.885232)
					(end 48.114204 -233.885232)
				)
			)
		)
	)
	(zone
		(layers "In1.Cu" "In2.Cu")
		(hatch none 0.5)
		(connect_pads
			(clearance 0)
		)
		(min_thickness 0.25)
		(keepout
			(tracks not_allowed)
			(vias allowed)
			(pads allowed)
			(copperpour not_allowed)
			(footprints allowed)
		)
		(placement
			(enabled no)
			(sheetname "")
		)
		(fill yes
			(thermal_gap 0.5)
			(thermal_bridge_width 0.5)
			(island_removal_mode 0)
		)
		(polygon
			(pts
				(arc
					(start 191.490346 -304.435256)
					(mid 190.829946 -304.435256)
					(end 191.490346 -304.435256)
				)
			)
		)
	)
	(zone
		(layers "In1.Cu" "In2.Cu")
		(hatch none 0.5)
		(connect_pads
			(clearance 0)
		)
		(min_thickness 0.25)
		(keepout
			(tracks not_allowed)
			(vias allowed)
			(pads allowed)
			(copperpour not_allowed)
			(footprints allowed)
		)
		(placement
			(enabled no)
			(sheetname "")
		)
		(fill yes
			(thermal_gap 0.5)
			(thermal_bridge_width 0.5)
			(island_removal_mode 0)
		)
		(polygon
			(pts
				(arc
					(start 454.518268 -228.785166)
					(mid 453.857868 -228.785166)
					(end 454.518268 -228.785166)
				)
			)
		)
	)
	(zone
		(layers "In1.Cu" "In2.Cu")
		(hatch none 0.5)
		(connect_pads
			(clearance 0)
		)
		(min_thickness 0.25)
		(keepout
			(tracks not_allowed)
			(vias allowed)
			(pads allowed)
			(copperpour not_allowed)
			(footprints allowed)
		)
		(placement
			(enabled no)
			(sheetname "")
		)
		(fill yes
			(thermal_gap 0.5)
			(thermal_bridge_width 0.5)
			(island_removal_mode 0)
		)
		(polygon
			(pts
				(arc
					(start 40.57015 -211.7852)
					(mid 39.90975 -211.7852)
					(end 40.57015 -211.7852)
				)
			)
		)
	)
	(zone
		(layers "In1.Cu" "In2.Cu")
		(hatch none 0.5)
		(connect_pads
			(clearance 0)
		)
		(min_thickness 0.25)
		(keepout
			(tracks not_allowed)
			(vias allowed)
			(pads allowed)
			(copperpour not_allowed)
			(footprints allowed)
		)
		(placement
			(enabled no)
			(sheetname "")
		)
		(fill yes
			(thermal_gap 0.5)
			(thermal_bridge_width 0.5)
			(island_removal_mode 0)
		)
		(polygon
			(pts
				(arc
					(start 176.402238 -219.435426)
					(mid 175.741838 -219.435426)
					(end 176.402238 -219.435426)
				)
			)
		)
	)
	(zone
		(layers "In1.Cu" "In2.Cu")
		(hatch none 0.5)
		(connect_pads
			(clearance 0)
		)
		(min_thickness 0.25)
		(keepout
			(tracks not_allowed)
			(vias allowed)
			(pads allowed)
			(copperpour not_allowed)
			(footprints allowed)
		)
		(placement
			(enabled no)
			(sheetname "")
		)
		(fill yes
			(thermal_gap 0.5)
			(thermal_bridge_width 0.5)
			(island_removal_mode 0)
		)
		(polygon
			(pts
				(arc
					(start 273.422364 -301.034958)
					(mid 272.761964 -301.034958)
					(end 273.422364 -301.034958)
				)
			)
		)
	)
	(zone
		(layers "In1.Cu" "In2.Cu")
		(hatch none 0.5)
		(connect_pads
			(clearance 0)
		)
		(min_thickness 0.25)
		(keepout
			(tracks not_allowed)
			(vias allowed)
			(pads allowed)
			(copperpour not_allowed)
			(footprints allowed)
		)
		(placement
			(enabled no)
			(sheetname "")
		)
		(fill yes
			(thermal_gap 0.5)
			(thermal_bridge_width 0.5)
			(island_removal_mode 0)
		)
		(polygon
			(pts
				(arc
					(start 280.966164 -310.384952)
					(mid 280.305764 -310.384952)
					(end 280.966164 -310.384952)
				)
			)
		)
	)
	(zone
		(layers "In1.Cu" "In2.Cu")
		(hatch none 0.5)
		(connect_pads
			(clearance 0)
		)
		(min_thickness 0.25)
		(keepout
			(tracks not_allowed)
			(vias allowed)
			(pads allowed)
			(copperpour not_allowed)
			(footprints allowed)
		)
		(placement
			(enabled no)
			(sheetname "")
		)
		(fill yes
			(thermal_gap 0.5)
			(thermal_bridge_width 0.5)
			(island_removal_mode 0)
		)
		(polygon
			(pts
				(arc
					(start 177.832258 -51.558698)
					(mid 177.88614 -51.581016)
					(end 177.908458 -51.634898)
				)
				(arc
					(start 177.908458 -52.46497)
					(mid 177.88614 -52.518852)
					(end 177.832258 -52.54117)
				)
				(arc
					(start 176.384458 -52.54117)
					(mid 176.330576 -52.518852)
					(end 176.308258 -52.46497)
				)
				(arc
					(start 176.308258 -51.634898)
					(mid 176.330576 -51.581016)
					(end 176.384458 -51.558698)
				)
			)
		)
	)
	(zone
		(layers "In1.Cu" "In2.Cu")
		(hatch none 0.5)
		(connect_pads
			(clearance 0)
		)
		(min_thickness 0.25)
		(keepout
			(tracks not_allowed)
			(vias allowed)
			(pads allowed)
			(copperpour not_allowed)
			(footprints allowed)
		)
		(placement
			(enabled no)
			(sheetname "")
		)
		(fill yes
			(thermal_gap 0.5)
			(thermal_bridge_width 0.5)
			(island_removal_mode 0)
		)
		(polygon
			(pts
				(arc
					(start 435.330346 -248.335038)
					(mid 434.669946 -248.335038)
					(end 435.330346 -248.335038)
				)
			)
		)
	)
	(zone
		(layers "In1.Cu" "In2.Cu")
		(hatch none 0.5)
		(connect_pads
			(clearance 0)
		)
		(min_thickness 0.25)
		(keepout
			(tracks not_allowed)
			(vias allowed)
			(pads allowed)
			(copperpour not_allowed)
			(footprints allowed)
		)
		(placement
			(enabled no)
			(sheetname "")
		)
		(fill yes
			(thermal_gap 0.5)
			(thermal_bridge_width 0.5)
			(island_removal_mode 0)
		)
		(polygon
			(pts
				(arc
					(start 38.890194 -423.35704)
					(mid 38.905073 -423.392961)
					(end 38.940994 -423.40784)
				)
				(arc
					(start 40.210994 -423.40784)
					(mid 40.246915 -423.392961)
					(end 40.261794 -423.35704)
				)
				(arc
					(start 40.261794 -423.07764)
					(mid 40.246915 -423.041719)
					(end 40.210994 -423.02684)
				)
				(arc
					(start 38.940994 -423.02684)
					(mid 38.905073 -423.041719)
					(end 38.890194 -423.07764)
				)
			)
		)
	)
	(zone
		(layers "In1.Cu" "In2.Cu")
		(hatch none 0.5)
		(connect_pads
			(clearance 0)
		)
		(min_thickness 0.25)
		(keepout
			(tracks not_allowed)
			(vias allowed)
			(pads allowed)
			(copperpour not_allowed)
			(footprints allowed)
		)
		(placement
			(enabled no)
			(sheetname "")
		)
		(fill yes
			(thermal_gap 0.5)
			(thermal_bridge_width 0.5)
			(island_removal_mode 0)
		)
		(polygon
			(pts
				(arc
					(start 450.4182 -251.735082)
					(mid 449.7578 -251.735082)
					(end 450.4182 -251.735082)
				)
			)
		)
	)
	(zone
		(layers "In1.Cu" "In2.Cu")
		(hatch none 0.5)
		(connect_pads
			(clearance 0)
		)
		(min_thickness 0.25)
		(keepout
			(tracks not_allowed)
			(vias allowed)
			(pads allowed)
			(copperpour not_allowed)
			(footprints allowed)
		)
		(placement
			(enabled no)
			(sheetname "")
		)
		(fill yes
			(thermal_gap 0.5)
			(thermal_bridge_width 0.5)
			(island_removal_mode 0)
		)
		(polygon
			(pts
				(arc
					(start 280.966164 -244.934994)
					(mid 280.305764 -244.934994)
					(end 280.966164 -244.934994)
				)
			)
		)
	)
	(zone
		(layers "In1.Cu" "In2.Cu")
		(hatch none 0.5)
		(connect_pads
			(clearance 0)
		)
		(min_thickness 0.25)
		(keepout
			(tracks not_allowed)
			(vias allowed)
			(pads allowed)
			(copperpour not_allowed)
			(footprints allowed)
		)
		(placement
			(enabled no)
			(sheetname "")
		)
		(fill yes
			(thermal_gap 0.5)
			(thermal_bridge_width 0.5)
			(island_removal_mode 0)
		)
		(polygon
			(pts
				(arc
					(start 427.786292 -227.935028)
					(mid 427.125892 -227.935028)
					(end 427.786292 -227.935028)
				)
			)
		)
	)
	(zone
		(layers "In1.Cu" "In2.Cu")
		(hatch none 0.5)
		(connect_pads
			(clearance 0)
		)
		(min_thickness 0.25)
		(keepout
			(tracks not_allowed)
			(vias allowed)
			(pads allowed)
			(copperpour not_allowed)
			(footprints allowed)
		)
		(placement
			(enabled no)
			(sheetname "")
		)
		(fill yes
			(thermal_gap 0.5)
			(thermal_bridge_width 0.5)
			(island_removal_mode 0)
		)
		(polygon
			(pts
				(arc
					(start 442.8744 -244.934994)
					(mid 442.214 -244.934994)
					(end 442.8744 -244.934994)
				)
			)
		)
	)
	(zone
		(layers "In1.Cu" "In2.Cu")
		(hatch none 0.5)
		(connect_pads
			(clearance 0)
		)
		(min_thickness 0.25)
		(keepout
			(tracks not_allowed)
			(vias allowed)
			(pads allowed)
			(copperpour not_allowed)
			(footprints allowed)
		)
		(placement
			(enabled no)
			(sheetname "")
		)
		(fill yes
			(thermal_gap 0.5)
			(thermal_bridge_width 0.5)
			(island_removal_mode 0)
		)
		(polygon
			(pts
				(arc
					(start 17.938242 -233.885232)
					(mid 17.277842 -233.885232)
					(end 17.938242 -233.885232)
				)
			)
		)
	)
	(zone
		(layers "In1.Cu" "In2.Cu")
		(hatch none 0.5)
		(connect_pads
			(clearance 0)
		)
		(min_thickness 0.25)
		(keepout
			(tracks not_allowed)
			(vias allowed)
			(pads allowed)
			(copperpour not_allowed)
			(footprints allowed)
		)
		(placement
			(enabled no)
			(sheetname "")
		)
		(fill yes
			(thermal_gap 0.5)
			(thermal_bridge_width 0.5)
			(island_removal_mode 0)
		)
		(polygon
			(pts
				(arc
					(start 296.054272 -209.23504)
					(mid 295.393872 -209.23504)
					(end 296.054272 -209.23504)
				)
			)
		)
	)
	(zone
		(layers "In1.Cu" "In2.Cu")
		(hatch none 0.5)
		(connect_pads
			(clearance 0)
		)
		(min_thickness 0.25)
		(keepout
			(tracks not_allowed)
			(vias allowed)
			(pads allowed)
			(copperpour not_allowed)
			(footprints allowed)
		)
		(placement
			(enabled no)
			(sheetname "")
		)
		(fill yes
			(thermal_gap 0.5)
			(thermal_bridge_width 0.5)
			(island_removal_mode 0)
		)
		(polygon
			(pts
				(arc
					(start 454.518268 -244.08511)
					(mid 453.857868 -244.08511)
					(end 454.518268 -244.08511)
				)
			)
		)
	)
	(zone
		(layers "In1.Cu" "In2.Cu")
		(hatch none 0.5)
		(connect_pads
			(clearance 0)
		)
		(min_thickness 0.25)
		(keepout
			(tracks not_allowed)
			(vias allowed)
			(pads allowed)
			(copperpour not_allowed)
			(footprints allowed)
		)
		(placement
			(enabled no)
			(sheetname "")
		)
		(fill yes
			(thermal_gap 0.5)
			(thermal_bridge_width 0.5)
			(island_removal_mode 0)
		)
		(polygon
			(pts
				(arc
					(start 454.518268 -231.335072)
					(mid 453.857868 -231.335072)
					(end 454.518268 -231.335072)
				)
			)
		)
	)
	(zone
		(layers "In1.Cu" "In2.Cu")
		(hatch none 0.5)
		(connect_pads
			(clearance 0)
		)
		(min_thickness 0.25)
		(keepout
			(tracks not_allowed)
			(vias allowed)
			(pads allowed)
			(copperpour not_allowed)
			(footprints allowed)
		)
		(placement
			(enabled no)
			(sheetname "")
		)
		(fill yes
			(thermal_gap 0.5)
			(thermal_bridge_width 0.5)
			(island_removal_mode 0)
		)
		(polygon
			(pts
				(arc
					(start 285.066232 -262.785098)
					(mid 284.405832 -262.785098)
					(end 285.066232 -262.785098)
				)
			)
		)
	)
	(zone
		(layers "In1.Cu" "In2.Cu")
		(hatch none 0.5)
		(connect_pads
			(clearance 0)
		)
		(min_thickness 0.25)
		(keepout
			(tracks not_allowed)
			(vias allowed)
			(pads allowed)
			(copperpour not_allowed)
			(footprints allowed)
		)
		(placement
			(enabled no)
			(sheetname "")
		)
		(fill yes
			(thermal_gap 0.5)
			(thermal_bridge_width 0.5)
			(island_removal_mode 0)
		)
		(polygon
			(pts
				(arc
					(start 439.430414 -287.435036)
					(mid 438.770014 -287.435036)
					(end 439.430414 -287.435036)
				)
			)
		)
	)
	(zone
		(layers "In1.Cu" "In2.Cu")
		(hatch none 0.5)
		(connect_pads
			(clearance 0)
		)
		(min_thickness 0.25)
		(keepout
			(tracks not_allowed)
			(vias allowed)
			(pads allowed)
			(copperpour not_allowed)
			(footprints allowed)
		)
		(placement
			(enabled no)
			(sheetname "")
		)
		(fill yes
			(thermal_gap 0.5)
			(thermal_bridge_width 0.5)
			(island_removal_mode 0)
		)
		(polygon
			(pts
				(arc
					(start 29.582364 -200.735438)
					(mid 28.921964 -200.735438)
					(end 29.582364 -200.735438)
				)
			)
		)
	)
	(zone
		(layers "In1.Cu" "In2.Cu")
		(hatch none 0.5)
		(connect_pads
			(clearance 0)
		)
		(min_thickness 0.25)
		(keepout
			(tracks not_allowed)
			(vias allowed)
			(pads allowed)
			(copperpour not_allowed)
			(footprints allowed)
		)
		(placement
			(enabled no)
			(sheetname "")
		)
		(fill yes
			(thermal_gap 0.5)
			(thermal_bridge_width 0.5)
			(island_removal_mode 0)
		)
		(polygon
			(pts
				(arc
					(start 29.582364 -273.835368)
					(mid 28.921964 -273.835368)
					(end 29.582364 -273.835368)
				)
			)
		)
	)
	(zone
		(layers "In1.Cu" "In2.Cu")
		(hatch none 0.5)
		(connect_pads
			(clearance 0)
		)
		(min_thickness 0.25)
		(keepout
			(tracks not_allowed)
			(vias allowed)
			(pads allowed)
			(copperpour not_allowed)
			(footprints allowed)
		)
		(placement
			(enabled no)
			(sheetname "")
		)
		(fill yes
			(thermal_gap 0.5)
			(thermal_bridge_width 0.5)
			(island_removal_mode 0)
		)
		(polygon
			(pts
				(arc
					(start 199.0344 -281.48534)
					(mid 198.374 -281.48534)
					(end 199.0344 -281.48534)
				)
			)
		)
	)
	(zone
		(layers "In1.Cu" "In2.Cu")
		(hatch none 0.5)
		(connect_pads
			(clearance 0)
		)
		(min_thickness 0.25)
		(keepout
			(tracks not_allowed)
			(vias allowed)
			(pads allowed)
			(copperpour not_allowed)
			(footprints allowed)
		)
		(placement
			(enabled no)
			(sheetname "")
		)
		(fill yes
			(thermal_gap 0.5)
			(thermal_bridge_width 0.5)
			(island_removal_mode 0)
		)
		(polygon
			(pts
				(arc
					(start 176.402238 -303.585372)
					(mid 175.741838 -303.585372)
					(end 176.402238 -303.585372)
				)
			)
		)
	)
	(zone
		(layers "In1.Cu" "In2.Cu")
		(hatch none 0.5)
		(connect_pads
			(clearance 0)
		)
		(min_thickness 0.25)
		(keepout
			(tracks not_allowed)
			(vias allowed)
			(pads allowed)
			(copperpour not_allowed)
			(footprints allowed)
		)
		(placement
			(enabled no)
			(sheetname "")
		)
		(fill yes
			(thermal_gap 0.5)
			(thermal_bridge_width 0.5)
			(island_removal_mode 0)
		)
		(polygon
			(pts
				(arc
					(start 179.846224 -253.435358)
					(mid 179.185824 -253.435358)
					(end 179.846224 -253.435358)
				)
			)
		)
	)
	(zone
		(layers "In1.Cu" "In2.Cu")
		(hatch none 0.5)
		(connect_pads
			(clearance 0)
		)
		(min_thickness 0.25)
		(keepout
			(tracks not_allowed)
			(vias allowed)
			(pads allowed)
			(copperpour not_allowed)
			(footprints allowed)
		)
		(placement
			(enabled no)
			(sheetname "")
		)
		(fill yes
			(thermal_gap 0.5)
			(thermal_bridge_width 0.5)
			(island_removal_mode 0)
		)
		(polygon
			(pts
				(arc
					(start 450.4182 -253.435104)
					(mid 449.7578 -253.435104)
					(end 450.4182 -253.435104)
				)
			)
		)
	)
	(zone
		(layers "In1.Cu" "In2.Cu")
		(hatch none 0.5)
		(connect_pads
			(clearance 0)
		)
		(min_thickness 0.25)
		(keepout
			(tracks not_allowed)
			(vias allowed)
			(pads allowed)
			(copperpour not_allowed)
			(footprints allowed)
		)
		(placement
			(enabled no)
			(sheetname "")
		)
		(fill yes
			(thermal_gap 0.5)
			(thermal_bridge_width 0.5)
			(island_removal_mode 0)
		)
		(polygon
			(pts
				(arc
					(start 269.978378 -262.785098)
					(mid 269.317978 -262.785098)
					(end 269.978378 -262.785098)
				)
			)
		)
	)
	(zone
		(layers "In1.Cu" "In2.Cu")
		(hatch none 0.5)
		(connect_pads
			(clearance 0)
		)
		(min_thickness 0.25)
		(keepout
			(tracks not_allowed)
			(vias allowed)
			(pads allowed)
			(copperpour not_allowed)
			(footprints allowed)
		)
		(placement
			(enabled no)
			(sheetname "")
		)
		(fill yes
			(thermal_gap 0.5)
			(thermal_bridge_width 0.5)
			(island_removal_mode 0)
		)
		(polygon
			(pts
				(arc
					(start 285.066232 -270.43507)
					(mid 284.405832 -270.43507)
					(end 285.066232 -270.43507)
				)
			)
		)
	)
	(zone
		(layers "In1.Cu" "In2.Cu")
		(hatch none 0.5)
		(connect_pads
			(clearance 0)
		)
		(min_thickness 0.25)
		(keepout
			(tracks not_allowed)
			(vias allowed)
			(pads allowed)
			(copperpour not_allowed)
			(footprints allowed)
		)
		(placement
			(enabled no)
			(sheetname "")
		)
		(fill yes
			(thermal_gap 0.5)
			(thermal_bridge_width 0.5)
			(island_removal_mode 0)
		)
		(polygon
			(pts
				(arc
					(start 179.846224 -286.585406)
					(mid 179.185824 -286.585406)
					(end 179.846224 -286.585406)
				)
			)
		)
	)
	(zone
		(layers "In1.Cu" "In2.Cu")
		(hatch none 0.5)
		(connect_pads
			(clearance 0)
		)
		(min_thickness 0.25)
		(keepout
			(tracks not_allowed)
			(vias allowed)
			(pads allowed)
			(copperpour not_allowed)
			(footprints allowed)
		)
		(placement
			(enabled no)
			(sheetname "")
		)
		(fill yes
			(thermal_gap 0.5)
			(thermal_bridge_width 0.5)
			(island_removal_mode 0)
		)
		(polygon
			(pts
				(arc
					(start 48.114204 -198.185278)
					(mid 47.453804 -198.185278)
					(end 48.114204 -198.185278)
				)
			)
		)
	)
	(zone
		(layers "In1.Cu" "In2.Cu")
		(hatch none 0.5)
		(connect_pads
			(clearance 0)
		)
		(min_thickness 0.25)
		(keepout
			(tracks not_allowed)
			(vias allowed)
			(pads allowed)
			(copperpour not_allowed)
			(footprints allowed)
		)
		(placement
			(enabled no)
			(sheetname "")
		)
		(fill yes
			(thermal_gap 0.5)
			(thermal_bridge_width 0.5)
			(island_removal_mode 0)
		)
		(polygon
			(pts
				(arc
					(start 411.32379 -384.288284)
					(mid 411.343714 -384.29752)
					(end 411.365446 -384.30073)
				)
				(arc
					(start 411.56001 -384.30073)
					(mid 411.613892 -384.278412)
					(end 411.63621 -384.22453)
				)
				(arc
					(start 411.63621 -383.53873)
					(mid 411.613892 -383.484848)
					(end 411.56001 -383.46253)
				)
				(arc
					(start 411.365446 -383.46253)
					(mid 411.343702 -383.465698)
					(end 411.32379 -383.474976)
				)
				(arc
					(start 411.027626 -383.667762)
					(mid 410.985942 -383.679984)
					(end 410.944314 -383.667508)
				)
				(arc
					(start 410.65069 -383.474976)
					(mid 410.630766 -383.46574)
					(end 410.609034 -383.46253)
				)
				(arc
					(start 410.41447 -383.46253)
					(mid 410.360588 -383.484848)
					(end 410.33827 -383.53873)
				)
				(arc
					(start 410.33827 -384.22453)
					(mid 410.360588 -384.278412)
					(end 410.41447 -384.30073)
				)
				(arc
					(start 410.610304 -384.30073)
					(mid 410.632048 -384.297562)
					(end 410.65196 -384.288284)
				)
				(arc
					(start 410.945584 -384.095752)
					(mid 410.98724 -384.08335)
					(end 411.028896 -384.095752)
				)
			)
		)
	)
	(zone
		(layers "In1.Cu" "In2.Cu")
		(hatch none 0.5)
		(connect_pads
			(clearance 0)
		)
		(min_thickness 0.25)
		(keepout
			(tracks not_allowed)
			(vias allowed)
			(pads allowed)
			(copperpour not_allowed)
			(footprints allowed)
		)
		(placement
			(enabled no)
			(sheetname "")
		)
		(fill yes
			(thermal_gap 0.5)
			(thermal_bridge_width 0.5)
			(island_removal_mode 0)
		)
		(polygon
			(pts
				(arc
					(start 389.006842 -379.360684)
					(mid 389.026766 -379.36992)
					(end 389.048498 -379.37313)
				)
				(arc
					(start 389.243062 -379.37313)
					(mid 389.296944 -379.350812)
					(end 389.319262 -379.29693)
				)
				(arc
					(start 389.319262 -378.61113)
					(mid 389.296944 -378.557248)
					(end 389.243062 -378.53493)
				)
				(arc
					(start 389.048498 -378.53493)
					(mid 389.026754 -378.538098)
					(end 389.006842 -378.547376)
				)
				(arc
					(start 388.710678 -378.740162)
					(mid 388.668994 -378.752384)
					(end 388.627366 -378.739908)
				)
				(arc
					(start 388.333742 -378.547376)
					(mid 388.313818 -378.53814)
					(end 388.292086 -378.53493)
				)
				(arc
					(start 388.097522 -378.53493)
					(mid 388.04364 -378.557248)
					(end 388.021322 -378.61113)
				)
				(arc
					(start 388.021322 -379.29693)
					(mid 388.04364 -379.350812)
					(end 388.097522 -379.37313)
				)
				(arc
					(start 388.293356 -379.37313)
					(mid 388.3151 -379.369962)
					(end 388.335012 -379.360684)
				)
				(arc
					(start 388.628636 -379.168152)
					(mid 388.670292 -379.15575)
					(end 388.711948 -379.168152)
				)
			)
		)
	)
	(zone
		(layers "In1.Cu" "In2.Cu")
		(hatch none 0.5)
		(connect_pads
			(clearance 0)
		)
		(min_thickness 0.25)
		(keepout
			(tracks not_allowed)
			(vias allowed)
			(pads allowed)
			(copperpour not_allowed)
			(footprints allowed)
		)
		(placement
			(enabled no)
			(sheetname "")
		)
		(fill yes
			(thermal_gap 0.5)
			(thermal_bridge_width 0.5)
			(island_removal_mode 0)
		)
		(polygon
			(pts
				(arc
					(start 202.478132 -239.835436)
					(mid 201.817732 -239.835436)
					(end 202.478132 -239.835436)
				)
			)
		)
	)
	(zone
		(layers "In1.Cu" "In2.Cu")
		(hatch none 0.5)
		(connect_pads
			(clearance 0)
		)
		(min_thickness 0.25)
		(keepout
			(tracks not_allowed)
			(vias allowed)
			(pads allowed)
			(copperpour not_allowed)
			(footprints allowed)
		)
		(placement
			(enabled no)
			(sheetname "")
		)
		(fill yes
			(thermal_gap 0.5)
			(thermal_bridge_width 0.5)
			(island_removal_mode 0)
		)
		(polygon
			(pts
				(arc
					(start 25.482296 -297.635422)
					(mid 24.821896 -297.635422)
					(end 25.482296 -297.635422)
				)
			)
		)
	)
	(zone
		(layers "In1.Cu" "In2.Cu")
		(hatch none 0.5)
		(connect_pads
			(clearance 0)
		)
		(min_thickness 0.25)
		(keepout
			(tracks not_allowed)
			(vias allowed)
			(pads allowed)
			(copperpour not_allowed)
			(footprints allowed)
		)
		(placement
			(enabled no)
			(sheetname "")
		)
		(fill yes
			(thermal_gap 0.5)
			(thermal_bridge_width 0.5)
			(island_removal_mode 0)
		)
		(polygon
			(pts
				(arc
					(start 292.610286 -275.535136)
					(mid 291.949886 -275.535136)
					(end 292.610286 -275.535136)
				)
			)
		)
	)
	(zone
		(layers "In1.Cu" "In2.Cu")
		(hatch none 0.5)
		(connect_pads
			(clearance 0)
		)
		(min_thickness 0.25)
		(keepout
			(tracks not_allowed)
			(vias allowed)
			(pads allowed)
			(copperpour not_allowed)
			(footprints allowed)
		)
		(placement
			(enabled no)
			(sheetname "")
		)
		(fill yes
			(thermal_gap 0.5)
			(thermal_bridge_width 0.5)
			(island_removal_mode 0)
		)
		(polygon
			(pts
				(arc
					(start 187.390278 -254.285242)
					(mid 186.729878 -254.285242)
					(end 187.390278 -254.285242)
				)
			)
		)
	)
	(zone
		(layers "In1.Cu" "In2.Cu")
		(hatch none 0.5)
		(connect_pads
			(clearance 0)
		)
		(min_thickness 0.25)
		(keepout
			(tracks not_allowed)
			(vias allowed)
			(pads allowed)
			(copperpour not_allowed)
			(footprints allowed)
		)
		(placement
			(enabled no)
			(sheetname "")
		)
		(fill yes
			(thermal_gap 0.5)
			(thermal_bridge_width 0.5)
			(island_removal_mode 0)
		)
		(polygon
			(pts
				(arc
					(start 191.490346 -269.58544)
					(mid 190.829946 -269.58544)
					(end 191.490346 -269.58544)
				)
			)
		)
	)
	(zone
		(layers "In1.Cu" "In2.Cu")
		(hatch none 0.5)
		(connect_pads
			(clearance 0)
		)
		(min_thickness 0.25)
		(keepout
			(tracks not_allowed)
			(vias allowed)
			(pads allowed)
			(copperpour not_allowed)
			(footprints allowed)
		)
		(placement
			(enabled no)
			(sheetname "")
		)
		(fill yes
			(thermal_gap 0.5)
			(thermal_bridge_width 0.5)
			(island_removal_mode 0)
		)
		(polygon
			(pts
				(arc
					(start 176.402238 -216.035382)
					(mid 175.741838 -216.035382)
					(end 176.402238 -216.035382)
				)
			)
		)
	)
	(zone
		(layers "In1.Cu" "In2.Cu")
		(hatch none 0.5)
		(connect_pads
			(clearance 0)
		)
		(min_thickness 0.25)
		(keepout
			(tracks not_allowed)
			(vias allowed)
			(pads allowed)
			(copperpour not_allowed)
			(footprints allowed)
		)
		(placement
			(enabled no)
			(sheetname "")
		)
		(fill yes
			(thermal_gap 0.5)
			(thermal_bridge_width 0.5)
			(island_removal_mode 0)
		)
		(polygon
			(pts
				(arc
					(start 199.0344 -306.135278)
					(mid 198.374 -306.135278)
					(end 199.0344 -306.135278)
				)
			)
		)
	)
	(zone
		(layers "In1.Cu" "In2.Cu")
		(hatch none 0.5)
		(connect_pads
			(clearance 0)
		)
		(min_thickness 0.25)
		(keepout
			(tracks not_allowed)
			(vias allowed)
			(pads allowed)
			(copperpour not_allowed)
			(footprints allowed)
		)
		(placement
			(enabled no)
			(sheetname "")
		)
		(fill yes
			(thermal_gap 0.5)
			(thermal_bridge_width 0.5)
			(island_removal_mode 0)
		)
		(polygon
			(pts
				(arc
					(start 40.57015 -229.635304)
					(mid 39.90975 -229.635304)
					(end 40.57015 -229.635304)
				)
			)
		)
	)
	(zone
		(layers "In1.Cu" "In2.Cu")
		(hatch none 0.5)
		(connect_pads
			(clearance 0)
		)
		(min_thickness 0.25)
		(keepout
			(tracks not_allowed)
			(vias allowed)
			(pads allowed)
			(copperpour not_allowed)
			(footprints allowed)
		)
		(placement
			(enabled no)
			(sheetname "")
		)
		(fill yes
			(thermal_gap 0.5)
			(thermal_bridge_width 0.5)
			(island_removal_mode 0)
		)
		(polygon
			(pts
				(arc
					(start 22.03831 -281.48534)
					(mid 21.37791 -281.48534)
					(end 22.03831 -281.48534)
				)
			)
		)
	)
	(zone
		(layers "In1.Cu" "In2.Cu")
		(hatch none 0.5)
		(connect_pads
			(clearance 0)
		)
		(min_thickness 0.25)
		(keepout
			(tracks not_allowed)
			(vias allowed)
			(pads allowed)
			(copperpour not_allowed)
			(footprints allowed)
		)
		(placement
			(enabled no)
			(sheetname "")
		)
		(fill yes
			(thermal_gap 0.5)
			(thermal_bridge_width 0.5)
			(island_removal_mode 0)
		)
		(polygon
			(pts
				(arc
					(start 142.188438 -382.27381)
					(mid 142.179202 -382.293734)
					(end 142.175992 -382.315466)
				)
				(arc
					(start 142.175992 -382.51003)
					(mid 142.19831 -382.563912)
					(end 142.252192 -382.58623)
				)
				(arc
					(start 142.937992 -382.58623)
					(mid 142.991874 -382.563912)
					(end 143.014192 -382.51003)
				)
				(arc
					(start 143.014192 -382.315466)
					(mid 143.011024 -382.293722)
					(end 143.001746 -382.27381)
				)
				(arc
					(start 142.80896 -381.977646)
					(mid 142.796738 -381.935962)
					(end 142.809214 -381.894334)
				)
				(arc
					(start 143.001746 -381.60071)
					(mid 143.010982 -381.580786)
					(end 143.014192 -381.559054)
				)
				(arc
					(start 143.014192 -381.36449)
					(mid 142.991874 -381.310608)
					(end 142.937992 -381.28829)
				)
				(arc
					(start 142.252192 -381.28829)
					(mid 142.19831 -381.310608)
					(end 142.175992 -381.36449)
				)
				(arc
					(start 142.175992 -381.560324)
					(mid 142.17916 -381.582068)
					(end 142.188438 -381.60198)
				)
				(arc
					(start 142.38097 -381.895604)
					(mid 142.393372 -381.93726)
					(end 142.38097 -381.978916)
				)
			)
		)
	)
	(zone
		(layers "In1.Cu" "In2.Cu")
		(hatch none 0.5)
		(connect_pads
			(clearance 0)
		)
		(min_thickness 0.25)
		(keepout
			(tracks not_allowed)
			(vias allowed)
			(pads allowed)
			(copperpour not_allowed)
			(footprints allowed)
		)
		(placement
			(enabled no)
			(sheetname "")
		)
		(fill yes
			(thermal_gap 0.5)
			(thermal_bridge_width 0.5)
			(island_removal_mode 0)
		)
		(polygon
			(pts
				(arc
					(start 280.966164 -251.735082)
					(mid 280.305764 -251.735082)
					(end 280.966164 -251.735082)
				)
			)
		)
	)
	(zone
		(layers "In1.Cu" "In2.Cu")
		(hatch none 0.5)
		(connect_pads
			(clearance 0)
		)
		(min_thickness 0.25)
		(keepout
			(tracks not_allowed)
			(vias allowed)
			(pads allowed)
			(copperpour not_allowed)
			(footprints allowed)
		)
		(placement
			(enabled no)
			(sheetname "")
		)
		(fill yes
			(thermal_gap 0.5)
			(thermal_bridge_width 0.5)
			(island_removal_mode 0)
		)
		(polygon
			(pts
				(arc
					(start 17.938242 -254.285242)
					(mid 17.277842 -254.285242)
					(end 17.938242 -254.285242)
				)
			)
		)
	)
	(zone
		(layers "In1.Cu" "In2.Cu")
		(hatch none 0.5)
		(connect_pads
			(clearance 0)
		)
		(min_thickness 0.25)
		(keepout
			(tracks not_allowed)
			(vias allowed)
			(pads allowed)
			(copperpour not_allowed)
			(footprints allowed)
		)
		(placement
			(enabled no)
			(sheetname "")
		)
		(fill yes
			(thermal_gap 0.5)
			(thermal_bridge_width 0.5)
			(island_removal_mode 0)
		)
		(polygon
			(pts
				(arc
					(start 124.497846 -373.442484)
					(mid 124.51777 -373.45172)
					(end 124.539502 -373.45493)
				)
				(arc
					(start 124.734066 -373.45493)
					(mid 124.787948 -373.432612)
					(end 124.810266 -373.37873)
				)
				(arc
					(start 124.810266 -372.69293)
					(mid 124.787948 -372.639048)
					(end 124.734066 -372.61673)
				)
				(arc
					(start 124.539502 -372.61673)
					(mid 124.517758 -372.619898)
					(end 124.497846 -372.629176)
				)
				(arc
					(start 124.201682 -372.821962)
					(mid 124.159998 -372.834184)
					(end 124.11837 -372.821708)
				)
				(arc
					(start 123.824746 -372.629176)
					(mid 123.804822 -372.61994)
					(end 123.78309 -372.61673)
				)
				(arc
					(start 123.588526 -372.61673)
					(mid 123.534644 -372.639048)
					(end 123.512326 -372.69293)
				)
				(arc
					(start 123.512326 -373.37873)
					(mid 123.534644 -373.432612)
					(end 123.588526 -373.45493)
				)
				(arc
					(start 123.78436 -373.45493)
					(mid 123.806104 -373.451762)
					(end 123.826016 -373.442484)
				)
				(arc
					(start 124.11964 -373.249952)
					(mid 124.161296 -373.23755)
					(end 124.202952 -373.249952)
				)
			)
		)
	)
	(zone
		(layers "In1.Cu" "In2.Cu")
		(hatch none 0.5)
		(connect_pads
			(clearance 0)
		)
		(min_thickness 0.25)
		(keepout
			(tracks not_allowed)
			(vias allowed)
			(pads allowed)
			(copperpour not_allowed)
			(footprints allowed)
		)
		(placement
			(enabled no)
			(sheetname "")
		)
		(fill yes
			(thermal_gap 0.5)
			(thermal_bridge_width 0.5)
			(island_removal_mode 0)
		)
		(polygon
			(pts
				(arc
					(start 420.242238 -297.635168)
					(mid 419.581838 -297.635168)
					(end 420.242238 -297.635168)
				)
			)
		)
	)
	(zone
		(layers "In1.Cu" "In2.Cu")
		(hatch none 0.5)
		(connect_pads
			(clearance 0)
		)
		(min_thickness 0.25)
		(keepout
			(tracks not_allowed)
			(vias allowed)
			(pads allowed)
			(copperpour not_allowed)
			(footprints allowed)
		)
		(placement
			(enabled no)
			(sheetname "")
		)
		(fill yes
			(thermal_gap 0.5)
			(thermal_bridge_width 0.5)
			(island_removal_mode 0)
		)
		(polygon
			(pts
				(arc
					(start 40.57015 -216.885266)
					(mid 39.90975 -216.885266)
					(end 40.57015 -216.885266)
				)
			)
		)
	)
	(zone
		(layers "In1.Cu" "In2.Cu")
		(hatch none 0.5)
		(connect_pads
			(clearance 0)
		)
		(min_thickness 0.25)
		(keepout
			(tracks not_allowed)
			(vias allowed)
			(pads allowed)
			(copperpour not_allowed)
			(footprints allowed)
		)
		(placement
			(enabled no)
			(sheetname "")
		)
		(fill yes
			(thermal_gap 0.5)
			(thermal_bridge_width 0.5)
			(island_removal_mode 0)
		)
		(polygon
			(pts
				(arc
					(start 296.054272 -276.38502)
					(mid 295.393872 -276.38502)
					(end 296.054272 -276.38502)
				)
			)
		)
	)
	(zone
		(layers "In1.Cu" "In2.Cu")
		(hatch none 0.5)
		(connect_pads
			(clearance 0)
		)
		(min_thickness 0.25)
		(keepout
			(tracks not_allowed)
			(vias allowed)
			(pads allowed)
			(copperpour not_allowed)
			(footprints allowed)
		)
		(placement
			(enabled no)
			(sheetname "")
		)
		(fill yes
			(thermal_gap 0.5)
			(thermal_bridge_width 0.5)
			(island_removal_mode 0)
		)
		(polygon
			(pts
				(arc
					(start 176.402238 -266.185396)
					(mid 175.741838 -266.185396)
					(end 176.402238 -266.185396)
				)
			)
		)
	)
	(zone
		(layers "In1.Cu" "In2.Cu")
		(hatch none 0.5)
		(connect_pads
			(clearance 0)
		)
		(min_thickness 0.25)
		(keepout
			(tracks not_allowed)
			(vias allowed)
			(pads allowed)
			(copperpour not_allowed)
			(footprints allowed)
		)
		(placement
			(enabled no)
			(sheetname "")
		)
		(fill yes
			(thermal_gap 0.5)
			(thermal_bridge_width 0.5)
			(island_removal_mode 0)
		)
		(polygon
			(pts
				(arc
					(start 48.114204 -237.285276)
					(mid 47.453804 -237.285276)
					(end 48.114204 -237.285276)
				)
			)
		)
	)
	(zone
		(layers "In1.Cu" "In2.Cu")
		(hatch none 0.5)
		(connect_pads
			(clearance 0)
		)
		(min_thickness 0.25)
		(keepout
			(tracks not_allowed)
			(vias allowed)
			(pads allowed)
			(copperpour not_allowed)
			(footprints allowed)
		)
		(placement
			(enabled no)
			(sheetname "")
		)
		(fill yes
			(thermal_gap 0.5)
			(thermal_bridge_width 0.5)
			(island_removal_mode 0)
		)
		(polygon
			(pts
				(arc
					(start 194.934332 -205.83525)
					(mid 194.273932 -205.83525)
					(end 194.934332 -205.83525)
				)
			)
		)
	)
	(zone
		(layers "In1.Cu" "In2.Cu")
		(hatch none 0.5)
		(connect_pads
			(clearance 0)
		)
		(min_thickness 0.25)
		(keepout
			(tracks not_allowed)
			(vias allowed)
			(pads allowed)
			(copperpour not_allowed)
			(footprints allowed)
		)
		(placement
			(enabled no)
			(sheetname "")
		)
		(fill yes
			(thermal_gap 0.5)
			(thermal_bridge_width 0.5)
			(island_removal_mode 0)
		)
		(polygon
			(pts
				(arc
					(start 44.670218 -306.135278)
					(mid 44.009818 -306.135278)
					(end 44.670218 -306.135278)
				)
			)
		)
	)
	(zone
		(layers "In1.Cu" "In2.Cu")
		(hatch none 0.5)
		(connect_pads
			(clearance 0)
		)
		(min_thickness 0.25)
		(keepout
			(tracks not_allowed)
			(vias allowed)
			(pads allowed)
			(copperpour not_allowed)
			(footprints allowed)
		)
		(placement
			(enabled no)
			(sheetname "")
		)
		(fill yes
			(thermal_gap 0.5)
			(thermal_bridge_width 0.5)
			(island_removal_mode 0)
		)
		(polygon
			(pts
				(arc
					(start 288.510218 -222.834962)
					(mid 287.849818 -222.834962)
					(end 288.510218 -222.834962)
				)
			)
		)
	)
	(zone
		(layers "In1.Cu" "In2.Cu")
		(hatch none 0.5)
		(connect_pads
			(clearance 0)
		)
		(min_thickness 0.25)
		(keepout
			(tracks not_allowed)
			(vias allowed)
			(pads allowed)
			(copperpour not_allowed)
			(footprints allowed)
		)
		(placement
			(enabled no)
			(sheetname "")
		)
		(fill yes
			(thermal_gap 0.5)
			(thermal_bridge_width 0.5)
			(island_removal_mode 0)
		)
		(polygon
			(pts
				(arc
					(start 424.342306 -275.535136)
					(mid 423.681906 -275.535136)
					(end 424.342306 -275.535136)
				)
			)
		)
	)
	(zone
		(layers "In1.Cu" "In2.Cu")
		(hatch none 0.5)
		(connect_pads
			(clearance 0)
		)
		(min_thickness 0.25)
		(keepout
			(tracks not_allowed)
			(vias allowed)
			(pads allowed)
			(copperpour not_allowed)
			(footprints allowed)
		)
		(placement
			(enabled no)
			(sheetname "")
		)
		(fill yes
			(thermal_gap 0.5)
			(thermal_bridge_width 0.5)
			(island_removal_mode 0)
		)
		(polygon
			(pts
				(arc
					(start 176.402238 -311.235344)
					(mid 175.741838 -311.235344)
					(end 176.402238 -311.235344)
				)
			)
		)
	)
	(zone
		(layers "In1.Cu" "In2.Cu")
		(hatch none 0.5)
		(connect_pads
			(clearance 0)
		)
		(min_thickness 0.25)
		(keepout
			(tracks not_allowed)
			(vias allowed)
			(pads allowed)
			(copperpour not_allowed)
			(footprints allowed)
		)
		(placement
			(enabled no)
			(sheetname "")
		)
		(fill yes
			(thermal_gap 0.5)
			(thermal_bridge_width 0.5)
			(island_removal_mode 0)
		)
		(polygon
			(pts
				(arc
					(start 37.126164 -221.985332)
					(mid 36.465764 -221.985332)
					(end 37.126164 -221.985332)
				)
			)
		)
	)
	(zone
		(layers "In1.Cu" "In2.Cu")
		(hatch none 0.5)
		(connect_pads
			(clearance 0)
		)
		(min_thickness 0.25)
		(keepout
			(tracks not_allowed)
			(vias allowed)
			(pads allowed)
			(copperpour not_allowed)
			(footprints allowed)
		)
		(placement
			(enabled no)
			(sheetname "")
		)
		(fill yes
			(thermal_gap 0.5)
			(thermal_bridge_width 0.5)
			(island_removal_mode 0)
		)
		(polygon
			(pts
				(arc
					(start 418.051488 -11.91768)
					(mid 418.02917 -11.971562)
					(end 417.975288 -11.99388)
				)
				(arc
					(start 416.938714 -11.99388)
					(mid 416.884832 -11.971562)
					(end 416.862514 -11.91768)
				)
				(arc
					(start 416.862514 -10.51814)
					(mid 416.884832 -10.464258)
					(end 416.938714 -10.44194)
				)
				(arc
					(start 417.975288 -10.44194)
					(mid 418.02917 -10.464258)
					(end 418.051488 -10.51814)
				)
			)
		)
	)
	(zone
		(layers "In1.Cu" "In2.Cu")
		(hatch none 0.5)
		(connect_pads
			(clearance 0)
		)
		(min_thickness 0.25)
		(keepout
			(tracks not_allowed)
			(vias allowed)
			(pads allowed)
			(copperpour not_allowed)
			(footprints allowed)
		)
		(placement
			(enabled no)
			(sheetname "")
		)
		(fill yes
			(thermal_gap 0.5)
			(thermal_bridge_width 0.5)
			(island_removal_mode 0)
		)
		(polygon
			(pts
				(arc
					(start 22.03831 -206.685388)
					(mid 21.37791 -206.685388)
					(end 22.03831 -206.685388)
				)
			)
		)
	)
	(zone
		(layers "In1.Cu" "In2.Cu")
		(hatch none 0.5)
		(connect_pads
			(clearance 0)
		)
		(min_thickness 0.25)
		(keepout
			(tracks not_allowed)
			(vias allowed)
			(pads allowed)
			(copperpour not_allowed)
			(footprints allowed)
		)
		(placement
			(enabled no)
			(sheetname "")
		)
		(fill yes
			(thermal_gap 0.5)
			(thermal_bridge_width 0.5)
			(island_removal_mode 0)
		)
		(polygon
			(pts
				(arc
					(start 33.026096 -226.23526)
					(mid 32.365696 -226.23526)
					(end 33.026096 -226.23526)
				)
			)
		)
	)
	(zone
		(layers "In1.Cu" "In2.Cu")
		(hatch none 0.5)
		(connect_pads
			(clearance 0)
		)
		(min_thickness 0.25)
		(keepout
			(tracks not_allowed)
			(vias allowed)
			(pads allowed)
			(copperpour not_allowed)
			(footprints allowed)
		)
		(placement
			(enabled no)
			(sheetname "")
		)
		(fill yes
			(thermal_gap 0.5)
			(thermal_bridge_width 0.5)
			(island_removal_mode 0)
		)
		(polygon
			(pts
				(arc
					(start 300.15434 -307.835046)
					(mid 299.49394 -307.835046)
					(end 300.15434 -307.835046)
				)
			)
		)
	)
	(zone
		(layers "In1.Cu" "In2.Cu")
		(hatch none 0.5)
		(connect_pads
			(clearance 0)
		)
		(min_thickness 0.25)
		(keepout
			(tracks not_allowed)
			(vias allowed)
			(pads allowed)
			(copperpour not_allowed)
			(footprints allowed)
		)
		(placement
			(enabled no)
			(sheetname "")
		)
		(fill yes
			(thermal_gap 0.5)
			(thermal_bridge_width 0.5)
			(island_removal_mode 0)
		)
		(polygon
			(pts
				(arc
					(start 420.242238 -302.73498)
					(mid 419.581838 -302.73498)
					(end 420.242238 -302.73498)
				)
			)
		)
	)
	(zone
		(layers "In1.Cu" "In2.Cu")
		(hatch none 0.5)
		(connect_pads
			(clearance 0)
		)
		(min_thickness 0.25)
		(keepout
			(tracks not_allowed)
			(vias allowed)
			(pads allowed)
			(copperpour not_allowed)
			(footprints allowed)
		)
		(placement
			(enabled no)
			(sheetname "")
		)
		(fill yes
			(thermal_gap 0.5)
			(thermal_bridge_width 0.5)
			(island_removal_mode 0)
		)
		(polygon
			(pts
				(arc
					(start 280.966164 -235.585)
					(mid 280.305764 -235.585)
					(end 280.966164 -235.585)
				)
			)
		)
	)
	(zone
		(layers "In1.Cu" "In2.Cu")
		(hatch none 0.5)
		(connect_pads
			(clearance 0)
		)
		(min_thickness 0.25)
		(keepout
			(tracks not_allowed)
			(vias allowed)
			(pads allowed)
			(copperpour not_allowed)
			(footprints allowed)
		)
		(placement
			(enabled no)
			(sheetname "")
		)
		(fill yes
			(thermal_gap 0.5)
			(thermal_bridge_width 0.5)
			(island_removal_mode 0)
		)
		(polygon
			(pts
				(arc
					(start 439.430414 -262.785098)
					(mid 438.770014 -262.785098)
					(end 439.430414 -262.785098)
				)
			)
		)
	)
	(zone
		(layers "In1.Cu" "In2.Cu")
		(hatch none 0.5)
		(connect_pads
			(clearance 0)
		)
		(min_thickness 0.25)
		(keepout
			(tracks not_allowed)
			(vias allowed)
			(pads allowed)
			(copperpour not_allowed)
			(footprints allowed)
		)
		(placement
			(enabled no)
			(sheetname "")
		)
		(fill yes
			(thermal_gap 0.5)
			(thermal_bridge_width 0.5)
			(island_removal_mode 0)
		)
		(polygon
			(pts
				(arc
					(start 199.0344 -287.43529)
					(mid 198.374 -287.43529)
					(end 199.0344 -287.43529)
				)
			)
		)
	)
	(zone
		(layers "In1.Cu" "In2.Cu")
		(hatch none 0.5)
		(connect_pads
			(clearance 0)
		)
		(min_thickness 0.25)
		(keepout
			(tracks not_allowed)
			(vias allowed)
			(pads allowed)
			(copperpour not_allowed)
			(footprints allowed)
		)
		(placement
			(enabled no)
			(sheetname "")
		)
		(fill yes
			(thermal_gap 0.5)
			(thermal_bridge_width 0.5)
			(island_removal_mode 0)
		)
		(polygon
			(pts
				(arc
					(start 33.026096 -232.18521)
					(mid 32.365696 -232.18521)
					(end 33.026096 -232.18521)
				)
			)
		)
	)
	(zone
		(layers "In1.Cu" "In2.Cu")
		(hatch none 0.5)
		(connect_pads
			(clearance 0)
		)
		(min_thickness 0.25)
		(keepout
			(tracks not_allowed)
			(vias allowed)
			(pads allowed)
			(copperpour not_allowed)
			(footprints allowed)
		)
		(placement
			(enabled no)
			(sheetname "")
		)
		(fill yes
			(thermal_gap 0.5)
			(thermal_bridge_width 0.5)
			(island_removal_mode 0)
		)
		(polygon
			(pts
				(arc
					(start 454.518268 -240.685066)
					(mid 453.857868 -240.685066)
					(end 454.518268 -240.685066)
				)
			)
		)
	)
	(zone
		(layers "In1.Cu" "In2.Cu")
		(hatch none 0.5)
		(connect_pads
			(clearance 0)
		)
		(min_thickness 0.25)
		(keepout
			(tracks not_allowed)
			(vias allowed)
			(pads allowed)
			(copperpour not_allowed)
			(footprints allowed)
		)
		(placement
			(enabled no)
			(sheetname "")
		)
		(fill yes
			(thermal_gap 0.5)
			(thermal_bridge_width 0.5)
			(island_removal_mode 0)
		)
		(polygon
			(pts
				(arc
					(start 172.30217 -216.885266)
					(mid 171.64177 -216.885266)
					(end 172.30217 -216.885266)
				)
			)
		)
	)
	(zone
		(layers "In1.Cu" "In2.Cu")
		(hatch none 0.5)
		(connect_pads
			(clearance 0)
		)
		(min_thickness 0.25)
		(keepout
			(tracks not_allowed)
			(vias allowed)
			(pads allowed)
			(copperpour not_allowed)
			(footprints allowed)
		)
		(placement
			(enabled no)
			(sheetname "")
		)
		(fill yes
			(thermal_gap 0.5)
			(thermal_bridge_width 0.5)
			(island_removal_mode 0)
		)
		(polygon
			(pts
				(arc
					(start 37.126164 -199.035416)
					(mid 36.465764 -199.035416)
					(end 37.126164 -199.035416)
				)
			)
		)
	)
	(zone
		(layers "In1.Cu" "In2.Cu")
		(hatch none 0.5)
		(connect_pads
			(clearance 0)
		)
		(min_thickness 0.25)
		(keepout
			(tracks not_allowed)
			(vias allowed)
			(pads allowed)
			(copperpour not_allowed)
			(footprints allowed)
		)
		(placement
			(enabled no)
			(sheetname "")
		)
		(fill yes
			(thermal_gap 0.5)
			(thermal_bridge_width 0.5)
			(island_removal_mode 0)
		)
		(polygon
			(pts
				(arc
					(start 202.478132 -272.98523)
					(mid 201.817732 -272.98523)
					(end 202.478132 -272.98523)
				)
			)
		)
	)
	(zone
		(layers "In1.Cu" "In2.Cu")
		(hatch none 0.5)
		(connect_pads
			(clearance 0)
		)
		(min_thickness 0.25)
		(keepout
			(tracks not_allowed)
			(vias allowed)
			(pads allowed)
			(copperpour not_allowed)
			(footprints allowed)
		)
		(placement
			(enabled no)
			(sheetname "")
		)
		(fill yes
			(thermal_gap 0.5)
			(thermal_bridge_width 0.5)
			(island_removal_mode 0)
		)
		(polygon
			(pts
				(arc
					(start 176.402238 -264.485374)
					(mid 175.741838 -264.485374)
					(end 176.402238 -264.485374)
				)
			)
		)
	)
	(zone
		(layers "In1.Cu" "In2.Cu")
		(hatch none 0.5)
		(connect_pads
			(clearance 0)
		)
		(min_thickness 0.25)
		(keepout
			(tracks not_allowed)
			(vias allowed)
			(pads allowed)
			(copperpour not_allowed)
			(footprints allowed)
		)
		(placement
			(enabled no)
			(sheetname "")
		)
		(fill yes
			(thermal_gap 0.5)
			(thermal_bridge_width 0.5)
			(island_removal_mode 0)
		)
		(polygon
			(pts
				(arc
					(start 280.966164 -201.585068)
					(mid 280.305764 -201.585068)
					(end 280.966164 -201.585068)
				)
			)
		)
	)
	(zone
		(layers "In1.Cu" "In2.Cu")
		(hatch none 0.5)
		(connect_pads
			(clearance 0)
		)
		(min_thickness 0.25)
		(keepout
			(tracks not_allowed)
			(vias allowed)
			(pads allowed)
			(copperpour not_allowed)
			(footprints allowed)
		)
		(placement
			(enabled no)
			(sheetname "")
		)
		(fill yes
			(thermal_gap 0.5)
			(thermal_bridge_width 0.5)
			(island_removal_mode 0)
		)
		(polygon
			(pts
				(arc
					(start 450.4182 -211.784946)
					(mid 449.7578 -211.784946)
					(end 450.4182 -211.784946)
				)
			)
		)
	)
	(zone
		(layers "In1.Cu" "In2.Cu")
		(hatch none 0.5)
		(connect_pads
			(clearance 0)
		)
		(min_thickness 0.25)
		(keepout
			(tracks not_allowed)
			(vias allowed)
			(pads allowed)
			(copperpour not_allowed)
			(footprints allowed)
		)
		(placement
			(enabled no)
			(sheetname "")
		)
		(fill yes
			(thermal_gap 0.5)
			(thermal_bridge_width 0.5)
			(island_removal_mode 0)
		)
		(polygon
			(pts
				(arc
					(start 202.478132 -230.485442)
					(mid 201.817732 -230.485442)
					(end 202.478132 -230.485442)
				)
			)
		)
	)
	(zone
		(layers "In1.Cu" "In2.Cu")
		(hatch none 0.5)
		(connect_pads
			(clearance 0)
		)
		(min_thickness 0.25)
		(keepout
			(tracks not_allowed)
			(vias allowed)
			(pads allowed)
			(copperpour not_allowed)
			(footprints allowed)
		)
		(placement
			(enabled no)
			(sheetname "")
		)
		(fill yes
			(thermal_gap 0.5)
			(thermal_bridge_width 0.5)
			(island_removal_mode 0)
		)
		(polygon
			(pts
				(arc
					(start 40.57015 -250.035314)
					(mid 39.90975 -250.035314)
					(end 40.57015 -250.035314)
				)
			)
		)
	)
	(zone
		(layers "In1.Cu" "In2.Cu")
		(hatch none 0.5)
		(connect_pads
			(clearance 0)
		)
		(min_thickness 0.25)
		(keepout
			(tracks not_allowed)
			(vias allowed)
			(pads allowed)
			(copperpour not_allowed)
			(footprints allowed)
		)
		(placement
			(enabled no)
			(sheetname "")
		)
		(fill yes
			(thermal_gap 0.5)
			(thermal_bridge_width 0.5)
			(island_removal_mode 0)
		)
		(polygon
			(pts
				(arc
					(start 420.242238 -293.384986)
					(mid 419.581838 -293.384986)
					(end 420.242238 -293.384986)
				)
			)
		)
	)
	(zone
		(layers "In1.Cu" "In2.Cu")
		(hatch none 0.5)
		(connect_pads
			(clearance 0)
		)
		(min_thickness 0.25)
		(keepout
			(tracks not_allowed)
			(vias allowed)
			(pads allowed)
			(copperpour not_allowed)
			(footprints allowed)
		)
		(placement
			(enabled no)
			(sheetname "")
		)
		(fill yes
			(thermal_gap 0.5)
			(thermal_bridge_width 0.5)
			(island_removal_mode 0)
		)
		(polygon
			(pts
				(arc
					(start 202.478132 -282.335224)
					(mid 201.817732 -282.335224)
					(end 202.478132 -282.335224)
				)
			)
		)
	)
	(zone
		(layers "In1.Cu" "In2.Cu")
		(hatch none 0.5)
		(connect_pads
			(clearance 0)
		)
		(min_thickness 0.25)
		(keepout
			(tracks not_allowed)
			(vias allowed)
			(pads allowed)
			(copperpour not_allowed)
			(footprints allowed)
		)
		(placement
			(enabled no)
			(sheetname "")
		)
		(fill yes
			(thermal_gap 0.5)
			(thermal_bridge_width 0.5)
			(island_removal_mode 0)
		)
		(polygon
			(pts
				(arc
					(start 280.966164 -265.335004)
					(mid 280.305764 -265.335004)
					(end 280.966164 -265.335004)
				)
			)
		)
	)
	(zone
		(layers "In1.Cu" "In2.Cu")
		(hatch none 0.5)
		(connect_pads
			(clearance 0)
		)
		(min_thickness 0.25)
		(keepout
			(tracks not_allowed)
			(vias allowed)
			(pads allowed)
			(copperpour not_allowed)
			(footprints allowed)
		)
		(placement
			(enabled no)
			(sheetname "")
		)
		(fill yes
			(thermal_gap 0.5)
			(thermal_bridge_width 0.5)
			(island_removal_mode 0)
		)
		(polygon
			(pts
				(arc
					(start 269.978378 -225.385122)
					(mid 269.317978 -225.385122)
					(end 269.978378 -225.385122)
				)
			)
		)
	)
	(zone
		(layers "In1.Cu" "In2.Cu")
		(hatch none 0.5)
		(connect_pads
			(clearance 0)
		)
		(min_thickness 0.25)
		(keepout
			(tracks not_allowed)
			(vias allowed)
			(pads allowed)
			(copperpour not_allowed)
			(footprints allowed)
		)
		(placement
			(enabled no)
			(sheetname "")
		)
		(fill yes
			(thermal_gap 0.5)
			(thermal_bridge_width 0.5)
			(island_removal_mode 0)
		)
		(polygon
			(pts
				(arc
					(start 172.30217 -215.185244)
					(mid 171.64177 -215.185244)
					(end 172.30217 -215.185244)
				)
			)
		)
	)
	(zone
		(layers "In1.Cu" "In2.Cu")
		(hatch none 0.5)
		(connect_pads
			(clearance 0)
		)
		(min_thickness 0.25)
		(keepout
			(tracks not_allowed)
			(vias allowed)
			(pads allowed)
			(copperpour not_allowed)
			(footprints allowed)
		)
		(placement
			(enabled no)
			(sheetname "")
		)
		(fill yes
			(thermal_gap 0.5)
			(thermal_bridge_width 0.5)
			(island_removal_mode 0)
		)
		(polygon
			(pts
				(arc
					(start 52.214272 -309.535322)
					(mid 51.553872 -309.535322)
					(end 52.214272 -309.535322)
				)
			)
		)
	)
	(zone
		(layers "In1.Cu" "In2.Cu")
		(hatch none 0.5)
		(connect_pads
			(clearance 0)
		)
		(min_thickness 0.25)
		(keepout
			(tracks not_allowed)
			(vias allowed)
			(pads allowed)
			(copperpour not_allowed)
			(footprints allowed)
		)
		(placement
			(enabled no)
			(sheetname "")
		)
		(fill yes
			(thermal_gap 0.5)
			(thermal_bridge_width 0.5)
			(island_removal_mode 0)
		)
		(polygon
			(pts
				(arc
					(start 183.946292 -208.38541)
					(mid 183.285892 -208.38541)
					(end 183.946292 -208.38541)
				)
			)
		)
	)
	(zone
		(layers "In1.Cu" "In2.Cu")
		(hatch none 0.5)
		(connect_pads
			(clearance 0)
		)
		(min_thickness 0.25)
		(keepout
			(tracks not_allowed)
			(vias allowed)
			(pads allowed)
			(copperpour not_allowed)
			(footprints allowed)
		)
		(placement
			(enabled no)
			(sheetname "")
		)
		(fill yes
			(thermal_gap 0.5)
			(thermal_bridge_width 0.5)
			(island_removal_mode 0)
		)
		(polygon
			(pts
				(arc
					(start 435.330346 -246.635016)
					(mid 434.669946 -246.635016)
					(end 435.330346 -246.635016)
				)
			)
		)
	)
	(zone
		(layers "In1.Cu" "In2.Cu")
		(hatch none 0.5)
		(connect_pads
			(clearance 0)
		)
		(min_thickness 0.25)
		(keepout
			(tracks not_allowed)
			(vias allowed)
			(pads allowed)
			(copperpour not_allowed)
			(footprints allowed)
		)
		(placement
			(enabled no)
			(sheetname "")
		)
		(fill yes
			(thermal_gap 0.5)
			(thermal_bridge_width 0.5)
			(island_removal_mode 0)
		)
		(polygon
			(pts
				(arc
					(start 288.510218 -280.634948)
					(mid 287.849818 -280.634948)
					(end 288.510218 -280.634948)
				)
			)
		)
	)
	(zone
		(layers "In1.Cu" "In2.Cu")
		(hatch none 0.5)
		(connect_pads
			(clearance 0)
		)
		(min_thickness 0.25)
		(keepout
			(tracks not_allowed)
			(vias allowed)
			(pads allowed)
			(copperpour not_allowed)
			(footprints allowed)
		)
		(placement
			(enabled no)
			(sheetname "")
		)
		(fill yes
			(thermal_gap 0.5)
			(thermal_bridge_width 0.5)
			(island_removal_mode 0)
		)
		(polygon
			(pts
				(arc
					(start 194.934332 -276.385274)
					(mid 194.273932 -276.385274)
					(end 194.934332 -276.385274)
				)
			)
		)
	)
	(zone
		(layers "In1.Cu" "In2.Cu")
		(hatch none 0.5)
		(connect_pads
			(clearance 0)
		)
		(min_thickness 0.25)
		(keepout
			(tracks not_allowed)
			(vias allowed)
			(pads allowed)
			(copperpour not_allowed)
			(footprints allowed)
		)
		(placement
			(enabled no)
			(sheetname "")
		)
		(fill yes
			(thermal_gap 0.5)
			(thermal_bridge_width 0.5)
			(island_removal_mode 0)
		)
		(polygon
			(pts
				(arc
					(start 202.478132 -254.285242)
					(mid 201.817732 -254.285242)
					(end 202.478132 -254.285242)
				)
			)
		)
	)
	(zone
		(layers "In1.Cu" "In2.Cu")
		(hatch none 0.5)
		(connect_pads
			(clearance 0)
		)
		(min_thickness 0.25)
		(keepout
			(tracks not_allowed)
			(vias allowed)
			(pads allowed)
			(copperpour not_allowed)
			(footprints allowed)
		)
		(placement
			(enabled no)
			(sheetname "")
		)
		(fill yes
			(thermal_gap 0.5)
			(thermal_bridge_width 0.5)
			(island_removal_mode 0)
		)
		(polygon
			(pts
				(arc
					(start 277.522432 -236.435138)
					(mid 276.862032 -236.435138)
					(end 277.522432 -236.435138)
				)
			)
		)
	)
	(zone
		(layers "In1.Cu" "In2.Cu")
		(hatch none 0.5)
		(connect_pads
			(clearance 0)
		)
		(min_thickness 0.25)
		(keepout
			(tracks not_allowed)
			(vias allowed)
			(pads allowed)
			(copperpour not_allowed)
			(footprints allowed)
		)
		(placement
			(enabled no)
			(sheetname "")
		)
		(fill yes
			(thermal_gap 0.5)
			(thermal_bridge_width 0.5)
			(island_removal_mode 0)
		)
		(polygon
			(pts
				(arc
					(start 52.214272 -278.085296)
					(mid 51.553872 -278.085296)
					(end 52.214272 -278.085296)
				)
			)
		)
	)
	(zone
		(layers "In1.Cu" "In2.Cu")
		(hatch none 0.5)
		(connect_pads
			(clearance 0)
		)
		(min_thickness 0.25)
		(keepout
			(tracks not_allowed)
			(vias allowed)
			(pads allowed)
			(copperpour not_allowed)
			(footprints allowed)
		)
		(placement
			(enabled no)
			(sheetname "")
		)
		(fill yes
			(thermal_gap 0.5)
			(thermal_bridge_width 0.5)
			(island_removal_mode 0)
		)
		(polygon
			(pts
				(arc
					(start 277.522432 -229.63505)
					(mid 276.862032 -229.63505)
					(end 277.522432 -229.63505)
				)
			)
		)
	)
	(zone
		(layers "In1.Cu" "In2.Cu")
		(hatch none 0.5)
		(connect_pads
			(clearance 0)
		)
		(min_thickness 0.25)
		(keepout
			(tracks not_allowed)
			(vias allowed)
			(pads allowed)
			(copperpour not_allowed)
			(footprints allowed)
		)
		(placement
			(enabled no)
			(sheetname "")
		)
		(fill yes
			(thermal_gap 0.5)
			(thermal_bridge_width 0.5)
			(island_removal_mode 0)
		)
		(polygon
			(pts
				(arc
					(start 75.146154 -408.860244)
					(mid 75.168472 -408.914126)
					(end 75.222354 -408.936444)
				)
				(arc
					(start 75.417934 -408.936444)
					(mid 75.43981 -408.933312)
					(end 75.459844 -408.923998)
				)
				(arc
					(start 75.753468 -408.731466)
					(mid 75.795124 -408.719064)
					(end 75.83678 -408.731466)
				)
				(arc
					(start 76.131674 -408.923998)
					(mid 76.151598 -408.933234)
					(end 76.17333 -408.936444)
				)
				(arc
					(start 76.367894 -408.936444)
					(mid 76.421776 -408.914126)
					(end 76.444094 -408.860244)
				)
				(arc
					(start 76.444094 -408.174444)
					(mid 76.421776 -408.120562)
					(end 76.367894 -408.098244)
				)
				(arc
					(start 76.17333 -408.098244)
					(mid 76.151586 -408.101412)
					(end 76.131674 -408.11069)
				)
				(arc
					(start 75.83551 -408.303476)
					(mid 75.793826 -408.315698)
					(end 75.752198 -408.303222)
				)
				(arc
					(start 75.458574 -408.11069)
					(mid 75.43865 -408.101454)
					(end 75.416918 -408.098244)
				)
				(arc
					(start 75.222354 -408.098244)
					(mid 75.168472 -408.120562)
					(end 75.146154 -408.174444)
				)
			)
		)
	)
	(zone
		(layers "In1.Cu" "In2.Cu")
		(hatch none 0.5)
		(connect_pads
			(clearance 0)
		)
		(min_thickness 0.25)
		(keepout
			(tracks not_allowed)
			(vias allowed)
			(pads allowed)
			(copperpour not_allowed)
			(footprints allowed)
		)
		(placement
			(enabled no)
			(sheetname "")
		)
		(fill yes
			(thermal_gap 0.5)
			(thermal_bridge_width 0.5)
			(island_removal_mode 0)
		)
		(polygon
			(pts
				(arc
					(start 300.15434 -309.535068)
					(mid 299.49394 -309.535068)
					(end 300.15434 -309.535068)
				)
			)
		)
	)
	(zone
		(layers "In1.Cu" "In2.Cu")
		(hatch none 0.5)
		(connect_pads
			(clearance 0)
		)
		(min_thickness 0.25)
		(keepout
			(tracks not_allowed)
			(vias allowed)
			(pads allowed)
			(copperpour not_allowed)
			(footprints allowed)
		)
		(placement
			(enabled no)
			(sheetname "")
		)
		(fill yes
			(thermal_gap 0.5)
			(thermal_bridge_width 0.5)
			(island_removal_mode 0)
		)
		(polygon
			(pts
				(arc
					(start 202.478132 -246.63527)
					(mid 201.817732 -246.63527)
					(end 202.478132 -246.63527)
				)
			)
		)
	)
	(zone
		(layers "In1.Cu" "In2.Cu")
		(hatch none 0.5)
		(connect_pads
			(clearance 0)
		)
		(min_thickness 0.25)
		(keepout
			(tracks not_allowed)
			(vias allowed)
			(pads allowed)
			(copperpour not_allowed)
			(footprints allowed)
		)
		(placement
			(enabled no)
			(sheetname "")
		)
		(fill yes
			(thermal_gap 0.5)
			(thermal_bridge_width 0.5)
			(island_removal_mode 0)
		)
		(polygon
			(pts
				(arc
					(start 431.88636 -270.43507)
					(mid 431.22596 -270.43507)
					(end 431.88636 -270.43507)
				)
			)
		)
	)
	(zone
		(layers "In1.Cu" "In2.Cu")
		(hatch none 0.5)
		(connect_pads
			(clearance 0)
		)
		(min_thickness 0.25)
		(keepout
			(tracks not_allowed)
			(vias allowed)
			(pads allowed)
			(copperpour not_allowed)
			(footprints allowed)
		)
		(placement
			(enabled no)
			(sheetname "")
		)
		(fill yes
			(thermal_gap 0.5)
			(thermal_bridge_width 0.5)
			(island_removal_mode 0)
		)
		(polygon
			(pts
				(arc
					(start 454.518268 -227.085144)
					(mid 453.857868 -227.085144)
					(end 454.518268 -227.085144)
				)
			)
		)
	)
	(zone
		(layers "In1.Cu" "In2.Cu")
		(hatch none 0.5)
		(connect_pads
			(clearance 0)
		)
		(min_thickness 0.25)
		(keepout
			(tracks not_allowed)
			(vias allowed)
			(pads allowed)
			(copperpour not_allowed)
			(footprints allowed)
		)
		(placement
			(enabled no)
			(sheetname "")
		)
		(fill yes
			(thermal_gap 0.5)
			(thermal_bridge_width 0.5)
			(island_removal_mode 0)
		)
		(polygon
			(pts
				(arc
					(start 273.422364 -306.985162)
					(mid 272.761964 -306.985162)
					(end 273.422364 -306.985162)
				)
			)
		)
	)
	(zone
		(layers "In1.Cu" "In2.Cu")
		(hatch none 0.5)
		(connect_pads
			(clearance 0)
		)
		(min_thickness 0.25)
		(keepout
			(tracks not_allowed)
			(vias allowed)
			(pads allowed)
			(copperpour not_allowed)
			(footprints allowed)
		)
		(placement
			(enabled no)
			(sheetname "")
		)
		(fill yes
			(thermal_gap 0.5)
			(thermal_bridge_width 0.5)
			(island_removal_mode 0)
		)
		(polygon
			(pts
				(arc
					(start 288.510218 -215.18499)
					(mid 287.849818 -215.18499)
					(end 288.510218 -215.18499)
				)
			)
		)
	)
	(zone
		(layers "In1.Cu" "In2.Cu")
		(hatch none 0.5)
		(connect_pads
			(clearance 0)
		)
		(min_thickness 0.25)
		(keepout
			(tracks not_allowed)
			(vias allowed)
			(pads allowed)
			(copperpour not_allowed)
			(footprints allowed)
		)
		(placement
			(enabled no)
			(sheetname "")
		)
		(fill yes
			(thermal_gap 0.5)
			(thermal_bridge_width 0.5)
			(island_removal_mode 0)
		)
		(polygon
			(pts
				(arc
					(start 44.670218 -223.685354)
					(mid 44.009818 -223.685354)
					(end 44.670218 -223.685354)
				)
			)
		)
	)
	(zone
		(layers "In1.Cu" "In2.Cu")
		(hatch none 0.5)
		(connect_pads
			(clearance 0)
		)
		(min_thickness 0.25)
		(keepout
			(tracks not_allowed)
			(vias allowed)
			(pads allowed)
			(copperpour not_allowed)
			(footprints allowed)
		)
		(placement
			(enabled no)
			(sheetname "")
		)
		(fill yes
			(thermal_gap 0.5)
			(thermal_bridge_width 0.5)
			(island_removal_mode 0)
		)
		(polygon
			(pts
				(arc
					(start 273.422364 -305.28514)
					(mid 272.761964 -305.28514)
					(end 273.422364 -305.28514)
				)
			)
		)
	)
	(zone
		(layers "In1.Cu" "In2.Cu")
		(hatch none 0.5)
		(connect_pads
			(clearance 0)
		)
		(min_thickness 0.25)
		(keepout
			(tracks not_allowed)
			(vias allowed)
			(pads allowed)
			(copperpour not_allowed)
			(footprints allowed)
		)
		(placement
			(enabled no)
			(sheetname "")
		)
		(fill yes
			(thermal_gap 0.5)
			(thermal_bridge_width 0.5)
			(island_removal_mode 0)
		)
		(polygon
			(pts
				(arc
					(start 33.026096 -302.735234)
					(mid 32.365696 -302.735234)
					(end 33.026096 -302.735234)
				)
			)
		)
	)
	(zone
		(layers "In1.Cu" "In2.Cu")
		(hatch none 0.5)
		(connect_pads
			(clearance 0)
		)
		(min_thickness 0.25)
		(keepout
			(tracks not_allowed)
			(vias allowed)
			(pads allowed)
			(copperpour not_allowed)
			(footprints allowed)
		)
		(placement
			(enabled no)
			(sheetname "")
		)
		(fill yes
			(thermal_gap 0.5)
			(thermal_bridge_width 0.5)
			(island_removal_mode 0)
		)
		(polygon
			(pts
				(arc
					(start 296.054272 -198.185024)
					(mid 295.393872 -198.185024)
					(end 296.054272 -198.185024)
				)
			)
		)
	)
	(zone
		(layers "In1.Cu" "In2.Cu")
		(hatch none 0.5)
		(connect_pads
			(clearance 0)
		)
		(min_thickness 0.25)
		(keepout
			(tracks not_allowed)
			(vias allowed)
			(pads allowed)
			(copperpour not_allowed)
			(footprints allowed)
		)
		(placement
			(enabled no)
			(sheetname "")
		)
		(fill yes
			(thermal_gap 0.5)
			(thermal_bridge_width 0.5)
			(island_removal_mode 0)
		)
		(polygon
			(pts
				(arc
					(start 424.342306 -304.435002)
					(mid 423.681906 -304.435002)
					(end 424.342306 -304.435002)
				)
			)
		)
	)
	(zone
		(layers "In1.Cu" "In2.Cu")
		(hatch none 0.5)
		(connect_pads
			(clearance 0)
		)
		(min_thickness 0.25)
		(keepout
			(tracks not_allowed)
			(vias allowed)
			(pads allowed)
			(copperpour not_allowed)
			(footprints allowed)
		)
		(placement
			(enabled no)
			(sheetname "")
		)
		(fill yes
			(thermal_gap 0.5)
			(thermal_bridge_width 0.5)
			(island_removal_mode 0)
		)
		(polygon
			(pts
				(arc
					(start 191.490346 -227.085398)
					(mid 190.829946 -227.085398)
					(end 191.490346 -227.085398)
				)
			)
		)
	)
	(zone
		(layers "In1.Cu" "In2.Cu")
		(hatch none 0.5)
		(connect_pads
			(clearance 0)
		)
		(min_thickness 0.25)
		(keepout
			(tracks not_allowed)
			(vias allowed)
			(pads allowed)
			(copperpour not_allowed)
			(footprints allowed)
		)
		(placement
			(enabled no)
			(sheetname "")
		)
		(fill yes
			(thermal_gap 0.5)
			(thermal_bridge_width 0.5)
			(island_removal_mode 0)
		)
		(polygon
			(pts
				(arc
					(start 199.0344 -304.435256)
					(mid 198.374 -304.435256)
					(end 199.0344 -304.435256)
				)
			)
		)
	)
	(zone
		(layers "In1.Cu" "In2.Cu")
		(hatch none 0.5)
		(connect_pads
			(clearance 0)
		)
		(min_thickness 0.25)
		(keepout
			(tracks not_allowed)
			(vias allowed)
			(pads allowed)
			(copperpour not_allowed)
			(footprints allowed)
		)
		(placement
			(enabled no)
			(sheetname "")
		)
		(fill yes
			(thermal_gap 0.5)
			(thermal_bridge_width 0.5)
			(island_removal_mode 0)
		)
		(polygon
			(pts
				(arc
					(start 446.974468 -203.28509)
					(mid 446.314068 -203.28509)
					(end 446.974468 -203.28509)
				)
			)
		)
	)
	(zone
		(layers "In1.Cu" "In2.Cu")
		(hatch none 0.5)
		(connect_pads
			(clearance 0)
		)
		(min_thickness 0.25)
		(keepout
			(tracks not_allowed)
			(vias allowed)
			(pads allowed)
			(copperpour not_allowed)
			(footprints allowed)
		)
		(placement
			(enabled no)
			(sheetname "")
		)
		(fill yes
			(thermal_gap 0.5)
			(thermal_bridge_width 0.5)
			(island_removal_mode 0)
		)
		(polygon
			(pts
				(arc
					(start 52.214272 -301.88535)
					(mid 51.553872 -301.88535)
					(end 52.214272 -301.88535)
				)
			)
		)
	)
	(zone
		(layers "In1.Cu" "In2.Cu")
		(hatch none 0.5)
		(connect_pads
			(clearance 0)
		)
		(min_thickness 0.25)
		(keepout
			(tracks not_allowed)
			(vias allowed)
			(pads allowed)
			(copperpour not_allowed)
			(footprints allowed)
		)
		(placement
			(enabled no)
			(sheetname "")
		)
		(fill yes
			(thermal_gap 0.5)
			(thermal_bridge_width 0.5)
			(island_removal_mode 0)
		)
		(polygon
			(pts
				(arc
					(start 300.15434 -245.785132)
					(mid 299.49394 -245.785132)
					(end 300.15434 -245.785132)
				)
			)
		)
	)
	(zone
		(layers "In1.Cu" "In2.Cu")
		(hatch none 0.5)
		(connect_pads
			(clearance 0)
		)
		(min_thickness 0.25)
		(keepout
			(tracks not_allowed)
			(vias allowed)
			(pads allowed)
			(copperpour not_allowed)
			(footprints allowed)
		)
		(placement
			(enabled no)
			(sheetname "")
		)
		(fill yes
			(thermal_gap 0.5)
			(thermal_bridge_width 0.5)
			(island_removal_mode 0)
		)
		(polygon
			(pts
				(arc
					(start 48.114204 -221.135194)
					(mid 47.453804 -221.135194)
					(end 48.114204 -221.135194)
				)
			)
		)
	)
	(zone
		(layers "In1.Cu" "In2.Cu")
		(hatch none 0.5)
		(connect_pads
			(clearance 0)
		)
		(min_thickness 0.25)
		(keepout
			(tracks not_allowed)
			(vias allowed)
			(pads allowed)
			(copperpour not_allowed)
			(footprints allowed)
		)
		(placement
			(enabled no)
			(sheetname "")
		)
		(fill yes
			(thermal_gap 0.5)
			(thermal_bridge_width 0.5)
			(island_removal_mode 0)
		)
		(polygon
			(pts
				(arc
					(start 29.582364 -283.185362)
					(mid 28.921964 -283.185362)
					(end 29.582364 -283.185362)
				)
			)
		)
	)
	(zone
		(layers "In1.Cu" "In2.Cu")
		(hatch none 0.5)
		(connect_pads
			(clearance 0)
		)
		(min_thickness 0.25)
		(keepout
			(tracks not_allowed)
			(vias allowed)
			(pads allowed)
			(copperpour not_allowed)
			(footprints allowed)
		)
		(placement
			(enabled no)
			(sheetname "")
		)
		(fill yes
			(thermal_gap 0.5)
			(thermal_bridge_width 0.5)
			(island_removal_mode 0)
		)
		(polygon
			(pts
				(arc
					(start 22.45233 -7.672324)
					(mid 22.474648 -7.618442)
					(end 22.52853 -7.596124)
				)
				(arc
					(start 23.565104 -7.596124)
					(mid 23.618986 -7.618442)
					(end 23.641304 -7.672324)
				)
				(arc
					(start 23.641304 -9.071864)
					(mid 23.618986 -9.125746)
					(end 23.565104 -9.148064)
				)
				(arc
					(start 22.52853 -9.148064)
					(mid 22.474648 -9.125746)
					(end 22.45233 -9.071864)
				)
			)
		)
	)
	(zone
		(layers "In1.Cu" "In2.Cu")
		(hatch none 0.5)
		(connect_pads
			(clearance 0)
		)
		(min_thickness 0.25)
		(keepout
			(tracks not_allowed)
			(vias allowed)
			(pads allowed)
			(copperpour not_allowed)
			(footprints allowed)
		)
		(placement
			(enabled no)
			(sheetname "")
		)
		(fill yes
			(thermal_gap 0.5)
			(thermal_bridge_width 0.5)
			(island_removal_mode 0)
		)
		(polygon
			(pts
				(arc
					(start 187.390278 -316.33541)
					(mid 186.729878 -316.33541)
					(end 187.390278 -316.33541)
				)
			)
		)
	)
	(zone
		(layers "In1.Cu" "In2.Cu")
		(hatch none 0.5)
		(connect_pads
			(clearance 0)
		)
		(min_thickness 0.25)
		(keepout
			(tracks not_allowed)
			(vias allowed)
			(pads allowed)
			(copperpour not_allowed)
			(footprints allowed)
		)
		(placement
			(enabled no)
			(sheetname "")
		)
		(fill yes
			(thermal_gap 0.5)
			(thermal_bridge_width 0.5)
			(island_removal_mode 0)
		)
		(polygon
			(pts
				(arc
					(start 450.4182 -204.134974)
					(mid 449.7578 -204.134974)
					(end 450.4182 -204.134974)
				)
			)
		)
	)
	(zone
		(layers "In1.Cu" "In2.Cu")
		(hatch none 0.5)
		(connect_pads
			(clearance 0)
		)
		(min_thickness 0.25)
		(keepout
			(tracks not_allowed)
			(vias allowed)
			(pads allowed)
			(copperpour not_allowed)
			(footprints allowed)
		)
		(placement
			(enabled no)
			(sheetname "")
		)
		(fill yes
			(thermal_gap 0.5)
			(thermal_bridge_width 0.5)
			(island_removal_mode 0)
		)
		(polygon
			(pts
				(arc
					(start 424.342306 -290.83508)
					(mid 423.681906 -290.83508)
					(end 424.342306 -290.83508)
				)
			)
		)
	)
	(zone
		(layers "In1.Cu" "In2.Cu")
		(hatch none 0.5)
		(connect_pads
			(clearance 0)
		)
		(min_thickness 0.25)
		(keepout
			(tracks not_allowed)
			(vias allowed)
			(pads allowed)
			(copperpour not_allowed)
			(footprints allowed)
		)
		(placement
			(enabled no)
			(sheetname "")
		)
		(fill yes
			(thermal_gap 0.5)
			(thermal_bridge_width 0.5)
			(island_removal_mode 0)
		)
		(polygon
			(pts
				(arc
					(start 44.670218 -295.085262)
					(mid 44.009818 -295.085262)
					(end 44.670218 -295.085262)
				)
			)
		)
	)
	(zone
		(layers "In1.Cu" "In2.Cu")
		(hatch none 0.5)
		(connect_pads
			(clearance 0)
		)
		(min_thickness 0.25)
		(keepout
			(tracks not_allowed)
			(vias allowed)
			(pads allowed)
			(copperpour not_allowed)
			(footprints allowed)
		)
		(placement
			(enabled no)
			(sheetname "")
		)
		(fill yes
			(thermal_gap 0.5)
			(thermal_bridge_width 0.5)
			(island_removal_mode 0)
		)
		(polygon
			(pts
				(arc
					(start 187.390278 -213.485222)
					(mid 186.729878 -213.485222)
					(end 187.390278 -213.485222)
				)
			)
		)
	)
	(zone
		(layers "In1.Cu" "In2.Cu")
		(hatch none 0.5)
		(connect_pads
			(clearance 0)
		)
		(min_thickness 0.25)
		(keepout
			(tracks not_allowed)
			(vias allowed)
			(pads allowed)
			(copperpour not_allowed)
			(footprints allowed)
		)
		(placement
			(enabled no)
			(sheetname "")
		)
		(fill yes
			(thermal_gap 0.5)
			(thermal_bridge_width 0.5)
			(island_removal_mode 0)
		)
		(polygon
			(pts
				(arc
					(start 40.57015 -241.535204)
					(mid 39.90975 -241.535204)
					(end 40.57015 -241.535204)
				)
			)
		)
	)
	(zone
		(layers "In1.Cu" "In2.Cu")
		(hatch none 0.5)
		(connect_pads
			(clearance 0)
		)
		(min_thickness 0.25)
		(keepout
			(tracks not_allowed)
			(vias allowed)
			(pads allowed)
			(copperpour not_allowed)
			(footprints allowed)
		)
		(placement
			(enabled no)
			(sheetname "")
		)
		(fill yes
			(thermal_gap 0.5)
			(thermal_bridge_width 0.5)
			(island_removal_mode 0)
		)
		(polygon
			(pts
				(arc
					(start 292.610286 -214.335106)
					(mid 291.949886 -214.335106)
					(end 292.610286 -214.335106)
				)
			)
		)
	)
	(zone
		(layers "In1.Cu" "In2.Cu")
		(hatch none 0.5)
		(connect_pads
			(clearance 0)
		)
		(min_thickness 0.25)
		(keepout
			(tracks not_allowed)
			(vias allowed)
			(pads allowed)
			(copperpour not_allowed)
			(footprints allowed)
		)
		(placement
			(enabled no)
			(sheetname "")
		)
		(fill yes
			(thermal_gap 0.5)
			(thermal_bridge_width 0.5)
			(island_removal_mode 0)
		)
		(polygon
			(pts
				(arc
					(start 133.006846 -370.978684)
					(mid 133.02677 -370.98792)
					(end 133.048502 -370.99113)
				)
				(arc
					(start 133.243066 -370.99113)
					(mid 133.296948 -370.968812)
					(end 133.319266 -370.91493)
				)
				(arc
					(start 133.319266 -370.22913)
					(mid 133.296948 -370.175248)
					(end 133.243066 -370.15293)
				)
				(arc
					(start 133.048502 -370.15293)
					(mid 133.026758 -370.156098)
					(end 133.006846 -370.165376)
				)
				(arc
					(start 132.710682 -370.358162)
					(mid 132.668998 -370.370384)
					(end 132.62737 -370.357908)
				)
				(arc
					(start 132.333746 -370.165376)
					(mid 132.313822 -370.15614)
					(end 132.29209 -370.15293)
				)
				(arc
					(start 132.097526 -370.15293)
					(mid 132.043644 -370.175248)
					(end 132.021326 -370.22913)
				)
				(arc
					(start 132.021326 -370.91493)
					(mid 132.043644 -370.968812)
					(end 132.097526 -370.99113)
				)
				(arc
					(start 132.29336 -370.99113)
					(mid 132.315104 -370.987962)
					(end 132.335016 -370.978684)
				)
				(arc
					(start 132.62864 -370.786152)
					(mid 132.670296 -370.77375)
					(end 132.711952 -370.786152)
				)
			)
		)
	)
	(zone
		(layers "In1.Cu" "In2.Cu")
		(hatch none 0.5)
		(connect_pads
			(clearance 0)
		)
		(min_thickness 0.25)
		(keepout
			(tracks not_allowed)
			(vias allowed)
			(pads allowed)
			(copperpour not_allowed)
			(footprints allowed)
		)
		(placement
			(enabled no)
			(sheetname "")
		)
		(fill yes
			(thermal_gap 0.5)
			(thermal_bridge_width 0.5)
			(island_removal_mode 0)
		)
		(polygon
			(pts
				(arc
					(start 187.390278 -301.035212)
					(mid 186.729878 -301.035212)
					(end 187.390278 -301.035212)
				)
			)
		)
	)
	(zone
		(layers "In1.Cu" "In2.Cu")
		(hatch none 0.5)
		(connect_pads
			(clearance 0)
		)
		(min_thickness 0.25)
		(keepout
			(tracks not_allowed)
			(vias allowed)
			(pads allowed)
			(copperpour not_allowed)
			(footprints allowed)
		)
		(placement
			(enabled no)
			(sheetname "")
		)
		(fill yes
			(thermal_gap 0.5)
			(thermal_bridge_width 0.5)
			(island_removal_mode 0)
		)
		(polygon
			(pts
				(arc
					(start 48.114204 -293.38524)
					(mid 47.453804 -293.38524)
					(end 48.114204 -293.38524)
				)
			)
		)
	)
	(zone
		(layers "In1.Cu" "In2.Cu")
		(hatch none 0.5)
		(connect_pads
			(clearance 0)
		)
		(min_thickness 0.25)
		(keepout
			(tracks not_allowed)
			(vias allowed)
			(pads allowed)
			(copperpour not_allowed)
			(footprints allowed)
		)
		(placement
			(enabled no)
			(sheetname "")
		)
		(fill yes
			(thermal_gap 0.5)
			(thermal_bridge_width 0.5)
			(island_removal_mode 0)
		)
		(polygon
			(pts
				(arc
					(start 194.934332 -220.28531)
					(mid 194.273932 -220.28531)
					(end 194.934332 -220.28531)
				)
			)
		)
	)
	(zone
		(layers "In1.Cu" "In2.Cu")
		(hatch none 0.5)
		(connect_pads
			(clearance 0)
		)
		(min_thickness 0.25)
		(keepout
			(tracks not_allowed)
			(vias allowed)
			(pads allowed)
			(copperpour not_allowed)
			(footprints allowed)
		)
		(placement
			(enabled no)
			(sheetname "")
		)
		(fill yes
			(thermal_gap 0.5)
			(thermal_bridge_width 0.5)
			(island_removal_mode 0)
		)
		(polygon
			(pts
				(arc
					(start 17.938242 -274.685252)
					(mid 17.277842 -274.685252)
					(end 17.938242 -274.685252)
				)
			)
		)
	)
	(zone
		(layers "In1.Cu" "In2.Cu")
		(hatch none 0.5)
		(connect_pads
			(clearance 0)
		)
		(min_thickness 0.25)
		(keepout
			(tracks not_allowed)
			(vias allowed)
			(pads allowed)
			(copperpour not_allowed)
			(footprints allowed)
		)
		(placement
			(enabled no)
			(sheetname "")
		)
		(fill yes
			(thermal_gap 0.5)
			(thermal_bridge_width 0.5)
			(island_removal_mode 0)
		)
		(polygon
			(pts
				(arc
					(start 431.88636 -284.88513)
					(mid 431.22596 -284.88513)
					(end 431.88636 -284.88513)
				)
			)
		)
	)
	(zone
		(layers "In1.Cu" "In2.Cu")
		(hatch none 0.5)
		(connect_pads
			(clearance 0)
		)
		(min_thickness 0.25)
		(keepout
			(tracks not_allowed)
			(vias allowed)
			(pads allowed)
			(copperpour not_allowed)
			(footprints allowed)
		)
		(placement
			(enabled no)
			(sheetname "")
		)
		(fill yes
			(thermal_gap 0.5)
			(thermal_bridge_width 0.5)
			(island_removal_mode 0)
		)
		(polygon
			(pts
				(arc
					(start 176.402238 -220.28531)
					(mid 175.741838 -220.28531)
					(end 176.402238 -220.28531)
				)
			)
		)
	)
	(zone
		(layers "In1.Cu" "In2.Cu")
		(hatch none 0.5)
		(connect_pads
			(clearance 0)
		)
		(min_thickness 0.25)
		(keepout
			(tracks not_allowed)
			(vias allowed)
			(pads allowed)
			(copperpour not_allowed)
			(footprints allowed)
		)
		(placement
			(enabled no)
			(sheetname "")
		)
		(fill yes
			(thermal_gap 0.5)
			(thermal_bridge_width 0.5)
			(island_removal_mode 0)
		)
		(polygon
			(pts
				(arc
					(start 285.066232 -312.935112)
					(mid 284.405832 -312.935112)
					(end 285.066232 -312.935112)
				)
			)
		)
	)
	(zone
		(layers "In1.Cu" "In2.Cu")
		(hatch none 0.5)
		(connect_pads
			(clearance 0)
		)
		(min_thickness 0.25)
		(keepout
			(tracks not_allowed)
			(vias allowed)
			(pads allowed)
			(copperpour not_allowed)
			(footprints allowed)
		)
		(placement
			(enabled no)
			(sheetname "")
		)
		(fill yes
			(thermal_gap 0.5)
			(thermal_bridge_width 0.5)
			(island_removal_mode 0)
		)
		(polygon
			(pts
				(arc
					(start 29.582364 -238.135414)
					(mid 28.921964 -238.135414)
					(end 29.582364 -238.135414)
				)
			)
		)
	)
	(zone
		(layers "In1.Cu" "In2.Cu")
		(hatch none 0.5)
		(connect_pads
			(clearance 0)
		)
		(min_thickness 0.25)
		(keepout
			(tracks not_allowed)
			(vias allowed)
			(pads allowed)
			(copperpour not_allowed)
			(footprints allowed)
		)
		(placement
			(enabled no)
			(sheetname "")
		)
		(fill yes
			(thermal_gap 0.5)
			(thermal_bridge_width 0.5)
			(island_removal_mode 0)
		)
		(polygon
			(pts
				(arc
					(start 442.8744 -263.634982)
					(mid 442.214 -263.634982)
					(end 442.8744 -263.634982)
				)
			)
		)
	)
	(zone
		(layers "In1.Cu" "In2.Cu")
		(hatch none 0.5)
		(connect_pads
			(clearance 0)
		)
		(min_thickness 0.25)
		(keepout
			(tracks not_allowed)
			(vias allowed)
			(pads allowed)
			(copperpour not_allowed)
			(footprints allowed)
		)
		(placement
			(enabled no)
			(sheetname "")
		)
		(fill yes
			(thermal_gap 0.5)
			(thermal_bridge_width 0.5)
			(island_removal_mode 0)
		)
		(polygon
			(pts
				(arc
					(start 183.946292 -197.335394)
					(mid 183.285892 -197.335394)
					(end 183.946292 -197.335394)
				)
			)
		)
	)
	(zone
		(layers "In1.Cu" "In2.Cu")
		(hatch none 0.5)
		(connect_pads
			(clearance 0)
		)
		(min_thickness 0.25)
		(keepout
			(tracks not_allowed)
			(vias allowed)
			(pads allowed)
			(copperpour not_allowed)
			(footprints allowed)
		)
		(placement
			(enabled no)
			(sheetname "")
		)
		(fill yes
			(thermal_gap 0.5)
			(thermal_bridge_width 0.5)
			(island_removal_mode 0)
		)
		(polygon
			(pts
				(arc
					(start 48.114204 -284.035246)
					(mid 47.453804 -284.035246)
					(end 48.114204 -284.035246)
				)
			)
		)
	)
	(zone
		(layers "In1.Cu" "In2.Cu")
		(hatch none 0.5)
		(connect_pads
			(clearance 0)
		)
		(min_thickness 0.25)
		(keepout
			(tracks not_allowed)
			(vias allowed)
			(pads allowed)
			(copperpour not_allowed)
			(footprints allowed)
		)
		(placement
			(enabled no)
			(sheetname "")
		)
		(fill yes
			(thermal_gap 0.5)
			(thermal_bridge_width 0.5)
			(island_removal_mode 0)
		)
		(polygon
			(pts
				(arc
					(start 296.054272 -285.735014)
					(mid 295.393872 -285.735014)
					(end 296.054272 -285.735014)
				)
			)
		)
	)
	(zone
		(layers "In1.Cu" "In2.Cu")
		(hatch none 0.5)
		(connect_pads
			(clearance 0)
		)
		(min_thickness 0.25)
		(keepout
			(tracks not_allowed)
			(vias allowed)
			(pads allowed)
			(copperpour not_allowed)
			(footprints allowed)
		)
		(placement
			(enabled no)
			(sheetname "")
		)
		(fill yes
			(thermal_gap 0.5)
			(thermal_bridge_width 0.5)
			(island_removal_mode 0)
		)
		(polygon
			(pts
				(arc
					(start 176.402238 -295.085262)
					(mid 175.741838 -295.085262)
					(end 176.402238 -295.085262)
				)
			)
		)
	)
	(zone
		(layers "In1.Cu" "In2.Cu")
		(hatch none 0.5)
		(connect_pads
			(clearance 0)
		)
		(min_thickness 0.25)
		(keepout
			(tracks not_allowed)
			(vias allowed)
			(pads allowed)
			(copperpour not_allowed)
			(footprints allowed)
		)
		(placement
			(enabled no)
			(sheetname "")
		)
		(fill yes
			(thermal_gap 0.5)
			(thermal_bridge_width 0.5)
			(island_removal_mode 0)
		)
		(polygon
			(pts
				(arc
					(start 17.938242 -304.435256)
					(mid 17.277842 -304.435256)
					(end 17.938242 -304.435256)
				)
			)
		)
	)
	(zone
		(layers "In1.Cu" "In2.Cu")
		(hatch none 0.5)
		(connect_pads
			(clearance 0)
		)
		(min_thickness 0.25)
		(keepout
			(tracks not_allowed)
			(vias allowed)
			(pads allowed)
			(copperpour not_allowed)
			(footprints allowed)
		)
		(placement
			(enabled no)
			(sheetname "")
		)
		(fill yes
			(thermal_gap 0.5)
			(thermal_bridge_width 0.5)
			(island_removal_mode 0)
		)
		(polygon
			(pts
				(arc
					(start 40.57015 -201.585322)
					(mid 39.90975 -201.585322)
					(end 40.57015 -201.585322)
				)
			)
		)
	)
	(zone
		(layers "In1.Cu" "In2.Cu")
		(hatch none 0.5)
		(connect_pads
			(clearance 0)
		)
		(min_thickness 0.25)
		(keepout
			(tracks not_allowed)
			(vias allowed)
			(pads allowed)
			(copperpour not_allowed)
			(footprints allowed)
		)
		(placement
			(enabled no)
			(sheetname "")
		)
		(fill yes
			(thermal_gap 0.5)
			(thermal_bridge_width 0.5)
			(island_removal_mode 0)
		)
		(polygon
			(pts
				(arc
					(start 410.499052 -417.242244)
					(mid 410.52137 -417.296126)
					(end 410.575252 -417.318444)
				)
				(arc
					(start 410.770832 -417.318444)
					(mid 410.792708 -417.315312)
					(end 410.812742 -417.305998)
				)
				(arc
					(start 411.106366 -417.113466)
					(mid 411.148022 -417.101064)
					(end 411.189678 -417.113466)
				)
				(arc
					(start 411.484572 -417.305998)
					(mid 411.504496 -417.315234)
					(end 411.526228 -417.318444)
				)
				(arc
					(start 411.720792 -417.318444)
					(mid 411.774674 -417.296126)
					(end 411.796992 -417.242244)
				)
				(arc
					(start 411.796992 -416.556444)
					(mid 411.774674 -416.502562)
					(end 411.720792 -416.480244)
				)
				(arc
					(start 411.526228 -416.480244)
					(mid 411.504484 -416.483412)
					(end 411.484572 -416.49269)
				)
				(arc
					(start 411.188408 -416.685476)
					(mid 411.146724 -416.697698)
					(end 411.105096 -416.685222)
				)
				(arc
					(start 410.811472 -416.49269)
					(mid 410.791548 -416.483454)
					(end 410.769816 -416.480244)
				)
				(arc
					(start 410.575252 -416.480244)
					(mid 410.52137 -416.502562)
					(end 410.499052 -416.556444)
				)
			)
		)
	)
	(zone
		(layers "In1.Cu" "In2.Cu")
		(hatch none 0.5)
		(connect_pads
			(clearance 0)
		)
		(min_thickness 0.25)
		(keepout
			(tracks not_allowed)
			(vias allowed)
			(pads allowed)
			(copperpour not_allowed)
			(footprints allowed)
		)
		(placement
			(enabled no)
			(sheetname "")
		)
		(fill yes
			(thermal_gap 0.5)
			(thermal_bridge_width 0.5)
			(island_removal_mode 0)
		)
		(polygon
			(pts
				(arc
					(start 442.8744 -293.384986)
					(mid 442.214 -293.384986)
					(end 442.8744 -293.384986)
				)
			)
		)
	)
	(zone
		(layers "In1.Cu" "In2.Cu")
		(hatch none 0.5)
		(connect_pads
			(clearance 0)
		)
		(min_thickness 0.25)
		(keepout
			(tracks not_allowed)
			(vias allowed)
			(pads allowed)
			(copperpour not_allowed)
			(footprints allowed)
		)
		(placement
			(enabled no)
			(sheetname "")
		)
		(fill yes
			(thermal_gap 0.5)
			(thermal_bridge_width 0.5)
			(island_removal_mode 0)
		)
		(polygon
			(pts
				(arc
					(start 385.603242 -384.288284)
					(mid 385.623166 -384.29752)
					(end 385.644898 -384.30073)
				)
				(arc
					(start 385.839462 -384.30073)
					(mid 385.893344 -384.278412)
					(end 385.915662 -384.22453)
				)
				(arc
					(start 385.915662 -383.53873)
					(mid 385.893344 -383.484848)
					(end 385.839462 -383.46253)
				)
				(arc
					(start 385.644898 -383.46253)
					(mid 385.623154 -383.465698)
					(end 385.603242 -383.474976)
				)
				(arc
					(start 385.307078 -383.667762)
					(mid 385.265394 -383.679984)
					(end 385.223766 -383.667508)
				)
				(arc
					(start 384.930142 -383.474976)
					(mid 384.910218 -383.46574)
					(end 384.888486 -383.46253)
				)
				(arc
					(start 384.693922 -383.46253)
					(mid 384.64004 -383.484848)
					(end 384.617722 -383.53873)
				)
				(arc
					(start 384.617722 -384.22453)
					(mid 384.64004 -384.278412)
					(end 384.693922 -384.30073)
				)
				(arc
					(start 384.889756 -384.30073)
					(mid 384.9115 -384.297562)
					(end 384.931412 -384.288284)
				)
				(arc
					(start 385.225036 -384.095752)
					(mid 385.266692 -384.08335)
					(end 385.308348 -384.095752)
				)
			)
		)
	)
	(zone
		(layers "In1.Cu" "In2.Cu")
		(hatch none 0.5)
		(connect_pads
			(clearance 0)
		)
		(min_thickness 0.25)
		(keepout
			(tracks not_allowed)
			(vias allowed)
			(pads allowed)
			(copperpour not_allowed)
			(footprints allowed)
		)
		(placement
			(enabled no)
			(sheetname "")
		)
		(fill yes
			(thermal_gap 0.5)
			(thermal_bridge_width 0.5)
			(island_removal_mode 0)
		)
		(polygon
			(pts
				(arc
					(start 22.03831 -242.385342)
					(mid 21.37791 -242.385342)
					(end 22.03831 -242.385342)
				)
			)
		)
	)
	(zone
		(layers "In1.Cu" "In2.Cu")
		(hatch none 0.5)
		(connect_pads
			(clearance 0)
		)
		(min_thickness 0.25)
		(keepout
			(tracks not_allowed)
			(vias allowed)
			(pads allowed)
			(copperpour not_allowed)
			(footprints allowed)
		)
		(placement
			(enabled no)
			(sheetname "")
		)
		(fill yes
			(thermal_gap 0.5)
			(thermal_bridge_width 0.5)
			(island_removal_mode 0)
		)
		(polygon
			(pts
				(arc
					(start 44.670218 -289.135312)
					(mid 44.009818 -289.135312)
					(end 44.670218 -289.135312)
				)
			)
		)
	)
	(zone
		(layers "In1.Cu" "In2.Cu")
		(hatch none 0.5)
		(connect_pads
			(clearance 0)
		)
		(min_thickness 0.25)
		(keepout
			(tracks not_allowed)
			(vias allowed)
			(pads allowed)
			(copperpour not_allowed)
			(footprints allowed)
		)
		(placement
			(enabled no)
			(sheetname "")
		)
		(fill yes
			(thermal_gap 0.5)
			(thermal_bridge_width 0.5)
			(island_removal_mode 0)
		)
		(polygon
			(pts
				(arc
					(start 176.402238 -204.985366)
					(mid 175.741838 -204.985366)
					(end 176.402238 -204.985366)
				)
			)
		)
	)
	(zone
		(layers "In1.Cu" "In2.Cu")
		(hatch none 0.5)
		(connect_pads
			(clearance 0)
		)
		(min_thickness 0.25)
		(keepout
			(tracks not_allowed)
			(vias allowed)
			(pads allowed)
			(copperpour not_allowed)
			(footprints allowed)
		)
		(placement
			(enabled no)
			(sheetname "")
		)
		(fill yes
			(thermal_gap 0.5)
			(thermal_bridge_width 0.5)
			(island_removal_mode 0)
		)
		(polygon
			(pts
				(arc
					(start 288.510218 -251.735082)
					(mid 287.849818 -251.735082)
					(end 288.510218 -251.735082)
				)
			)
		)
	)
	(zone
		(layers "In1.Cu" "In2.Cu")
		(hatch none 0.5)
		(connect_pads
			(clearance 0)
		)
		(min_thickness 0.25)
		(keepout
			(tracks not_allowed)
			(vias allowed)
			(pads allowed)
			(copperpour not_allowed)
			(footprints allowed)
		)
		(placement
			(enabled no)
			(sheetname "")
		)
		(fill yes
			(thermal_gap 0.5)
			(thermal_bridge_width 0.5)
			(island_removal_mode 0)
		)
		(polygon
			(pts
				(arc
					(start 420.242238 -291.684964)
					(mid 419.581838 -291.684964)
					(end 420.242238 -291.684964)
				)
			)
		)
	)
	(zone
		(layers "In1.Cu" "In2.Cu")
		(hatch none 0.5)
		(connect_pads
			(clearance 0)
		)
		(min_thickness 0.25)
		(keepout
			(tracks not_allowed)
			(vias allowed)
			(pads allowed)
			(copperpour not_allowed)
			(footprints allowed)
		)
		(placement
			(enabled no)
			(sheetname "")
		)
		(fill yes
			(thermal_gap 0.5)
			(thermal_bridge_width 0.5)
			(island_removal_mode 0)
		)
		(polygon
			(pts
				(arc
					(start 52.214272 -233.035348)
					(mid 51.553872 -233.035348)
					(end 52.214272 -233.035348)
				)
			)
		)
	)
	(zone
		(layers "In1.Cu" "In2.Cu")
		(hatch none 0.5)
		(connect_pads
			(clearance 0)
		)
		(min_thickness 0.25)
		(keepout
			(tracks not_allowed)
			(vias allowed)
			(pads allowed)
			(copperpour not_allowed)
			(footprints allowed)
		)
		(placement
			(enabled no)
			(sheetname "")
		)
		(fill yes
			(thermal_gap 0.5)
			(thermal_bridge_width 0.5)
			(island_removal_mode 0)
		)
		(polygon
			(pts
				(arc
					(start 179.846224 -201.585322)
					(mid 179.185824 -201.585322)
					(end 179.846224 -201.585322)
				)
			)
		)
	)
	(zone
		(layers "In1.Cu" "In2.Cu")
		(hatch none 0.5)
		(connect_pads
			(clearance 0)
		)
		(min_thickness 0.25)
		(keepout
			(tracks not_allowed)
			(vias allowed)
			(pads allowed)
			(copperpour not_allowed)
			(footprints allowed)
		)
		(placement
			(enabled no)
			(sheetname "")
		)
		(fill yes
			(thermal_gap 0.5)
			(thermal_bridge_width 0.5)
			(island_removal_mode 0)
		)
		(polygon
			(pts
				(arc
					(start 191.490346 -309.535322)
					(mid 190.829946 -309.535322)
					(end 191.490346 -309.535322)
				)
			)
		)
	)
	(zone
		(layers "In1.Cu" "In2.Cu")
		(hatch none 0.5)
		(connect_pads
			(clearance 0)
		)
		(min_thickness 0.25)
		(keepout
			(tracks not_allowed)
			(vias allowed)
			(pads allowed)
			(copperpour not_allowed)
			(footprints allowed)
		)
		(placement
			(enabled no)
			(sheetname "")
		)
		(fill yes
			(thermal_gap 0.5)
			(thermal_bridge_width 0.5)
			(island_removal_mode 0)
		)
		(polygon
			(pts
				(arc
					(start 183.946292 -267.885418)
					(mid 183.285892 -267.885418)
					(end 183.946292 -267.885418)
				)
			)
		)
	)
	(zone
		(layers "In1.Cu" "In2.Cu")
		(hatch none 0.5)
		(connect_pads
			(clearance 0)
		)
		(min_thickness 0.25)
		(keepout
			(tracks not_allowed)
			(vias allowed)
			(pads allowed)
			(copperpour not_allowed)
			(footprints allowed)
		)
		(placement
			(enabled no)
			(sheetname "")
		)
		(fill yes
			(thermal_gap 0.5)
			(thermal_bridge_width 0.5)
			(island_removal_mode 0)
		)
		(polygon
			(pts
				(arc
					(start 52.214272 -203.285344)
					(mid 51.553872 -203.285344)
					(end 52.214272 -203.285344)
				)
			)
		)
	)
	(zone
		(layers "In1.Cu" "In2.Cu")
		(hatch none 0.5)
		(connect_pads
			(clearance 0)
		)
		(min_thickness 0.25)
		(keepout
			(tracks not_allowed)
			(vias allowed)
			(pads allowed)
			(copperpour not_allowed)
			(footprints allowed)
		)
		(placement
			(enabled no)
			(sheetname "")
		)
		(fill yes
			(thermal_gap 0.5)
			(thermal_bridge_width 0.5)
			(island_removal_mode 0)
		)
		(polygon
			(pts
				(arc
					(start 439.430414 -210.935062)
					(mid 438.770014 -210.935062)
					(end 439.430414 -210.935062)
				)
			)
		)
	)
	(zone
		(layers "In1.Cu" "In2.Cu")
		(hatch none 0.5)
		(connect_pads
			(clearance 0)
		)
		(min_thickness 0.25)
		(keepout
			(tracks not_allowed)
			(vias allowed)
			(pads allowed)
			(copperpour not_allowed)
			(footprints allowed)
		)
		(placement
			(enabled no)
			(sheetname "")
		)
		(fill yes
			(thermal_gap 0.5)
			(thermal_bridge_width 0.5)
			(island_removal_mode 0)
		)
		(polygon
			(pts
				(arc
					(start 62.893194 -408.860244)
					(mid 62.915512 -408.914126)
					(end 62.969394 -408.936444)
				)
				(arc
					(start 63.164974 -408.936444)
					(mid 63.18685 -408.933312)
					(end 63.206884 -408.923998)
				)
				(arc
					(start 63.500508 -408.731466)
					(mid 63.542164 -408.719064)
					(end 63.58382 -408.731466)
				)
				(arc
					(start 63.878714 -408.923998)
					(mid 63.898638 -408.933234)
					(end 63.92037 -408.936444)
				)
				(arc
					(start 64.114934 -408.936444)
					(mid 64.168816 -408.914126)
					(end 64.191134 -408.860244)
				)
				(arc
					(start 64.191134 -408.174444)
					(mid 64.168816 -408.120562)
					(end 64.114934 -408.098244)
				)
				(arc
					(start 63.92037 -408.098244)
					(mid 63.898626 -408.101412)
					(end 63.878714 -408.11069)
				)
				(arc
					(start 63.58255 -408.303476)
					(mid 63.540866 -408.315698)
					(end 63.499238 -408.303222)
				)
				(arc
					(start 63.205614 -408.11069)
					(mid 63.18569 -408.101454)
					(end 63.163958 -408.098244)
				)
				(arc
					(start 62.969394 -408.098244)
					(mid 62.915512 -408.120562)
					(end 62.893194 -408.174444)
				)
			)
		)
	)
	(zone
		(layers "In1.Cu" "In2.Cu")
		(hatch none 0.5)
		(connect_pads
			(clearance 0)
		)
		(min_thickness 0.25)
		(keepout
			(tracks not_allowed)
			(vias allowed)
			(pads allowed)
			(copperpour not_allowed)
			(footprints allowed)
		)
		(placement
			(enabled no)
			(sheetname "")
		)
		(fill yes
			(thermal_gap 0.5)
			(thermal_bridge_width 0.5)
			(island_removal_mode 0)
		)
		(polygon
			(pts
				(arc
					(start 52.214272 -245.785386)
					(mid 51.553872 -245.785386)
					(end 52.214272 -245.785386)
				)
			)
		)
	)
	(zone
		(layers "In1.Cu" "In2.Cu")
		(hatch none 0.5)
		(connect_pads
			(clearance 0)
		)
		(min_thickness 0.25)
		(keepout
			(tracks not_allowed)
			(vias allowed)
			(pads allowed)
			(copperpour not_allowed)
			(footprints allowed)
		)
		(placement
			(enabled no)
			(sheetname "")
		)
		(fill yes
			(thermal_gap 0.5)
			(thermal_bridge_width 0.5)
			(island_removal_mode 0)
		)
		(polygon
			(pts
				(arc
					(start 22.03831 -244.085364)
					(mid 21.37791 -244.085364)
					(end 22.03831 -244.085364)
				)
			)
		)
	)
	(zone
		(layers "In1.Cu" "In2.Cu")
		(hatch none 0.5)
		(connect_pads
			(clearance 0)
		)
		(min_thickness 0.25)
		(keepout
			(tracks not_allowed)
			(vias allowed)
			(pads allowed)
			(copperpour not_allowed)
			(footprints allowed)
		)
		(placement
			(enabled no)
			(sheetname "")
		)
		(fill yes
			(thermal_gap 0.5)
			(thermal_bridge_width 0.5)
			(island_removal_mode 0)
		)
		(polygon
			(pts
				(arc
					(start 179.846224 -207.535272)
					(mid 179.185824 -207.535272)
					(end 179.846224 -207.535272)
				)
			)
		)
	)
	(zone
		(layers "In1.Cu" "In2.Cu")
		(hatch none 0.5)
		(connect_pads
			(clearance 0)
		)
		(min_thickness 0.25)
		(keepout
			(tracks not_allowed)
			(vias allowed)
			(pads allowed)
			(copperpour not_allowed)
			(footprints allowed)
		)
		(placement
			(enabled no)
			(sheetname "")
		)
		(fill yes
			(thermal_gap 0.5)
			(thermal_bridge_width 0.5)
			(island_removal_mode 0)
		)
		(polygon
			(pts
				(arc
					(start 202.478132 -251.735336)
					(mid 201.817732 -251.735336)
					(end 202.478132 -251.735336)
				)
			)
		)
	)
	(zone
		(layers "In1.Cu" "In2.Cu")
		(hatch none 0.5)
		(connect_pads
			(clearance 0)
		)
		(min_thickness 0.25)
		(keepout
			(tracks not_allowed)
			(vias allowed)
			(pads allowed)
			(copperpour not_allowed)
			(footprints allowed)
		)
		(placement
			(enabled no)
			(sheetname "")
		)
		(fill yes
			(thermal_gap 0.5)
			(thermal_bridge_width 0.5)
			(island_removal_mode 0)
		)
		(polygon
			(pts
				(arc
					(start 450.4182 -276.38502)
					(mid 449.7578 -276.38502)
					(end 450.4182 -276.38502)
				)
			)
		)
	)
	(zone
		(layers "In1.Cu" "In2.Cu")
		(hatch none 0.5)
		(connect_pads
			(clearance 0)
		)
		(min_thickness 0.25)
		(keepout
			(tracks not_allowed)
			(vias allowed)
			(pads allowed)
			(copperpour not_allowed)
			(footprints allowed)
		)
		(placement
			(enabled no)
			(sheetname "")
		)
		(fill yes
			(thermal_gap 0.5)
			(thermal_bridge_width 0.5)
			(island_removal_mode 0)
		)
		(polygon
			(pts
				(arc
					(start 300.15434 -217.73515)
					(mid 299.49394 -217.73515)
					(end 300.15434 -217.73515)
				)
			)
		)
	)
	(zone
		(layers "In1.Cu" "In2.Cu")
		(hatch none 0.5)
		(connect_pads
			(clearance 0)
		)
		(min_thickness 0.25)
		(keepout
			(tracks not_allowed)
			(vias allowed)
			(pads allowed)
			(copperpour not_allowed)
			(footprints allowed)
		)
		(placement
			(enabled no)
			(sheetname "")
		)
		(fill yes
			(thermal_gap 0.5)
			(thermal_bridge_width 0.5)
			(island_removal_mode 0)
		)
		(polygon
			(pts
				(arc
					(start 17.938242 -199.8853)
					(mid 17.277842 -199.8853)
					(end 17.938242 -199.8853)
				)
			)
		)
	)
	(zone
		(layers "In1.Cu" "In2.Cu")
		(hatch none 0.5)
		(connect_pads
			(clearance 0)
		)
		(min_thickness 0.25)
		(keepout
			(tracks not_allowed)
			(vias allowed)
			(pads allowed)
			(copperpour not_allowed)
			(footprints allowed)
		)
		(placement
			(enabled no)
			(sheetname "")
		)
		(fill yes
			(thermal_gap 0.5)
			(thermal_bridge_width 0.5)
			(island_removal_mode 0)
		)
		(polygon
			(pts
				(arc
					(start 427.786292 -295.085008)
					(mid 427.125892 -295.085008)
					(end 427.786292 -295.085008)
				)
			)
		)
	)
	(zone
		(layers "In1.Cu" "In2.Cu")
		(hatch none 0.5)
		(connect_pads
			(clearance 0)
		)
		(min_thickness 0.25)
		(keepout
			(tracks not_allowed)
			(vias allowed)
			(pads allowed)
			(copperpour not_allowed)
			(footprints allowed)
		)
		(placement
			(enabled no)
			(sheetname "")
		)
		(fill yes
			(thermal_gap 0.5)
			(thermal_bridge_width 0.5)
			(island_removal_mode 0)
		)
		(polygon
			(pts
				(arc
					(start 292.610286 -270.43507)
					(mid 291.949886 -270.43507)
					(end 292.610286 -270.43507)
				)
			)
		)
	)
	(zone
		(layers "In1.Cu" "In2.Cu")
		(hatch none 0.5)
		(connect_pads
			(clearance 0)
		)
		(min_thickness 0.25)
		(keepout
			(tracks not_allowed)
			(vias allowed)
			(pads allowed)
			(copperpour not_allowed)
			(footprints allowed)
		)
		(placement
			(enabled no)
			(sheetname "")
		)
		(fill yes
			(thermal_gap 0.5)
			(thermal_bridge_width 0.5)
			(island_removal_mode 0)
		)
		(polygon
			(pts
				(arc
					(start 427.786292 -286.585152)
					(mid 427.125892 -286.585152)
					(end 427.786292 -286.585152)
				)
			)
		)
	)
	(zone
		(layers "In1.Cu" "In2.Cu")
		(hatch none 0.5)
		(connect_pads
			(clearance 0)
		)
		(min_thickness 0.25)
		(keepout
			(tracks not_allowed)
			(vias allowed)
			(pads allowed)
			(copperpour not_allowed)
			(footprints allowed)
		)
		(placement
			(enabled no)
			(sheetname "")
		)
		(fill yes
			(thermal_gap 0.5)
			(thermal_bridge_width 0.5)
			(island_removal_mode 0)
		)
		(polygon
			(pts
				(arc
					(start 172.30217 -282.335224)
					(mid 171.64177 -282.335224)
					(end 172.30217 -282.335224)
				)
			)
		)
	)
	(zone
		(layers "In1.Cu" "In2.Cu")
		(hatch none 0.5)
		(connect_pads
			(clearance 0)
		)
		(min_thickness 0.25)
		(keepout
			(tracks not_allowed)
			(vias allowed)
			(pads allowed)
			(copperpour not_allowed)
			(footprints allowed)
		)
		(placement
			(enabled no)
			(sheetname "")
		)
		(fill yes
			(thermal_gap 0.5)
			(thermal_bridge_width 0.5)
			(island_removal_mode 0)
		)
		(polygon
			(pts
				(arc
					(start 424.342306 -217.73515)
					(mid 423.681906 -217.73515)
					(end 424.342306 -217.73515)
				)
			)
		)
	)
	(zone
		(layers "In1.Cu" "In2.Cu")
		(hatch none 0.5)
		(connect_pads
			(clearance 0)
		)
		(min_thickness 0.25)
		(keepout
			(tracks not_allowed)
			(vias allowed)
			(pads allowed)
			(copperpour not_allowed)
			(footprints allowed)
		)
		(placement
			(enabled no)
			(sheetname "")
		)
		(fill yes
			(thermal_gap 0.5)
			(thermal_bridge_width 0.5)
			(island_removal_mode 0)
		)
		(polygon
			(pts
				(arc
					(start 427.786292 -226.235006)
					(mid 427.125892 -226.235006)
					(end 427.786292 -226.235006)
				)
			)
		)
	)
	(zone
		(layers "In1.Cu" "In2.Cu")
		(hatch none 0.5)
		(connect_pads
			(clearance 0)
		)
		(min_thickness 0.25)
		(keepout
			(tracks not_allowed)
			(vias allowed)
			(pads allowed)
			(copperpour not_allowed)
			(footprints allowed)
		)
		(placement
			(enabled no)
			(sheetname "")
		)
		(fill yes
			(thermal_gap 0.5)
			(thermal_bridge_width 0.5)
			(island_removal_mode 0)
		)
		(polygon
			(pts
				(arc
					(start 52.214272 -217.735404)
					(mid 51.553872 -217.735404)
					(end 52.214272 -217.735404)
				)
			)
		)
	)
	(zone
		(layers "In1.Cu" "In2.Cu")
		(hatch none 0.5)
		(connect_pads
			(clearance 0)
		)
		(min_thickness 0.25)
		(keepout
			(tracks not_allowed)
			(vias allowed)
			(pads allowed)
			(copperpour not_allowed)
			(footprints allowed)
		)
		(placement
			(enabled no)
			(sheetname "")
		)
		(fill yes
			(thermal_gap 0.5)
			(thermal_bridge_width 0.5)
			(island_removal_mode 0)
		)
		(polygon
			(pts
				(arc
					(start 442.8744 -230.485188)
					(mid 442.214 -230.485188)
					(end 442.8744 -230.485188)
				)
			)
		)
	)
	(zone
		(layers "In1.Cu" "In2.Cu")
		(hatch none 0.5)
		(connect_pads
			(clearance 0)
		)
		(min_thickness 0.25)
		(keepout
			(tracks not_allowed)
			(vias allowed)
			(pads allowed)
			(copperpour not_allowed)
			(footprints allowed)
		)
		(placement
			(enabled no)
			(sheetname "")
		)
		(fill yes
			(thermal_gap 0.5)
			(thermal_bridge_width 0.5)
			(island_removal_mode 0)
		)
		(polygon
			(pts
				(arc
					(start 29.582364 -309.535322)
					(mid 28.921964 -309.535322)
					(end 29.582364 -309.535322)
				)
			)
		)
	)
	(zone
		(layers "In1.Cu" "In2.Cu")
		(hatch none 0.5)
		(connect_pads
			(clearance 0)
		)
		(min_thickness 0.25)
		(keepout
			(tracks not_allowed)
			(vias allowed)
			(pads allowed)
			(copperpour not_allowed)
			(footprints allowed)
		)
		(placement
			(enabled no)
			(sheetname "")
		)
		(fill yes
			(thermal_gap 0.5)
			(thermal_bridge_width 0.5)
			(island_removal_mode 0)
		)
		(polygon
			(pts
				(arc
					(start 277.522432 -252.584966)
					(mid 276.862032 -252.584966)
					(end 277.522432 -252.584966)
				)
			)
		)
	)
	(zone
		(layers "In1.Cu" "In2.Cu")
		(hatch none 0.5)
		(connect_pads
			(clearance 0)
		)
		(min_thickness 0.25)
		(keepout
			(tracks not_allowed)
			(vias allowed)
			(pads allowed)
			(copperpour not_allowed)
			(footprints allowed)
		)
		(placement
			(enabled no)
			(sheetname "")
		)
		(fill yes
			(thermal_gap 0.5)
			(thermal_bridge_width 0.5)
			(island_removal_mode 0)
		)
		(polygon
			(pts
				(arc
					(start 191.490346 -311.235344)
					(mid 190.829946 -311.235344)
					(end 191.490346 -311.235344)
				)
			)
		)
	)
	(zone
		(layers "In1.Cu" "In2.Cu")
		(hatch none 0.5)
		(connect_pads
			(clearance 0)
		)
		(min_thickness 0.25)
		(keepout
			(tracks not_allowed)
			(vias allowed)
			(pads allowed)
			(copperpour not_allowed)
			(footprints allowed)
		)
		(placement
			(enabled no)
			(sheetname "")
		)
		(fill yes
			(thermal_gap 0.5)
			(thermal_bridge_width 0.5)
			(island_removal_mode 0)
		)
		(polygon
			(pts
				(arc
					(start 191.490346 -233.035348)
					(mid 190.829946 -233.035348)
					(end 191.490346 -233.035348)
				)
			)
		)
	)
	(zone
		(layers "In1.Cu" "In2.Cu")
		(hatch none 0.5)
		(connect_pads
			(clearance 0)
		)
		(min_thickness 0.25)
		(keepout
			(tracks not_allowed)
			(vias allowed)
			(pads allowed)
			(copperpour not_allowed)
			(footprints allowed)
		)
		(placement
			(enabled no)
			(sheetname "")
		)
		(fill yes
			(thermal_gap 0.5)
			(thermal_bridge_width 0.5)
			(island_removal_mode 0)
		)
		(polygon
			(pts
				(arc
					(start 442.8744 -248.335038)
					(mid 442.214 -248.335038)
					(end 442.8744 -248.335038)
				)
			)
		)
	)
	(zone
		(layers "In1.Cu" "In2.Cu")
		(hatch none 0.5)
		(connect_pads
			(clearance 0)
		)
		(min_thickness 0.25)
		(keepout
			(tracks not_allowed)
			(vias allowed)
			(pads allowed)
			(copperpour not_allowed)
			(footprints allowed)
		)
		(placement
			(enabled no)
			(sheetname "")
		)
		(fill yes
			(thermal_gap 0.5)
			(thermal_bridge_width 0.5)
			(island_removal_mode 0)
		)
		(polygon
			(pts
				(arc
					(start 179.846224 -205.83525)
					(mid 179.185824 -205.83525)
					(end 179.846224 -205.83525)
				)
			)
		)
	)
	(zone
		(layers "In1.Cu" "In2.Cu")
		(hatch none 0.5)
		(connect_pads
			(clearance 0)
		)
		(min_thickness 0.25)
		(keepout
			(tracks not_allowed)
			(vias allowed)
			(pads allowed)
			(copperpour not_allowed)
			(footprints allowed)
		)
		(placement
			(enabled no)
			(sheetname "")
		)
		(fill yes
			(thermal_gap 0.5)
			(thermal_bridge_width 0.5)
			(island_removal_mode 0)
		)
		(polygon
			(pts
				(arc
					(start 439.430414 -309.535068)
					(mid 438.770014 -309.535068)
					(end 439.430414 -309.535068)
				)
			)
		)
	)
	(zone
		(layers "In1.Cu" "In2.Cu")
		(hatch none 0.5)
		(connect_pads
			(clearance 0)
		)
		(min_thickness 0.25)
		(keepout
			(tracks not_allowed)
			(vias allowed)
			(pads allowed)
			(copperpour not_allowed)
			(footprints allowed)
		)
		(placement
			(enabled no)
			(sheetname "")
		)
		(fill yes
			(thermal_gap 0.5)
			(thermal_bridge_width 0.5)
			(island_removal_mode 0)
		)
		(polygon
			(pts
				(arc
					(start 22.03831 -311.235344)
					(mid 21.37791 -311.235344)
					(end 22.03831 -311.235344)
				)
			)
		)
	)
	(zone
		(layers "In1.Cu" "In2.Cu")
		(hatch none 0.5)
		(connect_pads
			(clearance 0)
		)
		(min_thickness 0.25)
		(keepout
			(tracks not_allowed)
			(vias allowed)
			(pads allowed)
			(copperpour not_allowed)
			(footprints allowed)
		)
		(placement
			(enabled no)
			(sheetname "")
		)
		(fill yes
			(thermal_gap 0.5)
			(thermal_bridge_width 0.5)
			(island_removal_mode 0)
		)
		(polygon
			(pts
				(arc
					(start 269.978378 -283.185108)
					(mid 269.317978 -283.185108)
					(end 269.978378 -283.185108)
				)
			)
		)
	)
	(zone
		(layers "In1.Cu" "In2.Cu")
		(hatch none 0.5)
		(connect_pads
			(clearance 0)
		)
		(min_thickness 0.25)
		(keepout
			(tracks not_allowed)
			(vias allowed)
			(pads allowed)
			(copperpour not_allowed)
			(footprints allowed)
		)
		(placement
			(enabled no)
			(sheetname "")
		)
		(fill yes
			(thermal_gap 0.5)
			(thermal_bridge_width 0.5)
			(island_removal_mode 0)
		)
		(polygon
			(pts
				(arc
					(start 285.066232 -266.185142)
					(mid 284.405832 -266.185142)
					(end 285.066232 -266.185142)
				)
			)
		)
	)
	(zone
		(layers "In1.Cu" "In2.Cu")
		(hatch none 0.5)
		(connect_pads
			(clearance 0)
		)
		(min_thickness 0.25)
		(keepout
			(tracks not_allowed)
			(vias allowed)
			(pads allowed)
			(copperpour not_allowed)
			(footprints allowed)
		)
		(placement
			(enabled no)
			(sheetname "")
		)
		(fill yes
			(thermal_gap 0.5)
			(thermal_bridge_width 0.5)
			(island_removal_mode 0)
		)
		(polygon
			(pts
				(arc
					(start 376.803412 -417.242244)
					(mid 376.82573 -417.296126)
					(end 376.879612 -417.318444)
				)
				(arc
					(start 377.075192 -417.318444)
					(mid 377.097068 -417.315312)
					(end 377.117102 -417.305998)
				)
				(arc
					(start 377.410726 -417.113466)
					(mid 377.452382 -417.101064)
					(end 377.494038 -417.113466)
				)
				(arc
					(start 377.788932 -417.305998)
					(mid 377.808856 -417.315234)
					(end 377.830588 -417.318444)
				)
				(arc
					(start 378.025152 -417.318444)
					(mid 378.079034 -417.296126)
					(end 378.101352 -417.242244)
				)
				(arc
					(start 378.101352 -416.556444)
					(mid 378.079034 -416.502562)
					(end 378.025152 -416.480244)
				)
				(arc
					(start 377.830588 -416.480244)
					(mid 377.808844 -416.483412)
					(end 377.788932 -416.49269)
				)
				(arc
					(start 377.492768 -416.685476)
					(mid 377.451084 -416.697698)
					(end 377.409456 -416.685222)
				)
				(arc
					(start 377.115832 -416.49269)
					(mid 377.095908 -416.483454)
					(end 377.074176 -416.480244)
				)
				(arc
					(start 376.879612 -416.480244)
					(mid 376.82573 -416.502562)
					(end 376.803412 -416.556444)
				)
			)
		)
	)
	(zone
		(layers "In1.Cu" "In2.Cu")
		(hatch none 0.5)
		(connect_pads
			(clearance 0)
		)
		(min_thickness 0.25)
		(keepout
			(tracks not_allowed)
			(vias allowed)
			(pads allowed)
			(copperpour not_allowed)
			(footprints allowed)
		)
		(placement
			(enabled no)
			(sheetname "")
		)
		(fill yes
			(thermal_gap 0.5)
			(thermal_bridge_width 0.5)
			(island_removal_mode 0)
		)
		(polygon
			(pts
				(arc
					(start 435.330346 -314.635134)
					(mid 434.669946 -314.635134)
					(end 435.330346 -314.635134)
				)
			)
		)
	)
	(zone
		(layers "In1.Cu" "In2.Cu")
		(hatch none 0.5)
		(connect_pads
			(clearance 0)
		)
		(min_thickness 0.25)
		(keepout
			(tracks not_allowed)
			(vias allowed)
			(pads allowed)
			(copperpour not_allowed)
			(footprints allowed)
		)
		(placement
			(enabled no)
			(sheetname "")
		)
		(fill yes
			(thermal_gap 0.5)
			(thermal_bridge_width 0.5)
			(island_removal_mode 0)
		)
		(polygon
			(pts
				(arc
					(start 450.4182 -295.085008)
					(mid 449.7578 -295.085008)
					(end 450.4182 -295.085008)
				)
			)
		)
	)
	(zone
		(layers "In1.Cu" "In2.Cu")
		(hatch none 0.5)
		(connect_pads
			(clearance 0)
		)
		(min_thickness 0.25)
		(keepout
			(tracks not_allowed)
			(vias allowed)
			(pads allowed)
			(copperpour not_allowed)
			(footprints allowed)
		)
		(placement
			(enabled no)
			(sheetname "")
		)
		(fill yes
			(thermal_gap 0.5)
			(thermal_bridge_width 0.5)
			(island_removal_mode 0)
		)
		(polygon
			(pts
				(arc
					(start 285.066232 -300.185074)
					(mid 284.405832 -300.185074)
					(end 285.066232 -300.185074)
				)
			)
		)
	)
	(zone
		(layers "In1.Cu" "In2.Cu")
		(hatch none 0.5)
		(connect_pads
			(clearance 0)
		)
		(min_thickness 0.25)
		(keepout
			(tracks not_allowed)
			(vias allowed)
			(pads allowed)
			(copperpour not_allowed)
			(footprints allowed)
		)
		(placement
			(enabled no)
			(sheetname "")
		)
		(fill yes
			(thermal_gap 0.5)
			(thermal_bridge_width 0.5)
			(island_removal_mode 0)
		)
		(polygon
			(pts
				(arc
					(start 450.4182 -243.234972)
					(mid 449.7578 -243.234972)
					(end 450.4182 -243.234972)
				)
			)
		)
	)
	(zone
		(layers "In1.Cu" "In2.Cu")
		(hatch none 0.5)
		(connect_pads
			(clearance 0)
		)
		(min_thickness 0.25)
		(keepout
			(tracks not_allowed)
			(vias allowed)
			(pads allowed)
			(copperpour not_allowed)
			(footprints allowed)
		)
		(placement
			(enabled no)
			(sheetname "")
		)
		(fill yes
			(thermal_gap 0.5)
			(thermal_bridge_width 0.5)
			(island_removal_mode 0)
		)
		(polygon
			(pts
				(arc
					(start 148.516594 -375.906284)
					(mid 148.536518 -375.91552)
					(end 148.55825 -375.91873)
				)
				(arc
					(start 148.752814 -375.91873)
					(mid 148.806696 -375.896412)
					(end 148.829014 -375.84253)
				)
				(arc
					(start 148.829014 -375.15673)
					(mid 148.806696 -375.102848)
					(end 148.752814 -375.08053)
				)
				(arc
					(start 148.55825 -375.08053)
					(mid 148.536506 -375.083698)
					(end 148.516594 -375.092976)
				)
				(arc
					(start 148.22043 -375.285762)
					(mid 148.178746 -375.297984)
					(end 148.137118 -375.285508)
				)
				(arc
					(start 147.843494 -375.092976)
					(mid 147.82357 -375.08374)
					(end 147.801838 -375.08053)
				)
				(arc
					(start 147.607274 -375.08053)
					(mid 147.553392 -375.102848)
					(end 147.531074 -375.15673)
				)
				(arc
					(start 147.531074 -375.84253)
					(mid 147.553392 -375.896412)
					(end 147.607274 -375.91873)
				)
				(arc
					(start 147.803108 -375.91873)
					(mid 147.824852 -375.915562)
					(end 147.844764 -375.906284)
				)
				(arc
					(start 148.138388 -375.713752)
					(mid 148.180044 -375.70135)
					(end 148.2217 -375.713752)
				)
			)
		)
	)
	(zone
		(layers "In1.Cu" "In2.Cu")
		(hatch none 0.5)
		(connect_pads
			(clearance 0)
		)
		(min_thickness 0.25)
		(keepout
			(tracks not_allowed)
			(vias allowed)
			(pads allowed)
			(copperpour not_allowed)
			(footprints allowed)
		)
		(placement
			(enabled no)
			(sheetname "")
		)
		(fill yes
			(thermal_gap 0.5)
			(thermal_bridge_width 0.5)
			(island_removal_mode 0)
		)
		(polygon
			(pts
				(arc
					(start 183.946292 -210.935316)
					(mid 183.285892 -210.935316)
					(end 183.946292 -210.935316)
				)
			)
		)
	)
	(zone
		(layers "In1.Cu" "In2.Cu")
		(hatch none 0.5)
		(connect_pads
			(clearance 0)
		)
		(min_thickness 0.25)
		(keepout
			(tracks not_allowed)
			(vias allowed)
			(pads allowed)
			(copperpour not_allowed)
			(footprints allowed)
		)
		(placement
			(enabled no)
			(sheetname "")
		)
		(fill yes
			(thermal_gap 0.5)
			(thermal_bridge_width 0.5)
			(island_removal_mode 0)
		)
		(polygon
			(pts
				(arc
					(start 435.330346 -295.085008)
					(mid 434.669946 -295.085008)
					(end 435.330346 -295.085008)
				)
			)
		)
	)
	(zone
		(layers "In1.Cu" "In2.Cu")
		(hatch none 0.5)
		(connect_pads
			(clearance 0)
		)
		(min_thickness 0.25)
		(keepout
			(tracks not_allowed)
			(vias allowed)
			(pads allowed)
			(copperpour not_allowed)
			(footprints allowed)
		)
		(placement
			(enabled no)
			(sheetname "")
		)
		(fill yes
			(thermal_gap 0.5)
			(thermal_bridge_width 0.5)
			(island_removal_mode 0)
		)
		(polygon
			(pts
				(arc
					(start 17.938242 -261.935214)
					(mid 17.277842 -261.935214)
					(end 17.938242 -261.935214)
				)
			)
		)
	)
	(zone
		(layers "In1.Cu" "In2.Cu")
		(hatch none 0.5)
		(connect_pads
			(clearance 0)
		)
		(min_thickness 0.25)
		(keepout
			(tracks not_allowed)
			(vias allowed)
			(pads allowed)
			(copperpour not_allowed)
			(footprints allowed)
		)
		(placement
			(enabled no)
			(sheetname "")
		)
		(fill yes
			(thermal_gap 0.5)
			(thermal_bridge_width 0.5)
			(island_removal_mode 0)
		)
		(polygon
			(pts
				(arc
					(start 277.522432 -225.385122)
					(mid 276.862032 -225.385122)
					(end 277.522432 -225.385122)
				)
			)
		)
	)
	(zone
		(layers "In1.Cu" "In2.Cu")
		(hatch none 0.5)
		(connect_pads
			(clearance 0)
		)
		(min_thickness 0.25)
		(keepout
			(tracks not_allowed)
			(vias allowed)
			(pads allowed)
			(copperpour not_allowed)
			(footprints allowed)
		)
		(placement
			(enabled no)
			(sheetname "")
		)
		(fill yes
			(thermal_gap 0.5)
			(thermal_bridge_width 0.5)
			(island_removal_mode 0)
		)
		(polygon
			(pts
				(arc
					(start 37.126164 -254.285242)
					(mid 36.465764 -254.285242)
					(end 37.126164 -254.285242)
				)
			)
		)
	)
	(zone
		(layers "In1.Cu" "In2.Cu")
		(hatch none 0.5)
		(connect_pads
			(clearance 0)
		)
		(min_thickness 0.25)
		(keepout
			(tracks not_allowed)
			(vias allowed)
			(pads allowed)
			(copperpour not_allowed)
			(footprints allowed)
		)
		(placement
			(enabled no)
			(sheetname "")
		)
		(fill yes
			(thermal_gap 0.5)
			(thermal_bridge_width 0.5)
			(island_removal_mode 0)
		)
		(polygon
			(pts
				(arc
					(start 296.054272 -265.335004)
					(mid 295.393872 -265.335004)
					(end 296.054272 -265.335004)
				)
			)
		)
	)
	(zone
		(layers "In1.Cu" "In2.Cu")
		(hatch none 0.5)
		(connect_pads
			(clearance 0)
		)
		(min_thickness 0.25)
		(keepout
			(tracks not_allowed)
			(vias allowed)
			(pads allowed)
			(copperpour not_allowed)
			(footprints allowed)
		)
		(placement
			(enabled no)
			(sheetname "")
		)
		(fill yes
			(thermal_gap 0.5)
			(thermal_bridge_width 0.5)
			(island_removal_mode 0)
		)
		(polygon
			(pts
				(arc
					(start 450.4182 -306.985162)
					(mid 449.7578 -306.985162)
					(end 450.4182 -306.985162)
				)
			)
		)
	)
	(zone
		(layers "In1.Cu" "In2.Cu")
		(hatch none 0.5)
		(connect_pads
			(clearance 0)
		)
		(min_thickness 0.25)
		(keepout
			(tracks not_allowed)
			(vias allowed)
			(pads allowed)
			(copperpour not_allowed)
			(footprints allowed)
		)
		(placement
			(enabled no)
			(sheetname "")
		)
		(fill yes
			(thermal_gap 0.5)
			(thermal_bridge_width 0.5)
			(island_removal_mode 0)
		)
		(polygon
			(pts
				(arc
					(start 40.57015 -306.985416)
					(mid 39.90975 -306.985416)
					(end 40.57015 -306.985416)
				)
			)
		)
	)
	(zone
		(layers "In1.Cu" "In2.Cu")
		(hatch none 0.5)
		(connect_pads
			(clearance 0)
		)
		(min_thickness 0.25)
		(keepout
			(tracks not_allowed)
			(vias allowed)
			(pads allowed)
			(copperpour not_allowed)
			(footprints allowed)
		)
		(placement
			(enabled no)
			(sheetname "")
		)
		(fill yes
			(thermal_gap 0.5)
			(thermal_bridge_width 0.5)
			(island_removal_mode 0)
		)
		(polygon
			(pts
				(arc
					(start 277.522432 -249.185176)
					(mid 276.862032 -249.185176)
					(end 277.522432 -249.185176)
				)
			)
		)
	)
	(zone
		(layers "In1.Cu" "In2.Cu")
		(hatch none 0.5)
		(connect_pads
			(clearance 0)
		)
		(min_thickness 0.25)
		(keepout
			(tracks not_allowed)
			(vias allowed)
			(pads allowed)
			(copperpour not_allowed)
			(footprints allowed)
		)
		(placement
			(enabled no)
			(sheetname "")
		)
		(fill yes
			(thermal_gap 0.5)
			(thermal_bridge_width 0.5)
			(island_removal_mode 0)
		)
		(polygon
			(pts
				(arc
					(start 446.974468 -307.835046)
					(mid 446.314068 -307.835046)
					(end 446.974468 -307.835046)
				)
			)
		)
	)
	(zone
		(layers "In1.Cu" "In2.Cu")
		(hatch none 0.5)
		(connect_pads
			(clearance 0)
		)
		(min_thickness 0.25)
		(keepout
			(tracks not_allowed)
			(vias allowed)
			(pads allowed)
			(copperpour not_allowed)
			(footprints allowed)
		)
		(placement
			(enabled no)
			(sheetname "")
		)
		(fill yes
			(thermal_gap 0.5)
			(thermal_bridge_width 0.5)
			(island_removal_mode 0)
		)
		(polygon
			(pts
				(arc
					(start 269.978378 -240.685066)
					(mid 269.317978 -240.685066)
					(end 269.978378 -240.685066)
				)
			)
		)
	)
	(zone
		(layers "In1.Cu" "In2.Cu")
		(hatch none 0.5)
		(connect_pads
			(clearance 0)
		)
		(min_thickness 0.25)
		(keepout
			(tracks not_allowed)
			(vias allowed)
			(pads allowed)
			(copperpour not_allowed)
			(footprints allowed)
		)
		(placement
			(enabled no)
			(sheetname "")
		)
		(fill yes
			(thermal_gap 0.5)
			(thermal_bridge_width 0.5)
			(island_removal_mode 0)
		)
		(polygon
			(pts
				(arc
					(start 273.422364 -230.485188)
					(mid 272.761964 -230.485188)
					(end 273.422364 -230.485188)
				)
			)
		)
	)
	(zone
		(layers "In1.Cu" "In2.Cu")
		(hatch none 0.5)
		(connect_pads
			(clearance 0)
		)
		(min_thickness 0.25)
		(keepout
			(tracks not_allowed)
			(vias allowed)
			(pads allowed)
			(copperpour not_allowed)
			(footprints allowed)
		)
		(placement
			(enabled no)
			(sheetname "")
		)
		(fill yes
			(thermal_gap 0.5)
			(thermal_bridge_width 0.5)
			(island_removal_mode 0)
		)
		(polygon
			(pts
				(arc
					(start 288.510218 -224.534984)
					(mid 287.849818 -224.534984)
					(end 288.510218 -224.534984)
				)
			)
		)
	)
	(zone
		(layers "In1.Cu" "In2.Cu")
		(hatch none 0.5)
		(connect_pads
			(clearance 0)
		)
		(min_thickness 0.25)
		(keepout
			(tracks not_allowed)
			(vias allowed)
			(pads allowed)
			(copperpour not_allowed)
			(footprints allowed)
		)
		(placement
			(enabled no)
			(sheetname "")
		)
		(fill yes
			(thermal_gap 0.5)
			(thermal_bridge_width 0.5)
			(island_removal_mode 0)
		)
		(polygon
			(pts
				(arc
					(start 172.30217 -238.985298)
					(mid 171.64177 -238.985298)
					(end 172.30217 -238.985298)
				)
			)
		)
	)
	(zone
		(layers "In1.Cu" "In2.Cu")
		(hatch none 0.5)
		(connect_pads
			(clearance 0)
		)
		(min_thickness 0.25)
		(keepout
			(tracks not_allowed)
			(vias allowed)
			(pads allowed)
			(copperpour not_allowed)
			(footprints allowed)
		)
		(placement
			(enabled no)
			(sheetname "")
		)
		(fill yes
			(thermal_gap 0.5)
			(thermal_bridge_width 0.5)
			(island_removal_mode 0)
		)
		(polygon
			(pts
				(arc
					(start 52.214272 -270.435324)
					(mid 51.553872 -270.435324)
					(end 52.214272 -270.435324)
				)
			)
		)
	)
	(zone
		(layers "In1.Cu" "In2.Cu")
		(hatch none 0.5)
		(connect_pads
			(clearance 0)
		)
		(min_thickness 0.25)
		(keepout
			(tracks not_allowed)
			(vias allowed)
			(pads allowed)
			(copperpour not_allowed)
			(footprints allowed)
		)
		(placement
			(enabled no)
			(sheetname "")
		)
		(fill yes
			(thermal_gap 0.5)
			(thermal_bridge_width 0.5)
			(island_removal_mode 0)
		)
		(polygon
			(pts
				(arc
					(start 435.330346 -230.485188)
					(mid 434.669946 -230.485188)
					(end 435.330346 -230.485188)
				)
			)
		)
	)
	(zone
		(layers "In1.Cu" "In2.Cu")
		(hatch none 0.5)
		(connect_pads
			(clearance 0)
		)
		(min_thickness 0.25)
		(keepout
			(tracks not_allowed)
			(vias allowed)
			(pads allowed)
			(copperpour not_allowed)
			(footprints allowed)
		)
		(placement
			(enabled no)
			(sheetname "")
		)
		(fill yes
			(thermal_gap 0.5)
			(thermal_bridge_width 0.5)
			(island_removal_mode 0)
		)
		(polygon
			(pts
				(arc
					(start 22.03831 -300.185328)
					(mid 21.37791 -300.185328)
					(end 22.03831 -300.185328)
				)
			)
		)
	)
	(zone
		(layers "In1.Cu" "In2.Cu")
		(hatch none 0.5)
		(connect_pads
			(clearance 0)
		)
		(min_thickness 0.25)
		(keepout
			(tracks not_allowed)
			(vias allowed)
			(pads allowed)
			(copperpour not_allowed)
			(footprints allowed)
		)
		(placement
			(enabled no)
			(sheetname "")
		)
		(fill yes
			(thermal_gap 0.5)
			(thermal_bridge_width 0.5)
			(island_removal_mode 0)
		)
		(polygon
			(pts
				(arc
					(start 172.30217 -230.485442)
					(mid 171.64177 -230.485442)
					(end 172.30217 -230.485442)
				)
			)
		)
	)
	(zone
		(layers "In1.Cu" "In2.Cu")
		(hatch none 0.5)
		(connect_pads
			(clearance 0)
		)
		(min_thickness 0.25)
		(keepout
			(tracks not_allowed)
			(vias allowed)
			(pads allowed)
			(copperpour not_allowed)
			(footprints allowed)
		)
		(placement
			(enabled no)
			(sheetname "")
		)
		(fill yes
			(thermal_gap 0.5)
			(thermal_bridge_width 0.5)
			(island_removal_mode 0)
		)
		(polygon
			(pts
				(arc
					(start 33.026096 -284.035246)
					(mid 32.365696 -284.035246)
					(end 33.026096 -284.035246)
				)
			)
		)
	)
	(zone
		(layers "In1.Cu" "In2.Cu")
		(hatch none 0.5)
		(connect_pads
			(clearance 0)
		)
		(min_thickness 0.25)
		(keepout
			(tracks not_allowed)
			(vias allowed)
			(pads allowed)
			(copperpour not_allowed)
			(footprints allowed)
		)
		(placement
			(enabled no)
			(sheetname "")
		)
		(fill yes
			(thermal_gap 0.5)
			(thermal_bridge_width 0.5)
			(island_removal_mode 0)
		)
		(polygon
			(pts
				(arc
					(start 191.490346 -201.585322)
					(mid 190.829946 -201.585322)
					(end 191.490346 -201.585322)
				)
			)
		)
	)
	(zone
		(layers "In1.Cu" "In2.Cu")
		(hatch none 0.5)
		(connect_pads
			(clearance 0)
		)
		(min_thickness 0.25)
		(keepout
			(tracks not_allowed)
			(vias allowed)
			(pads allowed)
			(copperpour not_allowed)
			(footprints allowed)
		)
		(placement
			(enabled no)
			(sheetname "")
		)
		(fill yes
			(thermal_gap 0.5)
			(thermal_bridge_width 0.5)
			(island_removal_mode 0)
		)
		(polygon
			(pts
				(arc
					(start 450.4182 -272.984976)
					(mid 449.7578 -272.984976)
					(end 450.4182 -272.984976)
				)
			)
		)
	)
	(zone
		(layers "In1.Cu" "In2.Cu")
		(hatch none 0.5)
		(connect_pads
			(clearance 0)
		)
		(min_thickness 0.25)
		(keepout
			(tracks not_allowed)
			(vias allowed)
			(pads allowed)
			(copperpour not_allowed)
			(footprints allowed)
		)
		(placement
			(enabled no)
			(sheetname "")
		)
		(fill yes
			(thermal_gap 0.5)
			(thermal_bridge_width 0.5)
			(island_removal_mode 0)
		)
		(polygon
			(pts
				(arc
					(start 288.510218 -239.835182)
					(mid 287.849818 -239.835182)
					(end 288.510218 -239.835182)
				)
			)
		)
	)
	(zone
		(layers "In1.Cu" "In2.Cu")
		(hatch none 0.5)
		(connect_pads
			(clearance 0)
		)
		(min_thickness 0.25)
		(keepout
			(tracks not_allowed)
			(vias allowed)
			(pads allowed)
			(copperpour not_allowed)
			(footprints allowed)
		)
		(placement
			(enabled no)
			(sheetname "")
		)
		(fill yes
			(thermal_gap 0.5)
			(thermal_bridge_width 0.5)
			(island_removal_mode 0)
		)
		(polygon
			(pts
				(arc
					(start 427.786292 -230.485188)
					(mid 427.125892 -230.485188)
					(end 427.786292 -230.485188)
				)
			)
		)
	)
	(zone
		(layers "In1.Cu" "In2.Cu")
		(hatch none 0.5)
		(connect_pads
			(clearance 0)
		)
		(min_thickness 0.25)
		(keepout
			(tracks not_allowed)
			(vias allowed)
			(pads allowed)
			(copperpour not_allowed)
			(footprints allowed)
		)
		(placement
			(enabled no)
			(sheetname "")
		)
		(fill yes
			(thermal_gap 0.5)
			(thermal_bridge_width 0.5)
			(island_removal_mode 0)
		)
		(polygon
			(pts
				(arc
					(start 450.4182 -304.435002)
					(mid 449.7578 -304.435002)
					(end 450.4182 -304.435002)
				)
			)
		)
	)
	(zone
		(layers "In1.Cu" "In2.Cu")
		(hatch none 0.5)
		(connect_pads
			(clearance 0)
		)
		(min_thickness 0.25)
		(keepout
			(tracks not_allowed)
			(vias allowed)
			(pads allowed)
			(copperpour not_allowed)
			(footprints allowed)
		)
		(placement
			(enabled no)
			(sheetname "")
		)
		(fill yes
			(thermal_gap 0.5)
			(thermal_bridge_width 0.5)
			(island_removal_mode 0)
		)
		(polygon
			(pts
				(arc
					(start 37.126164 -234.73537)
					(mid 36.465764 -234.73537)
					(end 37.126164 -234.73537)
				)
			)
		)
	)
	(zone
		(layers "In1.Cu" "In2.Cu")
		(hatch none 0.5)
		(connect_pads
			(clearance 0)
		)
		(min_thickness 0.25)
		(keepout
			(tracks not_allowed)
			(vias allowed)
			(pads allowed)
			(copperpour not_allowed)
			(footprints allowed)
		)
		(placement
			(enabled no)
			(sheetname "")
		)
		(fill yes
			(thermal_gap 0.5)
			(thermal_bridge_width 0.5)
			(island_removal_mode 0)
		)
		(polygon
			(pts
				(arc
					(start 277.522432 -279.785064)
					(mid 276.862032 -279.785064)
					(end 277.522432 -279.785064)
				)
			)
		)
	)
	(zone
		(layers "In1.Cu" "In2.Cu")
		(hatch none 0.5)
		(connect_pads
			(clearance 0)
		)
		(min_thickness 0.25)
		(keepout
			(tracks not_allowed)
			(vias allowed)
			(pads allowed)
			(copperpour not_allowed)
			(footprints allowed)
		)
		(placement
			(enabled no)
			(sheetname "")
		)
		(fill yes
			(thermal_gap 0.5)
			(thermal_bridge_width 0.5)
			(island_removal_mode 0)
		)
		(polygon
			(pts
				(arc
					(start 59.829954 -408.860244)
					(mid 59.852272 -408.914126)
					(end 59.906154 -408.936444)
				)
				(arc
					(start 60.101734 -408.936444)
					(mid 60.12361 -408.933312)
					(end 60.143644 -408.923998)
				)
				(arc
					(start 60.437268 -408.731466)
					(mid 60.478924 -408.719064)
					(end 60.52058 -408.731466)
				)
				(arc
					(start 60.815474 -408.923998)
					(mid 60.835398 -408.933234)
					(end 60.85713 -408.936444)
				)
				(arc
					(start 61.051694 -408.936444)
					(mid 61.105576 -408.914126)
					(end 61.127894 -408.860244)
				)
				(arc
					(start 61.127894 -408.174444)
					(mid 61.105576 -408.120562)
					(end 61.051694 -408.098244)
				)
				(arc
					(start 60.85713 -408.098244)
					(mid 60.835386 -408.101412)
					(end 60.815474 -408.11069)
				)
				(arc
					(start 60.51931 -408.303476)
					(mid 60.477626 -408.315698)
					(end 60.435998 -408.303222)
				)
				(arc
					(start 60.142374 -408.11069)
					(mid 60.12245 -408.101454)
					(end 60.100718 -408.098244)
				)
				(arc
					(start 59.906154 -408.098244)
					(mid 59.852272 -408.120562)
					(end 59.829954 -408.174444)
				)
			)
		)
	)
	(zone
		(layers "In1.Cu" "In2.Cu")
		(hatch none 0.5)
		(connect_pads
			(clearance 0)
		)
		(min_thickness 0.25)
		(keepout
			(tracks not_allowed)
			(vias allowed)
			(pads allowed)
			(copperpour not_allowed)
			(footprints allowed)
		)
		(placement
			(enabled no)
			(sheetname "")
		)
		(fill yes
			(thermal_gap 0.5)
			(thermal_bridge_width 0.5)
			(island_removal_mode 0)
		)
		(polygon
			(pts
				(arc
					(start 288.510218 -274.684998)
					(mid 287.849818 -274.684998)
					(end 288.510218 -274.684998)
				)
			)
		)
	)
	(zone
		(layers "In1.Cu" "In2.Cu")
		(hatch none 0.5)
		(connect_pads
			(clearance 0)
		)
		(min_thickness 0.25)
		(keepout
			(tracks not_allowed)
			(vias allowed)
			(pads allowed)
			(copperpour not_allowed)
			(footprints allowed)
		)
		(placement
			(enabled no)
			(sheetname "")
		)
		(fill yes
			(thermal_gap 0.5)
			(thermal_bridge_width 0.5)
			(island_removal_mode 0)
		)
		(polygon
			(pts
				(arc
					(start 199.0344 -267.885418)
					(mid 198.374 -267.885418)
					(end 199.0344 -267.885418)
				)
			)
		)
	)
	(zone
		(layers "In1.Cu" "In2.Cu")
		(hatch none 0.5)
		(connect_pads
			(clearance 0)
		)
		(min_thickness 0.25)
		(keepout
			(tracks not_allowed)
			(vias allowed)
			(pads allowed)
			(copperpour not_allowed)
			(footprints allowed)
		)
		(placement
			(enabled no)
			(sheetname "")
		)
		(fill yes
			(thermal_gap 0.5)
			(thermal_bridge_width 0.5)
			(island_removal_mode 0)
		)
		(polygon
			(pts
				(arc
					(start 277.522432 -300.185074)
					(mid 276.862032 -300.185074)
					(end 277.522432 -300.185074)
				)
			)
		)
	)
	(zone
		(layers "In1.Cu" "In2.Cu")
		(hatch none 0.5)
		(connect_pads
			(clearance 0)
		)
		(min_thickness 0.25)
		(keepout
			(tracks not_allowed)
			(vias allowed)
			(pads allowed)
			(copperpour not_allowed)
			(footprints allowed)
		)
		(placement
			(enabled no)
			(sheetname "")
		)
		(fill yes
			(thermal_gap 0.5)
			(thermal_bridge_width 0.5)
			(island_removal_mode 0)
		)
		(polygon
			(pts
				(arc
					(start 187.390278 -253.435358)
					(mid 186.729878 -253.435358)
					(end 187.390278 -253.435358)
				)
			)
		)
	)
	(zone
		(layers "In1.Cu" "In2.Cu")
		(hatch none 0.5)
		(connect_pads
			(clearance 0)
		)
		(min_thickness 0.25)
		(keepout
			(tracks not_allowed)
			(vias allowed)
			(pads allowed)
			(copperpour not_allowed)
			(footprints allowed)
		)
		(placement
			(enabled no)
			(sheetname "")
		)
		(fill yes
			(thermal_gap 0.5)
			(thermal_bridge_width 0.5)
			(island_removal_mode 0)
		)
		(polygon
			(pts
				(arc
					(start 187.390278 -306.985416)
					(mid 186.729878 -306.985416)
					(end 187.390278 -306.985416)
				)
			)
		)
	)
	(zone
		(layers "In1.Cu" "In2.Cu")
		(hatch none 0.5)
		(connect_pads
			(clearance 0)
		)
		(min_thickness 0.25)
		(keepout
			(tracks not_allowed)
			(vias allowed)
			(pads allowed)
			(copperpour not_allowed)
			(footprints allowed)
		)
		(placement
			(enabled no)
			(sheetname "")
		)
		(fill yes
			(thermal_gap 0.5)
			(thermal_bridge_width 0.5)
			(island_removal_mode 0)
		)
		(polygon
			(pts
				(arc
					(start 280.966164 -241.53495)
					(mid 280.305764 -241.53495)
					(end 280.966164 -241.53495)
				)
			)
		)
	)
	(zone
		(layers "In1.Cu" "In2.Cu")
		(hatch none 0.5)
		(connect_pads
			(clearance 0)
		)
		(min_thickness 0.25)
		(keepout
			(tracks not_allowed)
			(vias allowed)
			(pads allowed)
			(copperpour not_allowed)
			(footprints allowed)
		)
		(placement
			(enabled no)
			(sheetname "")
		)
		(fill yes
			(thermal_gap 0.5)
			(thermal_bridge_width 0.5)
			(island_removal_mode 0)
		)
		(polygon
			(pts
				(arc
					(start 288.510218 -277.235158)
					(mid 287.849818 -277.235158)
					(end 288.510218 -277.235158)
				)
			)
		)
	)
	(zone
		(layers "In1.Cu" "In2.Cu")
		(hatch none 0.5)
		(connect_pads
			(clearance 0)
		)
		(min_thickness 0.25)
		(keepout
			(tracks not_allowed)
			(vias allowed)
			(pads allowed)
			(copperpour not_allowed)
			(footprints allowed)
		)
		(placement
			(enabled no)
			(sheetname "")
		)
		(fill yes
			(thermal_gap 0.5)
			(thermal_bridge_width 0.5)
			(island_removal_mode 0)
		)
		(polygon
			(pts
				(arc
					(start 37.126164 -264.485374)
					(mid 36.465764 -264.485374)
					(end 37.126164 -264.485374)
				)
			)
		)
	)
	(zone
		(layers "In1.Cu" "In2.Cu")
		(hatch none 0.5)
		(connect_pads
			(clearance 0)
		)
		(min_thickness 0.25)
		(keepout
			(tracks not_allowed)
			(vias allowed)
			(pads allowed)
			(copperpour not_allowed)
			(footprints allowed)
		)
		(placement
			(enabled no)
			(sheetname "")
		)
		(fill yes
			(thermal_gap 0.5)
			(thermal_bridge_width 0.5)
			(island_removal_mode 0)
		)
		(polygon
			(pts
				(arc
					(start 300.15434 -240.685066)
					(mid 299.49394 -240.685066)
					(end 300.15434 -240.685066)
				)
			)
		)
	)
	(zone
		(layers "In1.Cu" "In2.Cu")
		(hatch none 0.5)
		(connect_pads
			(clearance 0)
		)
		(min_thickness 0.25)
		(keepout
			(tracks not_allowed)
			(vias allowed)
			(pads allowed)
			(copperpour not_allowed)
			(footprints allowed)
		)
		(placement
			(enabled no)
			(sheetname "")
		)
		(fill yes
			(thermal_gap 0.5)
			(thermal_bridge_width 0.5)
			(island_removal_mode 0)
		)
		(polygon
			(pts
				(arc
					(start 22.03831 -238.135414)
					(mid 21.37791 -238.135414)
					(end 22.03831 -238.135414)
				)
			)
		)
	)
	(zone
		(layers "In1.Cu" "In2.Cu")
		(hatch none 0.5)
		(connect_pads
			(clearance 0)
		)
		(min_thickness 0.25)
		(keepout
			(tracks not_allowed)
			(vias allowed)
			(pads allowed)
			(copperpour not_allowed)
			(footprints allowed)
		)
		(placement
			(enabled no)
			(sheetname "")
		)
		(fill yes
			(thermal_gap 0.5)
			(thermal_bridge_width 0.5)
			(island_removal_mode 0)
		)
		(polygon
			(pts
				(arc
					(start 52.214272 -225.385376)
					(mid 51.553872 -225.385376)
					(end 52.214272 -225.385376)
				)
			)
		)
	)
	(zone
		(layers "In1.Cu" "In2.Cu")
		(hatch none 0.5)
		(connect_pads
			(clearance 0)
		)
		(min_thickness 0.25)
		(keepout
			(tracks not_allowed)
			(vias allowed)
			(pads allowed)
			(copperpour not_allowed)
			(footprints allowed)
		)
		(placement
			(enabled no)
			(sheetname "")
		)
		(fill yes
			(thermal_gap 0.5)
			(thermal_bridge_width 0.5)
			(island_removal_mode 0)
		)
		(polygon
			(pts
				(arc
					(start 17.938242 -215.185244)
					(mid 17.277842 -215.185244)
					(end 17.938242 -215.185244)
				)
			)
		)
	)
	(zone
		(layers "In1.Cu" "In2.Cu")
		(hatch none 0.5)
		(connect_pads
			(clearance 0)
		)
		(min_thickness 0.25)
		(keepout
			(tracks not_allowed)
			(vias allowed)
			(pads allowed)
			(copperpour not_allowed)
			(footprints allowed)
		)
		(placement
			(enabled no)
			(sheetname "")
		)
		(fill yes
			(thermal_gap 0.5)
			(thermal_bridge_width 0.5)
			(island_removal_mode 0)
		)
		(polygon
			(pts
				(arc
					(start 450.4182 -297.635168)
					(mid 449.7578 -297.635168)
					(end 450.4182 -297.635168)
				)
			)
		)
	)
	(zone
		(layers "In1.Cu" "In2.Cu")
		(hatch none 0.5)
		(connect_pads
			(clearance 0)
		)
		(min_thickness 0.25)
		(keepout
			(tracks not_allowed)
			(vias allowed)
			(pads allowed)
			(copperpour not_allowed)
			(footprints allowed)
		)
		(placement
			(enabled no)
			(sheetname "")
		)
		(fill yes
			(thermal_gap 0.5)
			(thermal_bridge_width 0.5)
			(island_removal_mode 0)
		)
		(polygon
			(pts
				(arc
					(start 44.670218 -276.385274)
					(mid 44.009818 -276.385274)
					(end 44.670218 -276.385274)
				)
			)
		)
	)
	(zone
		(layers "In1.Cu" "In2.Cu")
		(hatch none 0.5)
		(connect_pads
			(clearance 0)
		)
		(min_thickness 0.25)
		(keepout
			(tracks not_allowed)
			(vias allowed)
			(pads allowed)
			(copperpour not_allowed)
			(footprints allowed)
		)
		(placement
			(enabled no)
			(sheetname "")
		)
		(fill yes
			(thermal_gap 0.5)
			(thermal_bridge_width 0.5)
			(island_removal_mode 0)
		)
		(polygon
			(pts
				(arc
					(start 296.054272 -205.834996)
					(mid 295.393872 -205.834996)
					(end 296.054272 -205.834996)
				)
			)
		)
	)
	(zone
		(layers "In1.Cu" "In2.Cu")
		(hatch none 0.5)
		(connect_pads
			(clearance 0)
		)
		(min_thickness 0.25)
		(keepout
			(tracks not_allowed)
			(vias allowed)
			(pads allowed)
			(copperpour not_allowed)
			(footprints allowed)
		)
		(placement
			(enabled no)
			(sheetname "")
		)
		(fill yes
			(thermal_gap 0.5)
			(thermal_bridge_width 0.5)
			(island_removal_mode 0)
		)
		(polygon
			(pts
				(arc
					(start 296.054272 -250.03506)
					(mid 295.393872 -250.03506)
					(end 296.054272 -250.03506)
				)
			)
		)
	)
	(zone
		(layers "In1.Cu" "In2.Cu")
		(hatch none 0.5)
		(connect_pads
			(clearance 0)
		)
		(min_thickness 0.25)
		(keepout
			(tracks not_allowed)
			(vias allowed)
			(pads allowed)
			(copperpour not_allowed)
			(footprints allowed)
		)
		(placement
			(enabled no)
			(sheetname "")
		)
		(fill yes
			(thermal_gap 0.5)
			(thermal_bridge_width 0.5)
			(island_removal_mode 0)
		)
		(polygon
			(pts
				(arc
					(start 17.938242 -209.235294)
					(mid 17.277842 -209.235294)
					(end 17.938242 -209.235294)
				)
			)
		)
	)
	(zone
		(layers "In1.Cu" "In2.Cu")
		(hatch none 0.5)
		(connect_pads
			(clearance 0)
		)
		(min_thickness 0.25)
		(keepout
			(tracks not_allowed)
			(vias allowed)
			(pads allowed)
			(copperpour not_allowed)
			(footprints allowed)
		)
		(placement
			(enabled no)
			(sheetname "")
		)
		(fill yes
			(thermal_gap 0.5)
			(thermal_bridge_width 0.5)
			(island_removal_mode 0)
		)
		(polygon
			(pts
				(arc
					(start 187.390278 -305.285394)
					(mid 186.729878 -305.285394)
					(end 187.390278 -305.285394)
				)
			)
		)
	)
	(zone
		(layers "In1.Cu" "In2.Cu")
		(hatch none 0.5)
		(connect_pads
			(clearance 0)
		)
		(min_thickness 0.25)
		(keepout
			(tracks not_allowed)
			(vias allowed)
			(pads allowed)
			(copperpour not_allowed)
			(footprints allowed)
		)
		(placement
			(enabled no)
			(sheetname "")
		)
		(fill yes
			(thermal_gap 0.5)
			(thermal_bridge_width 0.5)
			(island_removal_mode 0)
		)
		(polygon
			(pts
				(arc
					(start 29.582364 -285.735268)
					(mid 28.921964 -285.735268)
					(end 29.582364 -285.735268)
				)
			)
		)
	)
	(zone
		(layers "In1.Cu" "In2.Cu")
		(hatch none 0.5)
		(connect_pads
			(clearance 0)
		)
		(min_thickness 0.25)
		(keepout
			(tracks not_allowed)
			(vias allowed)
			(pads allowed)
			(copperpour not_allowed)
			(footprints allowed)
		)
		(placement
			(enabled no)
			(sheetname "")
		)
		(fill yes
			(thermal_gap 0.5)
			(thermal_bridge_width 0.5)
			(island_removal_mode 0)
		)
		(polygon
			(pts
				(arc
					(start 446.974468 -303.585118)
					(mid 446.314068 -303.585118)
					(end 446.974468 -303.585118)
				)
			)
		)
	)
	(zone
		(layers "In1.Cu" "In2.Cu")
		(hatch none 0.5)
		(connect_pads
			(clearance 0)
		)
		(min_thickness 0.25)
		(keepout
			(tracks not_allowed)
			(vias allowed)
			(pads allowed)
			(copperpour not_allowed)
			(footprints allowed)
		)
		(placement
			(enabled no)
			(sheetname "")
		)
		(fill yes
			(thermal_gap 0.5)
			(thermal_bridge_width 0.5)
			(island_removal_mode 0)
		)
		(polygon
			(pts
				(arc
					(start 454.518268 -292.535102)
					(mid 453.857868 -292.535102)
					(end 454.518268 -292.535102)
				)
			)
		)
	)
	(zone
		(layers "In1.Cu" "In2.Cu")
		(hatch none 0.5)
		(connect_pads
			(clearance 0)
		)
		(min_thickness 0.25)
		(keepout
			(tracks not_allowed)
			(vias allowed)
			(pads allowed)
			(copperpour not_allowed)
			(footprints allowed)
		)
		(placement
			(enabled no)
			(sheetname "")
		)
		(fill yes
			(thermal_gap 0.5)
			(thermal_bridge_width 0.5)
			(island_removal_mode 0)
		)
		(polygon
			(pts
				(arc
					(start 446.974468 -261.085076)
					(mid 446.314068 -261.085076)
					(end 446.974468 -261.085076)
				)
			)
		)
	)
	(zone
		(layers "In1.Cu" "In2.Cu")
		(hatch none 0.5)
		(connect_pads
			(clearance 0)
		)
		(min_thickness 0.25)
		(keepout
			(tracks not_allowed)
			(vias allowed)
			(pads allowed)
			(copperpour not_allowed)
			(footprints allowed)
		)
		(placement
			(enabled no)
			(sheetname "")
		)
		(fill yes
			(thermal_gap 0.5)
			(thermal_bridge_width 0.5)
			(island_removal_mode 0)
		)
		(polygon
			(pts
				(arc
					(start 285.066232 -289.135058)
					(mid 284.405832 -289.135058)
					(end 285.066232 -289.135058)
				)
			)
		)
	)
	(zone
		(layers "In1.Cu" "In2.Cu")
		(hatch none 0.5)
		(connect_pads
			(clearance 0)
		)
		(min_thickness 0.25)
		(keepout
			(tracks not_allowed)
			(vias allowed)
			(pads allowed)
			(copperpour not_allowed)
			(footprints allowed)
		)
		(placement
			(enabled no)
			(sheetname "")
		)
		(fill yes
			(thermal_gap 0.5)
			(thermal_bridge_width 0.5)
			(island_removal_mode 0)
		)
		(polygon
			(pts
				(arc
					(start 273.422364 -220.285056)
					(mid 272.761964 -220.285056)
					(end 273.422364 -220.285056)
				)
			)
		)
	)
	(zone
		(layers "In1.Cu" "In2.Cu")
		(hatch none 0.5)
		(connect_pads
			(clearance 0)
		)
		(min_thickness 0.25)
		(keepout
			(tracks not_allowed)
			(vias allowed)
			(pads allowed)
			(copperpour not_allowed)
			(footprints allowed)
		)
		(placement
			(enabled no)
			(sheetname "")
		)
		(fill yes
			(thermal_gap 0.5)
			(thermal_bridge_width 0.5)
			(island_removal_mode 0)
		)
		(polygon
			(pts
				(arc
					(start 439.430414 -269.585186)
					(mid 438.770014 -269.585186)
					(end 439.430414 -269.585186)
				)
			)
		)
	)
	(zone
		(layers "In1.Cu" "In2.Cu")
		(hatch none 0.5)
		(connect_pads
			(clearance 0)
		)
		(min_thickness 0.25)
		(keepout
			(tracks not_allowed)
			(vias allowed)
			(pads allowed)
			(copperpour not_allowed)
			(footprints allowed)
		)
		(placement
			(enabled no)
			(sheetname "")
		)
		(fill yes
			(thermal_gap 0.5)
			(thermal_bridge_width 0.5)
			(island_removal_mode 0)
		)
		(polygon
			(pts
				(arc
					(start 22.03831 -294.235378)
					(mid 21.37791 -294.235378)
					(end 22.03831 -294.235378)
				)
			)
		)
	)
	(zone
		(layers "In1.Cu" "In2.Cu")
		(hatch none 0.5)
		(connect_pads
			(clearance 0)
		)
		(min_thickness 0.25)
		(keepout
			(tracks not_allowed)
			(vias allowed)
			(pads allowed)
			(copperpour not_allowed)
			(footprints allowed)
		)
		(placement
			(enabled no)
			(sheetname "")
		)
		(fill yes
			(thermal_gap 0.5)
			(thermal_bridge_width 0.5)
			(island_removal_mode 0)
		)
		(polygon
			(pts
				(arc
					(start 446.974468 -201.585068)
					(mid 446.314068 -201.585068)
					(end 446.974468 -201.585068)
				)
			)
		)
	)
	(zone
		(layers "In1.Cu" "In2.Cu")
		(hatch none 0.5)
		(connect_pads
			(clearance 0)
		)
		(min_thickness 0.25)
		(keepout
			(tracks not_allowed)
			(vias allowed)
			(pads allowed)
			(copperpour not_allowed)
			(footprints allowed)
		)
		(placement
			(enabled no)
			(sheetname "")
		)
		(fill yes
			(thermal_gap 0.5)
			(thermal_bridge_width 0.5)
			(island_removal_mode 0)
		)
		(polygon
			(pts
				(arc
					(start 172.30217 -227.935282)
					(mid 171.64177 -227.935282)
					(end 172.30217 -227.935282)
				)
			)
		)
	)
	(zone
		(layers "In1.Cu" "In2.Cu")
		(hatch none 0.5)
		(connect_pads
			(clearance 0)
		)
		(min_thickness 0.25)
		(keepout
			(tracks not_allowed)
			(vias allowed)
			(pads allowed)
			(copperpour not_allowed)
			(footprints allowed)
		)
		(placement
			(enabled no)
			(sheetname "")
		)
		(fill yes
			(thermal_gap 0.5)
			(thermal_bridge_width 0.5)
			(island_removal_mode 0)
		)
		(polygon
			(pts
				(arc
					(start 52.214272 -220.28531)
					(mid 51.553872 -220.28531)
					(end 52.214272 -220.28531)
				)
			)
		)
	)
	(zone
		(layers "In1.Cu" "In2.Cu")
		(hatch none 0.5)
		(connect_pads
			(clearance 0)
		)
		(min_thickness 0.25)
		(keepout
			(tracks not_allowed)
			(vias allowed)
			(pads allowed)
			(copperpour not_allowed)
			(footprints allowed)
		)
		(placement
			(enabled no)
			(sheetname "")
		)
		(fill yes
			(thermal_gap 0.5)
			(thermal_bridge_width 0.5)
			(island_removal_mode 0)
		)
		(polygon
			(pts
				(arc
					(start 202.478132 -306.985416)
					(mid 201.817732 -306.985416)
					(end 202.478132 -306.985416)
				)
			)
		)
	)
	(zone
		(layers "In1.Cu" "In2.Cu")
		(hatch none 0.5)
		(connect_pads
			(clearance 0)
		)
		(min_thickness 0.25)
		(keepout
			(tracks not_allowed)
			(vias allowed)
			(pads allowed)
			(copperpour not_allowed)
			(footprints allowed)
		)
		(placement
			(enabled no)
			(sheetname "")
		)
		(fill yes
			(thermal_gap 0.5)
			(thermal_bridge_width 0.5)
			(island_removal_mode 0)
		)
		(polygon
			(pts
				(arc
					(start 183.946292 -238.985298)
					(mid 183.285892 -238.985298)
					(end 183.946292 -238.985298)
				)
			)
		)
	)
	(zone
		(layers "In1.Cu" "In2.Cu")
		(hatch none 0.5)
		(connect_pads
			(clearance 0)
		)
		(min_thickness 0.25)
		(keepout
			(tracks not_allowed)
			(vias allowed)
			(pads allowed)
			(copperpour not_allowed)
			(footprints allowed)
		)
		(placement
			(enabled no)
			(sheetname "")
		)
		(fill yes
			(thermal_gap 0.5)
			(thermal_bridge_width 0.5)
			(island_removal_mode 0)
		)
		(polygon
			(pts
				(arc
					(start 424.342306 -273.835114)
					(mid 423.681906 -273.835114)
					(end 424.342306 -273.835114)
				)
			)
		)
	)
	(zone
		(layers "In1.Cu" "In2.Cu")
		(hatch none 0.5)
		(connect_pads
			(clearance 0)
		)
		(min_thickness 0.25)
		(keepout
			(tracks not_allowed)
			(vias allowed)
			(pads allowed)
			(copperpour not_allowed)
			(footprints allowed)
		)
		(placement
			(enabled no)
			(sheetname "")
		)
		(fill yes
			(thermal_gap 0.5)
			(thermal_bridge_width 0.5)
			(island_removal_mode 0)
		)
		(polygon
			(pts
				(arc
					(start 280.966164 -286.585152)
					(mid 280.305764 -286.585152)
					(end 280.966164 -286.585152)
				)
			)
		)
	)
	(zone
		(layers "In1.Cu" "In2.Cu")
		(hatch none 0.5)
		(connect_pads
			(clearance 0)
		)
		(min_thickness 0.25)
		(keepout
			(tracks not_allowed)
			(vias allowed)
			(pads allowed)
			(copperpour not_allowed)
			(footprints allowed)
		)
		(placement
			(enabled no)
			(sheetname "")
		)
		(fill yes
			(thermal_gap 0.5)
			(thermal_bridge_width 0.5)
			(island_removal_mode 0)
		)
		(polygon
			(pts
				(arc
					(start 33.026096 -254.285242)
					(mid 32.365696 -254.285242)
					(end 33.026096 -254.285242)
				)
			)
		)
	)
	(zone
		(layers "In1.Cu" "In2.Cu")
		(hatch none 0.5)
		(connect_pads
			(clearance 0)
		)
		(min_thickness 0.25)
		(keepout
			(tracks not_allowed)
			(vias allowed)
			(pads allowed)
			(copperpour not_allowed)
			(footprints allowed)
		)
		(placement
			(enabled no)
			(sheetname "")
		)
		(fill yes
			(thermal_gap 0.5)
			(thermal_bridge_width 0.5)
			(island_removal_mode 0)
		)
		(polygon
			(pts
				(arc
					(start 199.0344 -249.18543)
					(mid 198.374 -249.18543)
					(end 199.0344 -249.18543)
				)
			)
		)
	)
	(zone
		(layers "In1.Cu" "In2.Cu")
		(hatch none 0.5)
		(connect_pads
			(clearance 0)
		)
		(min_thickness 0.25)
		(keepout
			(tracks not_allowed)
			(vias allowed)
			(pads allowed)
			(copperpour not_allowed)
			(footprints allowed)
		)
		(placement
			(enabled no)
			(sheetname "")
		)
		(fill yes
			(thermal_gap 0.5)
			(thermal_bridge_width 0.5)
			(island_removal_mode 0)
		)
		(polygon
			(pts
				(arc
					(start 22.03831 -272.135346)
					(mid 21.37791 -272.135346)
					(end 22.03831 -272.135346)
				)
			)
		)
	)
	(zone
		(layers "In1.Cu" "In2.Cu")
		(hatch none 0.5)
		(connect_pads
			(clearance 0)
		)
		(min_thickness 0.25)
		(keepout
			(tracks not_allowed)
			(vias allowed)
			(pads allowed)
			(copperpour not_allowed)
			(footprints allowed)
		)
		(placement
			(enabled no)
			(sheetname "")
		)
		(fill yes
			(thermal_gap 0.5)
			(thermal_bridge_width 0.5)
			(island_removal_mode 0)
		)
		(polygon
			(pts
				(arc
					(start 40.57015 -312.085228)
					(mid 39.90975 -312.085228)
					(end 40.57015 -312.085228)
				)
			)
		)
	)
	(zone
		(layers "In1.Cu" "In2.Cu")
		(hatch none 0.5)
		(connect_pads
			(clearance 0)
		)
		(min_thickness 0.25)
		(keepout
			(tracks not_allowed)
			(vias allowed)
			(pads allowed)
			(copperpour not_allowed)
			(footprints allowed)
		)
		(placement
			(enabled no)
			(sheetname "")
		)
		(fill yes
			(thermal_gap 0.5)
			(thermal_bridge_width 0.5)
			(island_removal_mode 0)
		)
		(polygon
			(pts
				(arc
					(start 130.052318 -12.952222)
					(mid 130.074636 -12.89834)
					(end 130.128518 -12.876022)
				)
				(arc
					(start 131.165092 -12.876022)
					(mid 131.218974 -12.89834)
					(end 131.241292 -12.952222)
				)
				(arc
					(start 131.241292 -14.351762)
					(mid 131.218974 -14.405644)
					(end 131.165092 -14.427962)
				)
				(arc
					(start 130.128518 -14.427962)
					(mid 130.074636 -14.405644)
					(end 130.052318 -14.351762)
				)
			)
		)
	)
	(zone
		(layers "In1.Cu" "In2.Cu")
		(hatch none 0.5)
		(connect_pads
			(clearance 0)
		)
		(min_thickness 0.25)
		(keepout
			(tracks not_allowed)
			(vias allowed)
			(pads allowed)
			(copperpour not_allowed)
			(footprints allowed)
		)
		(placement
			(enabled no)
			(sheetname "")
		)
		(fill yes
			(thermal_gap 0.5)
			(thermal_bridge_width 0.5)
			(island_removal_mode 0)
		)
		(polygon
			(pts
				(arc
					(start 179.846224 -250.035314)
					(mid 179.185824 -250.035314)
					(end 179.846224 -250.035314)
				)
			)
		)
	)
	(zone
		(layers "In1.Cu" "In2.Cu")
		(hatch none 0.5)
		(connect_pads
			(clearance 0)
		)
		(min_thickness 0.25)
		(keepout
			(tracks not_allowed)
			(vias allowed)
			(pads allowed)
			(copperpour not_allowed)
			(footprints allowed)
		)
		(placement
			(enabled no)
			(sheetname "")
		)
		(fill yes
			(thermal_gap 0.5)
			(thermal_bridge_width 0.5)
			(island_removal_mode 0)
		)
		(polygon
			(pts
				(arc
					(start 29.582364 -304.435256)
					(mid 28.921964 -304.435256)
					(end 29.582364 -304.435256)
				)
			)
		)
	)
	(zone
		(layers "In1.Cu" "In2.Cu")
		(hatch none 0.5)
		(connect_pads
			(clearance 0)
		)
		(min_thickness 0.25)
		(keepout
			(tracks not_allowed)
			(vias allowed)
			(pads allowed)
			(copperpour not_allowed)
			(footprints allowed)
		)
		(placement
			(enabled no)
			(sheetname "")
		)
		(fill yes
			(thermal_gap 0.5)
			(thermal_bridge_width 0.5)
			(island_removal_mode 0)
		)
		(polygon
			(pts
				(arc
					(start 199.0344 -236.435392)
					(mid 198.374 -236.435392)
					(end 199.0344 -236.435392)
				)
			)
		)
	)
	(zone
		(layers "In1.Cu" "In2.Cu")
		(hatch none 0.5)
		(connect_pads
			(clearance 0)
		)
		(min_thickness 0.25)
		(keepout
			(tracks not_allowed)
			(vias allowed)
			(pads allowed)
			(copperpour not_allowed)
			(footprints allowed)
		)
		(placement
			(enabled no)
			(sheetname "")
		)
		(fill yes
			(thermal_gap 0.5)
			(thermal_bridge_width 0.5)
			(island_removal_mode 0)
		)
		(polygon
			(pts
				(arc
					(start 194.934332 -284.035246)
					(mid 194.273932 -284.035246)
					(end 194.934332 -284.035246)
				)
			)
		)
	)
	(zone
		(layers "In1.Cu" "In2.Cu")
		(hatch none 0.5)
		(connect_pads
			(clearance 0)
		)
		(min_thickness 0.25)
		(keepout
			(tracks not_allowed)
			(vias allowed)
			(pads allowed)
			(copperpour not_allowed)
			(footprints allowed)
		)
		(placement
			(enabled no)
			(sheetname "")
		)
		(fill yes
			(thermal_gap 0.5)
			(thermal_bridge_width 0.5)
			(island_removal_mode 0)
		)
		(polygon
			(pts
				(arc
					(start 199.0344 -272.135346)
					(mid 198.374 -272.135346)
					(end 199.0344 -272.135346)
				)
			)
		)
	)
	(zone
		(layers "In1.Cu" "In2.Cu")
		(hatch none 0.5)
		(connect_pads
			(clearance 0)
		)
		(min_thickness 0.25)
		(keepout
			(tracks not_allowed)
			(vias allowed)
			(pads allowed)
			(copperpour not_allowed)
			(footprints allowed)
		)
		(placement
			(enabled no)
			(sheetname "")
		)
		(fill yes
			(thermal_gap 0.5)
			(thermal_bridge_width 0.5)
			(island_removal_mode 0)
		)
		(polygon
			(pts
				(arc
					(start 29.582364 -208.38541)
					(mid 28.921964 -208.38541)
					(end 29.582364 -208.38541)
				)
			)
		)
	)
	(zone
		(layers "In1.Cu" "In2.Cu")
		(hatch none 0.5)
		(connect_pads
			(clearance 0)
		)
		(min_thickness 0.25)
		(keepout
			(tracks not_allowed)
			(vias allowed)
			(pads allowed)
			(copperpour not_allowed)
			(footprints allowed)
		)
		(placement
			(enabled no)
			(sheetname "")
		)
		(fill yes
			(thermal_gap 0.5)
			(thermal_bridge_width 0.5)
			(island_removal_mode 0)
		)
		(polygon
			(pts
				(arc
					(start 202.478132 -244.935248)
					(mid 201.817732 -244.935248)
					(end 202.478132 -244.935248)
				)
			)
		)
	)
	(zone
		(layers "In1.Cu" "In2.Cu")
		(hatch none 0.5)
		(connect_pads
			(clearance 0)
		)
		(min_thickness 0.25)
		(keepout
			(tracks not_allowed)
			(vias allowed)
			(pads allowed)
			(copperpour not_allowed)
			(footprints allowed)
		)
		(placement
			(enabled no)
			(sheetname "")
		)
		(fill yes
			(thermal_gap 0.5)
			(thermal_bridge_width 0.5)
			(island_removal_mode 0)
		)
		(polygon
			(pts
				(arc
					(start 269.978378 -315.485018)
					(mid 269.317978 -315.485018)
					(end 269.978378 -315.485018)
				)
			)
		)
	)
	(zone
		(layers "In1.Cu" "In2.Cu")
		(hatch none 0.5)
		(connect_pads
			(clearance 0)
		)
		(min_thickness 0.25)
		(keepout
			(tracks not_allowed)
			(vias allowed)
			(pads allowed)
			(copperpour not_allowed)
			(footprints allowed)
		)
		(placement
			(enabled no)
			(sheetname "")
		)
		(fill yes
			(thermal_gap 0.5)
			(thermal_bridge_width 0.5)
			(island_removal_mode 0)
		)
		(polygon
			(pts
				(arc
					(start 183.946292 -289.135312)
					(mid 183.285892 -289.135312)
					(end 183.946292 -289.135312)
				)
			)
		)
	)
	(zone
		(layers "In1.Cu" "In2.Cu")
		(hatch none 0.5)
		(connect_pads
			(clearance 0)
		)
		(min_thickness 0.25)
		(keepout
			(tracks not_allowed)
			(vias allowed)
			(pads allowed)
			(copperpour not_allowed)
			(footprints allowed)
		)
		(placement
			(enabled no)
			(sheetname "")
		)
		(fill yes
			(thermal_gap 0.5)
			(thermal_bridge_width 0.5)
			(island_removal_mode 0)
		)
		(polygon
			(pts
				(arc
					(start 172.30217 -204.135228)
					(mid 171.64177 -204.135228)
					(end 172.30217 -204.135228)
				)
			)
		)
	)
	(zone
		(layers "In1.Cu" "In2.Cu")
		(hatch none 0.5)
		(connect_pads
			(clearance 0)
		)
		(min_thickness 0.25)
		(keepout
			(tracks not_allowed)
			(vias allowed)
			(pads allowed)
			(copperpour not_allowed)
			(footprints allowed)
		)
		(placement
			(enabled no)
			(sheetname "")
		)
		(fill yes
			(thermal_gap 0.5)
			(thermal_bridge_width 0.5)
			(island_removal_mode 0)
		)
		(polygon
			(pts
				(arc
					(start 292.610286 -294.235124)
					(mid 291.949886 -294.235124)
					(end 292.610286 -294.235124)
				)
			)
		)
	)
	(zone
		(layers "In1.Cu" "In2.Cu")
		(hatch none 0.5)
		(connect_pads
			(clearance 0)
		)
		(min_thickness 0.25)
		(keepout
			(tracks not_allowed)
			(vias allowed)
			(pads allowed)
			(copperpour not_allowed)
			(footprints allowed)
		)
		(placement
			(enabled no)
			(sheetname "")
		)
		(fill yes
			(thermal_gap 0.5)
			(thermal_bridge_width 0.5)
			(island_removal_mode 0)
		)
		(polygon
			(pts
				(arc
					(start 277.522432 -219.435172)
					(mid 276.862032 -219.435172)
					(end 277.522432 -219.435172)
				)
			)
		)
	)
	(zone
		(layers "In1.Cu" "In2.Cu")
		(hatch none 0.5)
		(connect_pads
			(clearance 0)
		)
		(min_thickness 0.25)
		(keepout
			(tracks not_allowed)
			(vias allowed)
			(pads allowed)
			(copperpour not_allowed)
			(footprints allowed)
		)
		(placement
			(enabled no)
			(sheetname "")
		)
		(fill yes
			(thermal_gap 0.5)
			(thermal_bridge_width 0.5)
			(island_removal_mode 0)
		)
		(polygon
			(pts
				(arc
					(start 33.026096 -229.635304)
					(mid 32.365696 -229.635304)
					(end 33.026096 -229.635304)
				)
			)
		)
	)
	(zone
		(layers "In1.Cu" "In2.Cu")
		(hatch none 0.5)
		(connect_pads
			(clearance 0)
		)
		(min_thickness 0.25)
		(keepout
			(tracks not_allowed)
			(vias allowed)
			(pads allowed)
			(copperpour not_allowed)
			(footprints allowed)
		)
		(placement
			(enabled no)
			(sheetname "")
		)
		(fill yes
			(thermal_gap 0.5)
			(thermal_bridge_width 0.5)
			(island_removal_mode 0)
		)
		(polygon
			(pts
				(arc
					(start 273.422364 -267.035026)
					(mid 272.761964 -267.035026)
					(end 273.422364 -267.035026)
				)
			)
		)
	)
	(zone
		(layers "In1.Cu" "In2.Cu")
		(hatch none 0.5)
		(connect_pads
			(clearance 0)
		)
		(min_thickness 0.25)
		(keepout
			(tracks not_allowed)
			(vias allowed)
			(pads allowed)
			(copperpour not_allowed)
			(footprints allowed)
		)
		(placement
			(enabled no)
			(sheetname "")
		)
		(fill yes
			(thermal_gap 0.5)
			(thermal_bridge_width 0.5)
			(island_removal_mode 0)
		)
		(polygon
			(pts
				(arc
					(start 187.390278 -221.135194)
					(mid 186.729878 -221.135194)
					(end 187.390278 -221.135194)
				)
			)
		)
	)
	(zone
		(layers "In1.Cu" "In2.Cu")
		(hatch none 0.5)
		(connect_pads
			(clearance 0)
		)
		(min_thickness 0.25)
		(keepout
			(tracks not_allowed)
			(vias allowed)
			(pads allowed)
			(copperpour not_allowed)
			(footprints allowed)
		)
		(placement
			(enabled no)
			(sheetname "")
		)
		(fill yes
			(thermal_gap 0.5)
			(thermal_bridge_width 0.5)
			(island_removal_mode 0)
		)
		(polygon
			(pts
				(arc
					(start 442.8744 -305.28514)
					(mid 442.214 -305.28514)
					(end 442.8744 -305.28514)
				)
			)
		)
	)
	(zone
		(layers "In1.Cu" "In2.Cu")
		(hatch none 0.5)
		(connect_pads
			(clearance 0)
		)
		(min_thickness 0.25)
		(keepout
			(tracks not_allowed)
			(vias allowed)
			(pads allowed)
			(copperpour not_allowed)
			(footprints allowed)
		)
		(placement
			(enabled no)
			(sheetname "")
		)
		(fill yes
			(thermal_gap 0.5)
			(thermal_bridge_width 0.5)
			(island_removal_mode 0)
		)
		(polygon
			(pts
				(arc
					(start 29.582364 -220.28531)
					(mid 28.921964 -220.28531)
					(end 29.582364 -220.28531)
				)
			)
		)
	)
	(zone
		(layers "In1.Cu" "In2.Cu")
		(hatch none 0.5)
		(connect_pads
			(clearance 0)
		)
		(min_thickness 0.25)
		(keepout
			(tracks not_allowed)
			(vias allowed)
			(pads allowed)
			(copperpour not_allowed)
			(footprints allowed)
		)
		(placement
			(enabled no)
			(sheetname "")
		)
		(fill yes
			(thermal_gap 0.5)
			(thermal_bridge_width 0.5)
			(island_removal_mode 0)
		)
		(polygon
			(pts
				(arc
					(start 296.054272 -313.784996)
					(mid 295.393872 -313.784996)
					(end 296.054272 -313.784996)
				)
			)
		)
	)
	(zone
		(layers "In1.Cu" "In2.Cu")
		(hatch none 0.5)
		(connect_pads
			(clearance 0)
		)
		(min_thickness 0.25)
		(keepout
			(tracks not_allowed)
			(vias allowed)
			(pads allowed)
			(copperpour not_allowed)
			(footprints allowed)
		)
		(placement
			(enabled no)
			(sheetname "")
		)
		(fill yes
			(thermal_gap 0.5)
			(thermal_bridge_width 0.5)
			(island_removal_mode 0)
		)
		(polygon
			(pts
				(arc
					(start 48.114204 -250.035314)
					(mid 47.453804 -250.035314)
					(end 48.114204 -250.035314)
				)
			)
		)
	)
	(zone
		(layers "In1.Cu" "In2.Cu")
		(hatch none 0.5)
		(connect_pads
			(clearance 0)
		)
		(min_thickness 0.25)
		(keepout
			(tracks not_allowed)
			(vias allowed)
			(pads allowed)
			(copperpour not_allowed)
			(footprints allowed)
		)
		(placement
			(enabled no)
			(sheetname "")
		)
		(fill yes
			(thermal_gap 0.5)
			(thermal_bridge_width 0.5)
			(island_removal_mode 0)
		)
		(polygon
			(pts
				(arc
					(start 400.552158 -7.672324)
					(mid 400.574476 -7.618442)
					(end 400.628358 -7.596124)
				)
				(arc
					(start 401.664932 -7.596124)
					(mid 401.718814 -7.618442)
					(end 401.741132 -7.672324)
				)
				(arc
					(start 401.741132 -9.071864)
					(mid 401.718814 -9.125746)
					(end 401.664932 -9.148064)
				)
				(arc
					(start 400.628358 -9.148064)
					(mid 400.574476 -9.125746)
					(end 400.552158 -9.071864)
				)
			)
		)
	)
	(zone
		(layers "In1.Cu" "In2.Cu")
		(hatch none 0.5)
		(connect_pads
			(clearance 0)
		)
		(min_thickness 0.25)
		(keepout
			(tracks not_allowed)
			(vias allowed)
			(pads allowed)
			(copperpour not_allowed)
			(footprints allowed)
		)
		(placement
			(enabled no)
			(sheetname "")
		)
		(fill yes
			(thermal_gap 0.5)
			(thermal_bridge_width 0.5)
			(island_removal_mode 0)
		)
		(polygon
			(pts
				(arc
					(start 191.490346 -252.58522)
					(mid 190.829946 -252.58522)
					(end 191.490346 -252.58522)
				)
			)
		)
	)
	(zone
		(layers "In1.Cu" "In2.Cu")
		(hatch none 0.5)
		(connect_pads
			(clearance 0)
		)
		(min_thickness 0.25)
		(keepout
			(tracks not_allowed)
			(vias allowed)
			(pads allowed)
			(copperpour not_allowed)
			(footprints allowed)
		)
		(placement
			(enabled no)
			(sheetname "")
		)
		(fill yes
			(thermal_gap 0.5)
			(thermal_bridge_width 0.5)
			(island_removal_mode 0)
		)
		(polygon
			(pts
				(arc
					(start 29.582364 -269.58544)
					(mid 28.921964 -269.58544)
					(end 29.582364 -269.58544)
				)
			)
		)
	)
	(zone
		(layers "In1.Cu" "In2.Cu")
		(hatch none 0.5)
		(connect_pads
			(clearance 0)
		)
		(min_thickness 0.25)
		(keepout
			(tracks not_allowed)
			(vias allowed)
			(pads allowed)
			(copperpour not_allowed)
			(footprints allowed)
		)
		(placement
			(enabled no)
			(sheetname "")
		)
		(fill yes
			(thermal_gap 0.5)
			(thermal_bridge_width 0.5)
			(island_removal_mode 0)
		)
		(polygon
			(pts
				(arc
					(start 40.57015 -278.935434)
					(mid 39.90975 -278.935434)
					(end 40.57015 -278.935434)
				)
			)
		)
	)
	(zone
		(layers "In1.Cu" "In2.Cu")
		(hatch none 0.5)
		(connect_pads
			(clearance 0)
		)
		(min_thickness 0.25)
		(keepout
			(tracks not_allowed)
			(vias allowed)
			(pads allowed)
			(copperpour not_allowed)
			(footprints allowed)
		)
		(placement
			(enabled no)
			(sheetname "")
		)
		(fill yes
			(thermal_gap 0.5)
			(thermal_bridge_width 0.5)
			(island_removal_mode 0)
		)
		(polygon
			(pts
				(arc
					(start 288.510218 -293.384986)
					(mid 287.849818 -293.384986)
					(end 288.510218 -293.384986)
				)
			)
		)
	)
	(zone
		(layers "In1.Cu" "In2.Cu")
		(hatch none 0.5)
		(connect_pads
			(clearance 0)
		)
		(min_thickness 0.25)
		(keepout
			(tracks not_allowed)
			(vias allowed)
			(pads allowed)
			(copperpour not_allowed)
			(footprints allowed)
		)
		(placement
			(enabled no)
			(sheetname "")
		)
		(fill yes
			(thermal_gap 0.5)
			(thermal_bridge_width 0.5)
			(island_removal_mode 0)
		)
		(polygon
			(pts
				(arc
					(start 22.03831 -217.735404)
					(mid 21.37791 -217.735404)
					(end 22.03831 -217.735404)
				)
			)
		)
	)
	(zone
		(layers "In1.Cu" "In2.Cu")
		(hatch none 0.5)
		(connect_pads
			(clearance 0)
		)
		(min_thickness 0.25)
		(keepout
			(tracks not_allowed)
			(vias allowed)
			(pads allowed)
			(copperpour not_allowed)
			(footprints allowed)
		)
		(placement
			(enabled no)
			(sheetname "")
		)
		(fill yes
			(thermal_gap 0.5)
			(thermal_bridge_width 0.5)
			(island_removal_mode 0)
		)
		(polygon
			(pts
				(arc
					(start 288.510218 -232.184956)
					(mid 287.849818 -232.184956)
					(end 288.510218 -232.184956)
				)
			)
		)
	)
	(zone
		(layers "In1.Cu" "In2.Cu")
		(hatch none 0.5)
		(connect_pads
			(clearance 0)
		)
		(min_thickness 0.25)
		(keepout
			(tracks not_allowed)
			(vias allowed)
			(pads allowed)
			(copperpour not_allowed)
			(footprints allowed)
		)
		(placement
			(enabled no)
			(sheetname "")
		)
		(fill yes
			(thermal_gap 0.5)
			(thermal_bridge_width 0.5)
			(island_removal_mode 0)
		)
		(polygon
			(pts
				(arc
					(start 194.934332 -198.185278)
					(mid 194.273932 -198.185278)
					(end 194.934332 -198.185278)
				)
			)
		)
	)
	(zone
		(layers "In1.Cu" "In2.Cu")
		(hatch none 0.5)
		(connect_pads
			(clearance 0)
		)
		(min_thickness 0.25)
		(keepout
			(tracks not_allowed)
			(vias allowed)
			(pads allowed)
			(copperpour not_allowed)
			(footprints allowed)
		)
		(placement
			(enabled no)
			(sheetname "")
		)
		(fill yes
			(thermal_gap 0.5)
			(thermal_bridge_width 0.5)
			(island_removal_mode 0)
		)
		(polygon
			(pts
				(arc
					(start 25.482296 -284.035246)
					(mid 24.821896 -284.035246)
					(end 25.482296 -284.035246)
				)
			)
		)
	)
	(zone
		(layers "In1.Cu" "In2.Cu")
		(hatch none 0.5)
		(connect_pads
			(clearance 0)
		)
		(min_thickness 0.25)
		(keepout
			(tracks not_allowed)
			(vias allowed)
			(pads allowed)
			(copperpour not_allowed)
			(footprints allowed)
		)
		(placement
			(enabled no)
			(sheetname "")
		)
		(fill yes
			(thermal_gap 0.5)
			(thermal_bridge_width 0.5)
			(island_removal_mode 0)
		)
		(polygon
			(pts
				(arc
					(start 285.066232 -244.08511)
					(mid 284.405832 -244.08511)
					(end 285.066232 -244.08511)
				)
			)
		)
	)
	(zone
		(layers "In1.Cu" "In2.Cu")
		(hatch none 0.5)
		(connect_pads
			(clearance 0)
		)
		(min_thickness 0.25)
		(keepout
			(tracks not_allowed)
			(vias allowed)
			(pads allowed)
			(copperpour not_allowed)
			(footprints allowed)
		)
		(placement
			(enabled no)
			(sheetname "")
		)
		(fill yes
			(thermal_gap 0.5)
			(thermal_bridge_width 0.5)
			(island_removal_mode 0)
		)
		(polygon
			(pts
				(arc
					(start 300.15434 -236.435138)
					(mid 299.49394 -236.435138)
					(end 300.15434 -236.435138)
				)
			)
		)
	)
	(zone
		(layers "In1.Cu" "In2.Cu")
		(hatch none 0.5)
		(connect_pads
			(clearance 0)
		)
		(min_thickness 0.25)
		(keepout
			(tracks not_allowed)
			(vias allowed)
			(pads allowed)
			(copperpour not_allowed)
			(footprints allowed)
		)
		(placement
			(enabled no)
			(sheetname "")
		)
		(fill yes
			(thermal_gap 0.5)
			(thermal_bridge_width 0.5)
			(island_removal_mode 0)
		)
		(polygon
			(pts
				(arc
					(start 442.8744 -312.084974)
					(mid 442.214 -312.084974)
					(end 442.8744 -312.084974)
				)
			)
		)
	)
	(zone
		(layers "In1.Cu" "In2.Cu")
		(hatch none 0.5)
		(connect_pads
			(clearance 0)
		)
		(min_thickness 0.25)
		(keepout
			(tracks not_allowed)
			(vias allowed)
			(pads allowed)
			(copperpour not_allowed)
			(footprints allowed)
		)
		(placement
			(enabled no)
			(sheetname "")
		)
		(fill yes
			(thermal_gap 0.5)
			(thermal_bridge_width 0.5)
			(island_removal_mode 0)
		)
		(polygon
			(pts
				(arc
					(start 300.15434 -312.935112)
					(mid 299.49394 -312.935112)
					(end 300.15434 -312.935112)
				)
			)
		)
	)
	(zone
		(layers "In1.Cu" "In2.Cu")
		(hatch none 0.5)
		(connect_pads
			(clearance 0)
		)
		(min_thickness 0.25)
		(keepout
			(tracks not_allowed)
			(vias allowed)
			(pads allowed)
			(copperpour not_allowed)
			(footprints allowed)
		)
		(placement
			(enabled no)
			(sheetname "")
		)
		(fill yes
			(thermal_gap 0.5)
			(thermal_bridge_width 0.5)
			(island_removal_mode 0)
		)
		(polygon
			(pts
				(arc
					(start 454.518268 -210.935062)
					(mid 453.857868 -210.935062)
					(end 454.518268 -210.935062)
				)
			)
		)
	)
	(zone
		(layers "In1.Cu" "In2.Cu")
		(hatch none 0.5)
		(connect_pads
			(clearance 0)
		)
		(min_thickness 0.25)
		(keepout
			(tracks not_allowed)
			(vias allowed)
			(pads allowed)
			(copperpour not_allowed)
			(footprints allowed)
		)
		(placement
			(enabled no)
			(sheetname "")
		)
		(fill yes
			(thermal_gap 0.5)
			(thermal_bridge_width 0.5)
			(island_removal_mode 0)
		)
		(polygon
			(pts
				(arc
					(start 25.482296 -224.535238)
					(mid 24.821896 -224.535238)
					(end 25.482296 -224.535238)
				)
			)
		)
	)
	(zone
		(layers "In1.Cu" "In2.Cu")
		(hatch none 0.5)
		(connect_pads
			(clearance 0)
		)
		(min_thickness 0.25)
		(keepout
			(tracks not_allowed)
			(vias allowed)
			(pads allowed)
			(copperpour not_allowed)
			(footprints allowed)
		)
		(placement
			(enabled no)
			(sheetname "")
		)
		(fill yes
			(thermal_gap 0.5)
			(thermal_bridge_width 0.5)
			(island_removal_mode 0)
		)
		(polygon
			(pts
				(arc
					(start 446.974468 -228.785166)
					(mid 446.314068 -228.785166)
					(end 446.974468 -228.785166)
				)
			)
		)
	)
	(zone
		(layers "In1.Cu" "In2.Cu")
		(hatch none 0.5)
		(connect_pads
			(clearance 0)
		)
		(min_thickness 0.25)
		(keepout
			(tracks not_allowed)
			(vias allowed)
			(pads allowed)
			(copperpour not_allowed)
			(footprints allowed)
		)
		(placement
			(enabled no)
			(sheetname "")
		)
		(fill yes
			(thermal_gap 0.5)
			(thermal_bridge_width 0.5)
			(island_removal_mode 0)
		)
		(polygon
			(pts
				(arc
					(start 179.846224 -244.935248)
					(mid 179.185824 -244.935248)
					(end 179.846224 -244.935248)
				)
			)
		)
	)
	(zone
		(layers "In1.Cu" "In2.Cu")
		(hatch none 0.5)
		(connect_pads
			(clearance 0)
		)
		(min_thickness 0.25)
		(keepout
			(tracks not_allowed)
			(vias allowed)
			(pads allowed)
			(copperpour not_allowed)
			(footprints allowed)
		)
		(placement
			(enabled no)
			(sheetname "")
		)
		(fill yes
			(thermal_gap 0.5)
			(thermal_bridge_width 0.5)
			(island_removal_mode 0)
		)
		(polygon
			(pts
				(arc
					(start 420.242238 -251.735082)
					(mid 419.581838 -251.735082)
					(end 420.242238 -251.735082)
				)
			)
		)
	)
	(zone
		(layers "In1.Cu" "In2.Cu")
		(hatch none 0.5)
		(connect_pads
			(clearance 0)
		)
		(min_thickness 0.25)
		(keepout
			(tracks not_allowed)
			(vias allowed)
			(pads allowed)
			(copperpour not_allowed)
			(footprints allowed)
		)
		(placement
			(enabled no)
			(sheetname "")
		)
		(fill yes
			(thermal_gap 0.5)
			(thermal_bridge_width 0.5)
			(island_removal_mode 0)
		)
		(polygon
			(pts
				(arc
					(start 29.582364 -270.435324)
					(mid 28.921964 -270.435324)
					(end 29.582364 -270.435324)
				)
			)
		)
	)
	(zone
		(layers "In1.Cu" "In2.Cu")
		(hatch none 0.5)
		(connect_pads
			(clearance 0)
		)
		(min_thickness 0.25)
		(keepout
			(tracks not_allowed)
			(vias allowed)
			(pads allowed)
			(copperpour not_allowed)
			(footprints allowed)
		)
		(placement
			(enabled no)
			(sheetname "")
		)
		(fill yes
			(thermal_gap 0.5)
			(thermal_bridge_width 0.5)
			(island_removal_mode 0)
		)
		(polygon
			(pts
				(arc
					(start 450.4182 -199.885046)
					(mid 449.7578 -199.885046)
					(end 450.4182 -199.885046)
				)
			)
		)
	)
	(zone
		(layers "In1.Cu" "In2.Cu")
		(hatch none 0.5)
		(connect_pads
			(clearance 0)
		)
		(min_thickness 0.25)
		(keepout
			(tracks not_allowed)
			(vias allowed)
			(pads allowed)
			(copperpour not_allowed)
			(footprints allowed)
		)
		(placement
			(enabled no)
			(sheetname "")
		)
		(fill yes
			(thermal_gap 0.5)
			(thermal_bridge_width 0.5)
			(island_removal_mode 0)
		)
		(polygon
			(pts
				(arc
					(start 273.422364 -213.484968)
					(mid 272.761964 -213.484968)
					(end 273.422364 -213.484968)
				)
			)
		)
	)
	(zone
		(layers "In1.Cu" "In2.Cu")
		(hatch none 0.5)
		(connect_pads
			(clearance 0)
		)
		(min_thickness 0.25)
		(keepout
			(tracks not_allowed)
			(vias allowed)
			(pads allowed)
			(copperpour not_allowed)
			(footprints allowed)
		)
		(placement
			(enabled no)
			(sheetname "")
		)
		(fill yes
			(thermal_gap 0.5)
			(thermal_bridge_width 0.5)
			(island_removal_mode 0)
		)
		(polygon
			(pts
				(arc
					(start 285.066232 -294.235124)
					(mid 284.405832 -294.235124)
					(end 285.066232 -294.235124)
				)
			)
		)
	)
	(zone
		(layers "In1.Cu" "In2.Cu")
		(hatch none 0.5)
		(connect_pads
			(clearance 0)
		)
		(min_thickness 0.25)
		(keepout
			(tracks not_allowed)
			(vias allowed)
			(pads allowed)
			(copperpour not_allowed)
			(footprints allowed)
		)
		(placement
			(enabled no)
			(sheetname "")
		)
		(fill yes
			(thermal_gap 0.5)
			(thermal_bridge_width 0.5)
			(island_removal_mode 0)
		)
		(polygon
			(pts
				(arc
					(start 48.114204 -310.385206)
					(mid 47.453804 -310.385206)
					(end 48.114204 -310.385206)
				)
			)
		)
	)
	(zone
		(layers "In1.Cu" "In2.Cu")
		(hatch none 0.5)
		(connect_pads
			(clearance 0)
		)
		(min_thickness 0.25)
		(keepout
			(tracks not_allowed)
			(vias allowed)
			(pads allowed)
			(copperpour not_allowed)
			(footprints allowed)
		)
		(placement
			(enabled no)
			(sheetname "")
		)
		(fill yes
			(thermal_gap 0.5)
			(thermal_bridge_width 0.5)
			(island_removal_mode 0)
		)
		(polygon
			(pts
				(arc
					(start 44.670218 -287.43529)
					(mid 44.009818 -287.43529)
					(end 44.670218 -287.43529)
				)
			)
		)
	)
	(zone
		(layers "In1.Cu" "In2.Cu")
		(hatch none 0.5)
		(connect_pads
			(clearance 0)
		)
		(min_thickness 0.25)
		(keepout
			(tracks not_allowed)
			(vias allowed)
			(pads allowed)
			(copperpour not_allowed)
			(footprints allowed)
		)
		(placement
			(enabled no)
			(sheetname "")
		)
		(fill yes
			(thermal_gap 0.5)
			(thermal_bridge_width 0.5)
			(island_removal_mode 0)
		)
		(polygon
			(pts
				(arc
					(start 435.330346 -289.985196)
					(mid 434.669946 -289.985196)
					(end 435.330346 -289.985196)
				)
			)
		)
	)
	(zone
		(layers "In1.Cu" "In2.Cu")
		(hatch none 0.5)
		(connect_pads
			(clearance 0)
		)
		(min_thickness 0.25)
		(keepout
			(tracks not_allowed)
			(vias allowed)
			(pads allowed)
			(copperpour not_allowed)
			(footprints allowed)
		)
		(placement
			(enabled no)
			(sheetname "")
		)
		(fill yes
			(thermal_gap 0.5)
			(thermal_bridge_width 0.5)
			(island_removal_mode 0)
		)
		(polygon
			(pts
				(arc
					(start 22.03831 -236.435392)
					(mid 21.37791 -236.435392)
					(end 22.03831 -236.435392)
				)
			)
		)
	)
	(zone
		(layers "In1.Cu" "In2.Cu")
		(hatch none 0.5)
		(connect_pads
			(clearance 0)
		)
		(min_thickness 0.25)
		(keepout
			(tracks not_allowed)
			(vias allowed)
			(pads allowed)
			(copperpour not_allowed)
			(footprints allowed)
		)
		(placement
			(enabled no)
			(sheetname "")
		)
		(fill yes
			(thermal_gap 0.5)
			(thermal_bridge_width 0.5)
			(island_removal_mode 0)
		)
		(polygon
			(pts
				(arc
					(start 25.482296 -246.63527)
					(mid 24.821896 -246.63527)
					(end 25.482296 -246.63527)
				)
			)
		)
	)
	(zone
		(layers "In1.Cu" "In2.Cu")
		(hatch none 0.5)
		(connect_pads
			(clearance 0)
		)
		(min_thickness 0.25)
		(keepout
			(tracks not_allowed)
			(vias allowed)
			(pads allowed)
			(copperpour not_allowed)
			(footprints allowed)
		)
		(placement
			(enabled no)
			(sheetname "")
		)
		(fill yes
			(thermal_gap 0.5)
			(thermal_bridge_width 0.5)
			(island_removal_mode 0)
		)
		(polygon
			(pts
				(arc
					(start 194.934332 -291.685218)
					(mid 194.273932 -291.685218)
					(end 194.934332 -291.685218)
				)
			)
		)
	)
	(zone
		(layers "In1.Cu" "In2.Cu")
		(hatch none 0.5)
		(connect_pads
			(clearance 0)
		)
		(min_thickness 0.25)
		(keepout
			(tracks not_allowed)
			(vias allowed)
			(pads allowed)
			(copperpour not_allowed)
			(footprints allowed)
		)
		(placement
			(enabled no)
			(sheetname "")
		)
		(fill yes
			(thermal_gap 0.5)
			(thermal_bridge_width 0.5)
			(island_removal_mode 0)
		)
		(polygon
			(pts
				(arc
					(start 420.242238 -276.38502)
					(mid 419.581838 -276.38502)
					(end 420.242238 -276.38502)
				)
			)
		)
	)
	(zone
		(layers "In1.Cu" "In2.Cu")
		(hatch none 0.5)
		(connect_pads
			(clearance 0)
		)
		(min_thickness 0.25)
		(keepout
			(tracks not_allowed)
			(vias allowed)
			(pads allowed)
			(copperpour not_allowed)
			(footprints allowed)
		)
		(placement
			(enabled no)
			(sheetname "")
		)
		(fill yes
			(thermal_gap 0.5)
			(thermal_bridge_width 0.5)
			(island_removal_mode 0)
		)
		(polygon
			(pts
				(arc
					(start 435.330346 -278.93518)
					(mid 434.669946 -278.93518)
					(end 435.330346 -278.93518)
				)
			)
		)
	)
	(zone
		(layers "In1.Cu" "In2.Cu")
		(hatch none 0.5)
		(connect_pads
			(clearance 0)
		)
		(min_thickness 0.25)
		(keepout
			(tracks not_allowed)
			(vias allowed)
			(pads allowed)
			(copperpour not_allowed)
			(footprints allowed)
		)
		(placement
			(enabled no)
			(sheetname "")
		)
		(fill yes
			(thermal_gap 0.5)
			(thermal_bridge_width 0.5)
			(island_removal_mode 0)
		)
		(polygon
			(pts
				(arc
					(start 277.522432 -278.085042)
					(mid 276.862032 -278.085042)
					(end 277.522432 -278.085042)
				)
			)
		)
	)
	(zone
		(layers "In1.Cu" "In2.Cu")
		(hatch none 0.5)
		(connect_pads
			(clearance 0)
		)
		(min_thickness 0.25)
		(keepout
			(tracks not_allowed)
			(vias allowed)
			(pads allowed)
			(copperpour not_allowed)
			(footprints allowed)
		)
		(placement
			(enabled no)
			(sheetname "")
		)
		(fill yes
			(thermal_gap 0.5)
			(thermal_bridge_width 0.5)
			(island_removal_mode 0)
		)
		(polygon
			(pts
				(arc
					(start 454.518268 -208.385156)
					(mid 453.857868 -208.385156)
					(end 454.518268 -208.385156)
				)
			)
		)
	)
	(zone
		(layers "In1.Cu" "In2.Cu")
		(hatch none 0.5)
		(connect_pads
			(clearance 0)
		)
		(min_thickness 0.25)
		(keepout
			(tracks not_allowed)
			(vias allowed)
			(pads allowed)
			(copperpour not_allowed)
			(footprints allowed)
		)
		(placement
			(enabled no)
			(sheetname "")
		)
		(fill yes
			(thermal_gap 0.5)
			(thermal_bridge_width 0.5)
			(island_removal_mode 0)
		)
		(polygon
			(pts
				(arc
					(start 269.978378 -197.33514)
					(mid 269.317978 -197.33514)
					(end 269.978378 -197.33514)
				)
			)
		)
	)
	(zone
		(layers "In1.Cu" "In2.Cu")
		(hatch none 0.5)
		(connect_pads
			(clearance 0)
		)
		(min_thickness 0.25)
		(keepout
			(tracks not_allowed)
			(vias allowed)
			(pads allowed)
			(copperpour not_allowed)
			(footprints allowed)
		)
		(placement
			(enabled no)
			(sheetname "")
		)
		(fill yes
			(thermal_gap 0.5)
			(thermal_bridge_width 0.5)
			(island_removal_mode 0)
		)
		(polygon
			(pts
				(arc
					(start 52.214272 -212.635338)
					(mid 51.553872 -212.635338)
					(end 52.214272 -212.635338)
				)
			)
		)
	)
	(zone
		(layers "In1.Cu" "In2.Cu")
		(hatch none 0.5)
		(connect_pads
			(clearance 0)
		)
		(min_thickness 0.25)
		(keepout
			(tracks not_allowed)
			(vias allowed)
			(pads allowed)
			(copperpour not_allowed)
			(footprints allowed)
		)
		(placement
			(enabled no)
			(sheetname "")
		)
		(fill yes
			(thermal_gap 0.5)
			(thermal_bridge_width 0.5)
			(island_removal_mode 0)
		)
		(polygon
			(pts
				(arc
					(start 446.974468 -210.935062)
					(mid 446.314068 -210.935062)
					(end 446.974468 -210.935062)
				)
			)
		)
	)
	(zone
		(layers "In1.Cu" "In2.Cu")
		(hatch none 0.5)
		(connect_pads
			(clearance 0)
		)
		(min_thickness 0.25)
		(keepout
			(tracks not_allowed)
			(vias allowed)
			(pads allowed)
			(copperpour not_allowed)
			(footprints allowed)
		)
		(placement
			(enabled no)
			(sheetname "")
		)
		(fill yes
			(thermal_gap 0.5)
			(thermal_bridge_width 0.5)
			(island_removal_mode 0)
		)
		(polygon
			(pts
				(arc
					(start 22.03831 -203.285344)
					(mid 21.37791 -203.285344)
					(end 22.03831 -203.285344)
				)
			)
		)
	)
	(zone
		(layers "In1.Cu" "In2.Cu")
		(hatch none 0.5)
		(connect_pads
			(clearance 0)
		)
		(min_thickness 0.25)
		(keepout
			(tracks not_allowed)
			(vias allowed)
			(pads allowed)
			(copperpour not_allowed)
			(footprints allowed)
		)
		(placement
			(enabled no)
			(sheetname "")
		)
		(fill yes
			(thermal_gap 0.5)
			(thermal_bridge_width 0.5)
			(island_removal_mode 0)
		)
		(polygon
			(pts
				(arc
					(start 179.846224 -241.535204)
					(mid 179.185824 -241.535204)
					(end 179.846224 -241.535204)
				)
			)
		)
	)
	(zone
		(layers "In1.Cu" "In2.Cu")
		(hatch none 0.5)
		(connect_pads
			(clearance 0)
		)
		(min_thickness 0.25)
		(keepout
			(tracks not_allowed)
			(vias allowed)
			(pads allowed)
			(copperpour not_allowed)
			(footprints allowed)
		)
		(placement
			(enabled no)
			(sheetname "")
		)
		(fill yes
			(thermal_gap 0.5)
			(thermal_bridge_width 0.5)
			(island_removal_mode 0)
		)
		(polygon
			(pts
				(arc
					(start 288.510218 -230.485188)
					(mid 287.849818 -230.485188)
					(end 288.510218 -230.485188)
				)
			)
		)
	)
	(zone
		(layers "In1.Cu" "In2.Cu")
		(hatch none 0.5)
		(connect_pads
			(clearance 0)
		)
		(min_thickness 0.25)
		(keepout
			(tracks not_allowed)
			(vias allowed)
			(pads allowed)
			(copperpour not_allowed)
			(footprints allowed)
		)
		(placement
			(enabled no)
			(sheetname "")
		)
		(fill yes
			(thermal_gap 0.5)
			(thermal_bridge_width 0.5)
			(island_removal_mode 0)
		)
		(polygon
			(pts
				(arc
					(start 101.838252 -370.978684)
					(mid 101.858176 -370.98792)
					(end 101.879908 -370.99113)
				)
				(arc
					(start 102.074472 -370.99113)
					(mid 102.128354 -370.968812)
					(end 102.150672 -370.91493)
				)
				(arc
					(start 102.150672 -370.22913)
					(mid 102.128354 -370.175248)
					(end 102.074472 -370.15293)
				)
				(arc
					(start 101.879908 -370.15293)
					(mid 101.858164 -370.156098)
					(end 101.838252 -370.165376)
				)
				(arc
					(start 101.542088 -370.358162)
					(mid 101.500404 -370.370384)
					(end 101.458776 -370.357908)
				)
				(arc
					(start 101.165152 -370.165376)
					(mid 101.145228 -370.15614)
					(end 101.123496 -370.15293)
				)
				(arc
					(start 100.928932 -370.15293)
					(mid 100.87505 -370.175248)
					(end 100.852732 -370.22913)
				)
				(arc
					(start 100.852732 -370.91493)
					(mid 100.87505 -370.968812)
					(end 100.928932 -370.99113)
				)
				(arc
					(start 101.124766 -370.99113)
					(mid 101.14651 -370.987962)
					(end 101.166422 -370.978684)
				)
				(arc
					(start 101.460046 -370.786152)
					(mid 101.501702 -370.77375)
					(end 101.543358 -370.786152)
				)
			)
		)
	)
	(zone
		(layers "In1.Cu" "In2.Cu")
		(hatch none 0.5)
		(connect_pads
			(clearance 0)
		)
		(min_thickness 0.25)
		(keepout
			(tracks not_allowed)
			(vias allowed)
			(pads allowed)
			(copperpour not_allowed)
			(footprints allowed)
		)
		(placement
			(enabled no)
			(sheetname "")
		)
		(fill yes
			(thermal_gap 0.5)
			(thermal_bridge_width 0.5)
			(island_removal_mode 0)
		)
		(polygon
			(pts
				(arc
					(start 288.510218 -250.03506)
					(mid 287.849818 -250.03506)
					(end 288.510218 -250.03506)
				)
			)
		)
	)
	(zone
		(layers "In1.Cu" "In2.Cu")
		(hatch none 0.5)
		(connect_pads
			(clearance 0)
		)
		(min_thickness 0.25)
		(keepout
			(tracks not_allowed)
			(vias allowed)
			(pads allowed)
			(copperpour not_allowed)
			(footprints allowed)
		)
		(placement
			(enabled no)
			(sheetname "")
		)
		(fill yes
			(thermal_gap 0.5)
			(thermal_bridge_width 0.5)
			(island_removal_mode 0)
		)
		(polygon
			(pts
				(arc
					(start 52.214272 -300.185328)
					(mid 51.553872 -300.185328)
					(end 52.214272 -300.185328)
				)
			)
		)
	)
	(zone
		(layers "In1.Cu" "In2.Cu")
		(hatch none 0.5)
		(connect_pads
			(clearance 0)
		)
		(min_thickness 0.25)
		(keepout
			(tracks not_allowed)
			(vias allowed)
			(pads allowed)
			(copperpour not_allowed)
			(footprints allowed)
		)
		(placement
			(enabled no)
			(sheetname "")
		)
		(fill yes
			(thermal_gap 0.5)
			(thermal_bridge_width 0.5)
			(island_removal_mode 0)
		)
		(polygon
			(pts
				(arc
					(start 269.978378 -204.985112)
					(mid 269.317978 -204.985112)
					(end 269.978378 -204.985112)
				)
			)
		)
	)
	(zone
		(layers "In1.Cu" "In2.Cu")
		(hatch none 0.5)
		(connect_pads
			(clearance 0)
		)
		(min_thickness 0.25)
		(keepout
			(tracks not_allowed)
			(vias allowed)
			(pads allowed)
			(copperpour not_allowed)
			(footprints allowed)
		)
		(placement
			(enabled no)
			(sheetname "")
		)
		(fill yes
			(thermal_gap 0.5)
			(thermal_bridge_width 0.5)
			(island_removal_mode 0)
		)
		(polygon
			(pts
				(arc
					(start 183.946292 -200.735438)
					(mid 183.285892 -200.735438)
					(end 183.946292 -200.735438)
				)
			)
		)
	)
	(zone
		(layers "In1.Cu" "In2.Cu")
		(hatch none 0.5)
		(connect_pads
			(clearance 0)
		)
		(min_thickness 0.25)
		(keepout
			(tracks not_allowed)
			(vias allowed)
			(pads allowed)
			(copperpour not_allowed)
			(footprints allowed)
		)
		(placement
			(enabled no)
			(sheetname "")
		)
		(fill yes
			(thermal_gap 0.5)
			(thermal_bridge_width 0.5)
			(island_removal_mode 0)
		)
		(polygon
			(pts
				(arc
					(start 288.510218 -227.935028)
					(mid 287.849818 -227.935028)
					(end 288.510218 -227.935028)
				)
			)
		)
	)
	(zone
		(layers "In1.Cu" "In2.Cu")
		(hatch none 0.5)
		(connect_pads
			(clearance 0)
		)
		(min_thickness 0.25)
		(keepout
			(tracks not_allowed)
			(vias allowed)
			(pads allowed)
			(copperpour not_allowed)
			(footprints allowed)
		)
		(placement
			(enabled no)
			(sheetname "")
		)
		(fill yes
			(thermal_gap 0.5)
			(thermal_bridge_width 0.5)
			(island_removal_mode 0)
		)
		(polygon
			(pts
				(arc
					(start 285.066232 -223.6851)
					(mid 284.405832 -223.6851)
					(end 285.066232 -223.6851)
				)
			)
		)
	)
	(zone
		(layers "In1.Cu" "In2.Cu")
		(hatch none 0.5)
		(connect_pads
			(clearance 0)
		)
		(min_thickness 0.25)
		(keepout
			(tracks not_allowed)
			(vias allowed)
			(pads allowed)
			(copperpour not_allowed)
			(footprints allowed)
		)
		(placement
			(enabled no)
			(sheetname "")
		)
		(fill yes
			(thermal_gap 0.5)
			(thermal_bridge_width 0.5)
			(island_removal_mode 0)
		)
		(polygon
			(pts
				(arc
					(start 179.846224 -204.135228)
					(mid 179.185824 -204.135228)
					(end 179.846224 -204.135228)
				)
			)
		)
	)
	(zone
		(layers "In1.Cu" "In2.Cu")
		(hatch none 0.5)
		(connect_pads
			(clearance 0)
		)
		(min_thickness 0.25)
		(keepout
			(tracks not_allowed)
			(vias allowed)
			(pads allowed)
			(copperpour not_allowed)
			(footprints allowed)
		)
		(placement
			(enabled no)
			(sheetname "")
		)
		(fill yes
			(thermal_gap 0.5)
			(thermal_bridge_width 0.5)
			(island_removal_mode 0)
		)
		(polygon
			(pts
				(arc
					(start 325.019416 -417.242244)
					(mid 325.041734 -417.296126)
					(end 325.095616 -417.318444)
				)
				(arc
					(start 325.291196 -417.318444)
					(mid 325.313072 -417.315312)
					(end 325.333106 -417.305998)
				)
				(arc
					(start 325.62673 -417.113466)
					(mid 325.668386 -417.101064)
					(end 325.710042 -417.113466)
				)
				(arc
					(start 326.004936 -417.305998)
					(mid 326.02486 -417.315234)
					(end 326.046592 -417.318444)
				)
				(arc
					(start 326.241156 -417.318444)
					(mid 326.295038 -417.296126)
					(end 326.317356 -417.242244)
				)
				(arc
					(start 326.317356 -416.556444)
					(mid 326.295038 -416.502562)
					(end 326.241156 -416.480244)
				)
				(arc
					(start 326.046592 -416.480244)
					(mid 326.024848 -416.483412)
					(end 326.004936 -416.49269)
				)
				(arc
					(start 325.708772 -416.685476)
					(mid 325.667088 -416.697698)
					(end 325.62546 -416.685222)
				)
				(arc
					(start 325.331836 -416.49269)
					(mid 325.311912 -416.483454)
					(end 325.29018 -416.480244)
				)
				(arc
					(start 325.095616 -416.480244)
					(mid 325.041734 -416.502562)
					(end 325.019416 -416.556444)
				)
			)
		)
	)
	(zone
		(layers "In1.Cu" "In2.Cu")
		(hatch none 0.5)
		(connect_pads
			(clearance 0)
		)
		(min_thickness 0.25)
		(keepout
			(tracks not_allowed)
			(vias allowed)
			(pads allowed)
			(copperpour not_allowed)
			(footprints allowed)
		)
		(placement
			(enabled no)
			(sheetname "")
		)
		(fill yes
			(thermal_gap 0.5)
			(thermal_bridge_width 0.5)
			(island_removal_mode 0)
		)
		(polygon
			(pts
				(arc
					(start 273.422364 -235.585)
					(mid 272.761964 -235.585)
					(end 273.422364 -235.585)
				)
			)
		)
	)
	(zone
		(layers "In1.Cu" "In2.Cu")
		(hatch none 0.5)
		(connect_pads
			(clearance 0)
		)
		(min_thickness 0.25)
		(keepout
			(tracks not_allowed)
			(vias allowed)
			(pads allowed)
			(copperpour not_allowed)
			(footprints allowed)
		)
		(placement
			(enabled no)
			(sheetname "")
		)
		(fill yes
			(thermal_gap 0.5)
			(thermal_bridge_width 0.5)
			(island_removal_mode 0)
		)
		(polygon
			(pts
				(arc
					(start 280.966164 -215.18499)
					(mid 280.305764 -215.18499)
					(end 280.966164 -215.18499)
				)
			)
		)
	)
	(zone
		(layers "In1.Cu" "In2.Cu")
		(hatch none 0.5)
		(connect_pads
			(clearance 0)
		)
		(min_thickness 0.25)
		(keepout
			(tracks not_allowed)
			(vias allowed)
			(pads allowed)
			(copperpour not_allowed)
			(footprints allowed)
		)
		(placement
			(enabled no)
			(sheetname "")
		)
		(fill yes
			(thermal_gap 0.5)
			(thermal_bridge_width 0.5)
			(island_removal_mode 0)
		)
		(polygon
			(pts
				(arc
					(start 22.03831 -227.085398)
					(mid 21.37791 -227.085398)
					(end 22.03831 -227.085398)
				)
			)
		)
	)
	(zone
		(layers "In1.Cu" "In2.Cu")
		(hatch none 0.5)
		(connect_pads
			(clearance 0)
		)
		(min_thickness 0.25)
		(keepout
			(tracks not_allowed)
			(vias allowed)
			(pads allowed)
			(copperpour not_allowed)
			(footprints allowed)
		)
		(placement
			(enabled no)
			(sheetname "")
		)
		(fill yes
			(thermal_gap 0.5)
			(thermal_bridge_width 0.5)
			(island_removal_mode 0)
		)
		(polygon
			(pts
				(arc
					(start 454.518268 -307.835046)
					(mid 453.857868 -307.835046)
					(end 454.518268 -307.835046)
				)
			)
		)
	)
	(zone
		(layers "In1.Cu" "In2.Cu")
		(hatch none 0.5)
		(connect_pads
			(clearance 0)
		)
		(min_thickness 0.25)
		(keepout
			(tracks not_allowed)
			(vias allowed)
			(pads allowed)
			(copperpour not_allowed)
			(footprints allowed)
		)
		(placement
			(enabled no)
			(sheetname "")
		)
		(fill yes
			(thermal_gap 0.5)
			(thermal_bridge_width 0.5)
			(island_removal_mode 0)
		)
		(polygon
			(pts
				(arc
					(start 431.88636 -203.28509)
					(mid 431.22596 -203.28509)
					(end 431.88636 -203.28509)
				)
			)
		)
	)
	(zone
		(layers "In1.Cu" "In2.Cu")
		(hatch none 0.5)
		(connect_pads
			(clearance 0)
		)
		(min_thickness 0.25)
		(keepout
			(tracks not_allowed)
			(vias allowed)
			(pads allowed)
			(copperpour not_allowed)
			(footprints allowed)
		)
		(placement
			(enabled no)
			(sheetname "")
		)
		(fill yes
			(thermal_gap 0.5)
			(thermal_bridge_width 0.5)
			(island_removal_mode 0)
		)
		(polygon
			(pts
				(arc
					(start 202.478132 -267.03528)
					(mid 201.817732 -267.03528)
					(end 202.478132 -267.03528)
				)
			)
		)
	)
	(zone
		(layers "In1.Cu" "In2.Cu")
		(hatch none 0.5)
		(connect_pads
			(clearance 0)
		)
		(min_thickness 0.25)
		(keepout
			(tracks not_allowed)
			(vias allowed)
			(pads allowed)
			(copperpour not_allowed)
			(footprints allowed)
		)
		(placement
			(enabled no)
			(sheetname "")
		)
		(fill yes
			(thermal_gap 0.5)
			(thermal_bridge_width 0.5)
			(island_removal_mode 0)
		)
		(polygon
			(pts
				(arc
					(start 176.402238 -309.535322)
					(mid 175.741838 -309.535322)
					(end 176.402238 -309.535322)
				)
			)
		)
	)
	(zone
		(layers "In1.Cu" "In2.Cu")
		(hatch none 0.5)
		(connect_pads
			(clearance 0)
		)
		(min_thickness 0.25)
		(keepout
			(tracks not_allowed)
			(vias allowed)
			(pads allowed)
			(copperpour not_allowed)
			(footprints allowed)
		)
		(placement
			(enabled no)
			(sheetname "")
		)
		(fill yes
			(thermal_gap 0.5)
			(thermal_bridge_width 0.5)
			(island_removal_mode 0)
		)
		(polygon
			(pts
				(arc
					(start 172.30217 -222.835216)
					(mid 171.64177 -222.835216)
					(end 172.30217 -222.835216)
				)
			)
		)
	)
	(zone
		(layers "In1.Cu" "In2.Cu")
		(hatch none 0.5)
		(connect_pads
			(clearance 0)
		)
		(min_thickness 0.25)
		(keepout
			(tracks not_allowed)
			(vias allowed)
			(pads allowed)
			(copperpour not_allowed)
			(footprints allowed)
		)
		(placement
			(enabled no)
			(sheetname "")
		)
		(fill yes
			(thermal_gap 0.5)
			(thermal_bridge_width 0.5)
			(island_removal_mode 0)
		)
		(polygon
			(pts
				(arc
					(start 191.490346 -287.43529)
					(mid 190.829946 -287.43529)
					(end 191.490346 -287.43529)
				)
			)
		)
	)
	(zone
		(layers "In1.Cu" "In2.Cu")
		(hatch none 0.5)
		(connect_pads
			(clearance 0)
		)
		(min_thickness 0.25)
		(keepout
			(tracks not_allowed)
			(vias allowed)
			(pads allowed)
			(copperpour not_allowed)
			(footprints allowed)
		)
		(placement
			(enabled no)
			(sheetname "")
		)
		(fill yes
			(thermal_gap 0.5)
			(thermal_bridge_width 0.5)
			(island_removal_mode 0)
		)
		(polygon
			(pts
				(arc
					(start 29.582364 -278.085296)
					(mid 28.921964 -278.085296)
					(end 29.582364 -278.085296)
				)
			)
		)
	)
	(zone
		(layers "In1.Cu" "In2.Cu")
		(hatch none 0.5)
		(connect_pads
			(clearance 0)
		)
		(min_thickness 0.25)
		(keepout
			(tracks not_allowed)
			(vias allowed)
			(pads allowed)
			(copperpour not_allowed)
			(footprints allowed)
		)
		(placement
			(enabled no)
			(sheetname "")
		)
		(fill yes
			(thermal_gap 0.5)
			(thermal_bridge_width 0.5)
			(island_removal_mode 0)
		)
		(polygon
			(pts
				(arc
					(start 25.482296 -288.285428)
					(mid 24.821896 -288.285428)
					(end 25.482296 -288.285428)
				)
			)
		)
	)
	(zone
		(layers "In1.Cu" "In2.Cu")
		(hatch none 0.5)
		(connect_pads
			(clearance 0)
		)
		(min_thickness 0.25)
		(keepout
			(tracks not_allowed)
			(vias allowed)
			(pads allowed)
			(copperpour not_allowed)
			(footprints allowed)
		)
		(placement
			(enabled no)
			(sheetname "")
		)
		(fill yes
			(thermal_gap 0.5)
			(thermal_bridge_width 0.5)
			(island_removal_mode 0)
		)
		(polygon
			(pts
				(arc
					(start 44.670218 -301.88535)
					(mid 44.009818 -301.88535)
					(end 44.670218 -301.88535)
				)
			)
		)
	)
	(zone
		(layers "In1.Cu" "In2.Cu")
		(hatch none 0.5)
		(connect_pads
			(clearance 0)
		)
		(min_thickness 0.25)
		(keepout
			(tracks not_allowed)
			(vias allowed)
			(pads allowed)
			(copperpour not_allowed)
			(footprints allowed)
		)
		(placement
			(enabled no)
			(sheetname "")
		)
		(fill yes
			(thermal_gap 0.5)
			(thermal_bridge_width 0.5)
			(island_removal_mode 0)
		)
		(polygon
			(pts
				(arc
					(start 280.966164 -227.935028)
					(mid 280.305764 -227.935028)
					(end 280.966164 -227.935028)
				)
			)
		)
	)
	(zone
		(layers "In1.Cu" "In2.Cu")
		(hatch none 0.5)
		(connect_pads
			(clearance 0)
		)
		(min_thickness 0.25)
		(keepout
			(tracks not_allowed)
			(vias allowed)
			(pads allowed)
			(copperpour not_allowed)
			(footprints allowed)
		)
		(placement
			(enabled no)
			(sheetname "")
		)
		(fill yes
			(thermal_gap 0.5)
			(thermal_bridge_width 0.5)
			(island_removal_mode 0)
		)
		(polygon
			(pts
				(arc
					(start 25.482296 -238.985298)
					(mid 24.821896 -238.985298)
					(end 25.482296 -238.985298)
				)
			)
		)
	)
	(zone
		(layers "In1.Cu" "In2.Cu")
		(hatch none 0.5)
		(connect_pads
			(clearance 0)
		)
		(min_thickness 0.25)
		(keepout
			(tracks not_allowed)
			(vias allowed)
			(pads allowed)
			(copperpour not_allowed)
			(footprints allowed)
		)
		(placement
			(enabled no)
			(sheetname "")
		)
		(fill yes
			(thermal_gap 0.5)
			(thermal_bridge_width 0.5)
			(island_removal_mode 0)
		)
		(polygon
			(pts
				(arc
					(start 280.966164 -218.585034)
					(mid 280.305764 -218.585034)
					(end 280.966164 -218.585034)
				)
			)
		)
	)
	(zone
		(layers "In1.Cu" "In2.Cu")
		(hatch none 0.5)
		(connect_pads
			(clearance 0)
		)
		(min_thickness 0.25)
		(keepout
			(tracks not_allowed)
			(vias allowed)
			(pads allowed)
			(copperpour not_allowed)
			(footprints allowed)
		)
		(placement
			(enabled no)
			(sheetname "")
		)
		(fill yes
			(thermal_gap 0.5)
			(thermal_bridge_width 0.5)
			(island_removal_mode 0)
		)
		(polygon
			(pts
				(arc
					(start 17.938242 -301.035212)
					(mid 17.277842 -301.035212)
					(end 17.938242 -301.035212)
				)
			)
		)
	)
	(zone
		(layers "In1.Cu" "In2.Cu")
		(hatch none 0.5)
		(connect_pads
			(clearance 0)
		)
		(min_thickness 0.25)
		(keepout
			(tracks not_allowed)
			(vias allowed)
			(pads allowed)
			(copperpour not_allowed)
			(footprints allowed)
		)
		(placement
			(enabled no)
			(sheetname "")
		)
		(fill yes
			(thermal_gap 0.5)
			(thermal_bridge_width 0.5)
			(island_removal_mode 0)
		)
		(polygon
			(pts
				(arc
					(start 17.938242 -235.585254)
					(mid 17.277842 -235.585254)
					(end 17.938242 -235.585254)
				)
			)
		)
	)
	(zone
		(layers "In1.Cu" "In2.Cu")
		(hatch none 0.5)
		(connect_pads
			(clearance 0)
		)
		(min_thickness 0.25)
		(keepout
			(tracks not_allowed)
			(vias allowed)
			(pads allowed)
			(copperpour not_allowed)
			(footprints allowed)
		)
		(placement
			(enabled no)
			(sheetname "")
		)
		(fill yes
			(thermal_gap 0.5)
			(thermal_bridge_width 0.5)
			(island_removal_mode 0)
		)
		(polygon
			(pts
				(arc
					(start 277.522432 -204.985112)
					(mid 276.862032 -204.985112)
					(end 277.522432 -204.985112)
				)
			)
		)
	)
	(zone
		(layers "In1.Cu" "In2.Cu")
		(hatch none 0.5)
		(connect_pads
			(clearance 0)
		)
		(min_thickness 0.25)
		(keepout
			(tracks not_allowed)
			(vias allowed)
			(pads allowed)
			(copperpour not_allowed)
			(footprints allowed)
		)
		(placement
			(enabled no)
			(sheetname "")
		)
		(fill yes
			(thermal_gap 0.5)
			(thermal_bridge_width 0.5)
			(island_removal_mode 0)
		)
		(polygon
			(pts
				(arc
					(start 194.934332 -201.585322)
					(mid 194.273932 -201.585322)
					(end 194.934332 -201.585322)
				)
			)
		)
	)
	(zone
		(layers "In1.Cu" "In2.Cu")
		(hatch none 0.5)
		(connect_pads
			(clearance 0)
		)
		(min_thickness 0.25)
		(keepout
			(tracks not_allowed)
			(vias allowed)
			(pads allowed)
			(copperpour not_allowed)
			(footprints allowed)
		)
		(placement
			(enabled no)
			(sheetname "")
		)
		(fill yes
			(thermal_gap 0.5)
			(thermal_bridge_width 0.5)
			(island_removal_mode 0)
		)
		(polygon
			(pts
				(arc
					(start 37.126164 -219.435426)
					(mid 36.465764 -219.435426)
					(end 37.126164 -219.435426)
				)
			)
		)
	)
	(zone
		(layers "In1.Cu" "In2.Cu")
		(hatch none 0.5)
		(connect_pads
			(clearance 0)
		)
		(min_thickness 0.25)
		(keepout
			(tracks not_allowed)
			(vias allowed)
			(pads allowed)
			(copperpour not_allowed)
			(footprints allowed)
		)
		(placement
			(enabled no)
			(sheetname "")
		)
		(fill yes
			(thermal_gap 0.5)
			(thermal_bridge_width 0.5)
			(island_removal_mode 0)
		)
		(polygon
			(pts
				(arc
					(start 446.974468 -298.485052)
					(mid 446.314068 -298.485052)
					(end 446.974468 -298.485052)
				)
			)
		)
	)
	(zone
		(layers "In1.Cu" "In2.Cu")
		(hatch none 0.5)
		(connect_pads
			(clearance 0)
		)
		(min_thickness 0.25)
		(keepout
			(tracks not_allowed)
			(vias allowed)
			(pads allowed)
			(copperpour not_allowed)
			(footprints allowed)
		)
		(placement
			(enabled no)
			(sheetname "")
		)
		(fill yes
			(thermal_gap 0.5)
			(thermal_bridge_width 0.5)
			(island_removal_mode 0)
		)
		(polygon
			(pts
				(arc
					(start 29.582364 -247.485408)
					(mid 28.921964 -247.485408)
					(end 29.582364 -247.485408)
				)
			)
		)
	)
	(zone
		(layers "In1.Cu" "In2.Cu")
		(hatch none 0.5)
		(connect_pads
			(clearance 0)
		)
		(min_thickness 0.25)
		(keepout
			(tracks not_allowed)
			(vias allowed)
			(pads allowed)
			(copperpour not_allowed)
			(footprints allowed)
		)
		(placement
			(enabled no)
			(sheetname "")
		)
		(fill yes
			(thermal_gap 0.5)
			(thermal_bridge_width 0.5)
			(island_removal_mode 0)
		)
		(polygon
			(pts
				(arc
					(start 269.978378 -273.835114)
					(mid 269.317978 -273.835114)
					(end 269.978378 -273.835114)
				)
			)
		)
	)
	(zone
		(layers "In1.Cu" "In2.Cu")
		(hatch none 0.5)
		(connect_pads
			(clearance 0)
		)
		(min_thickness 0.25)
		(keepout
			(tracks not_allowed)
			(vias allowed)
			(pads allowed)
			(copperpour not_allowed)
			(footprints allowed)
		)
		(placement
			(enabled no)
			(sheetname "")
		)
		(fill yes
			(thermal_gap 0.5)
			(thermal_bridge_width 0.5)
			(island_removal_mode 0)
		)
		(polygon
			(pts
				(arc
					(start 194.934332 -251.735336)
					(mid 194.273932 -251.735336)
					(end 194.934332 -251.735336)
				)
			)
		)
	)
	(zone
		(layers "In1.Cu" "In2.Cu")
		(hatch none 0.5)
		(connect_pads
			(clearance 0)
		)
		(min_thickness 0.25)
		(keepout
			(tracks not_allowed)
			(vias allowed)
			(pads allowed)
			(copperpour not_allowed)
			(footprints allowed)
		)
		(placement
			(enabled no)
			(sheetname "")
		)
		(fill yes
			(thermal_gap 0.5)
			(thermal_bridge_width 0.5)
			(island_removal_mode 0)
		)
		(polygon
			(pts
				(arc
					(start 392.609578 -17.967198)
					(mid 392.631896 -18.02108)
					(end 392.685778 -18.043398)
				)
				(arc
					(start 392.881358 -18.043398)
					(mid 392.903234 -18.040266)
					(end 392.923268 -18.030952)
				)
				(arc
					(start 393.216892 -17.83842)
					(mid 393.258548 -17.826018)
					(end 393.300204 -17.83842)
				)
				(arc
					(start 393.595098 -18.030952)
					(mid 393.615022 -18.040188)
					(end 393.636754 -18.043398)
				)
				(arc
					(start 393.831318 -18.043398)
					(mid 393.8852 -18.02108)
					(end 393.907518 -17.967198)
				)
				(arc
					(start 393.907518 -17.281398)
					(mid 393.8852 -17.227516)
					(end 393.831318 -17.205198)
				)
				(arc
					(start 393.636754 -17.205198)
					(mid 393.61501 -17.208366)
					(end 393.595098 -17.217644)
				)
				(arc
					(start 393.298934 -17.41043)
					(mid 393.25725 -17.422652)
					(end 393.215622 -17.410176)
				)
				(arc
					(start 392.921998 -17.217644)
					(mid 392.902074 -17.208408)
					(end 392.880342 -17.205198)
				)
				(arc
					(start 392.685778 -17.205198)
					(mid 392.631896 -17.227516)
					(end 392.609578 -17.281398)
				)
			)
		)
	)
	(zone
		(layers "In1.Cu" "In2.Cu")
		(hatch none 0.5)
		(connect_pads
			(clearance 0)
		)
		(min_thickness 0.25)
		(keepout
			(tracks not_allowed)
			(vias allowed)
			(pads allowed)
			(copperpour not_allowed)
			(footprints allowed)
		)
		(placement
			(enabled no)
			(sheetname "")
		)
		(fill yes
			(thermal_gap 0.5)
			(thermal_bridge_width 0.5)
			(island_removal_mode 0)
		)
		(polygon
			(pts
				(arc
					(start 424.342306 -284.88513)
					(mid 423.681906 -284.88513)
					(end 424.342306 -284.88513)
				)
			)
		)
	)
	(zone
		(layers "In1.Cu" "In2.Cu")
		(hatch none 0.5)
		(connect_pads
			(clearance 0)
		)
		(min_thickness 0.25)
		(keepout
			(tracks not_allowed)
			(vias allowed)
			(pads allowed)
			(copperpour not_allowed)
			(footprints allowed)
		)
		(placement
			(enabled no)
			(sheetname "")
		)
		(fill yes
			(thermal_gap 0.5)
			(thermal_bridge_width 0.5)
			(island_removal_mode 0)
		)
		(polygon
			(pts
				(arc
					(start 288.510218 -198.185024)
					(mid 287.849818 -198.185024)
					(end 288.510218 -198.185024)
				)
			)
		)
	)
	(zone
		(layers "In1.Cu" "In2.Cu")
		(hatch none 0.5)
		(connect_pads
			(clearance 0)
		)
		(min_thickness 0.25)
		(keepout
			(tracks not_allowed)
			(vias allowed)
			(pads allowed)
			(copperpour not_allowed)
			(footprints allowed)
		)
		(placement
			(enabled no)
			(sheetname "")
		)
		(fill yes
			(thermal_gap 0.5)
			(thermal_bridge_width 0.5)
			(island_removal_mode 0)
		)
		(polygon
			(pts
				(arc
					(start 427.786292 -229.63505)
					(mid 427.125892 -229.63505)
					(end 427.786292 -229.63505)
				)
			)
		)
	)
	(zone
		(layers "In1.Cu" "In2.Cu")
		(hatch none 0.5)
		(connect_pads
			(clearance 0)
		)
		(min_thickness 0.25)
		(keepout
			(tracks not_allowed)
			(vias allowed)
			(pads allowed)
			(copperpour not_allowed)
			(footprints allowed)
		)
		(placement
			(enabled no)
			(sheetname "")
		)
		(fill yes
			(thermal_gap 0.5)
			(thermal_bridge_width 0.5)
			(island_removal_mode 0)
		)
		(polygon
			(pts
				(arc
					(start 29.582364 -216.035382)
					(mid 28.921964 -216.035382)
					(end 29.582364 -216.035382)
				)
			)
		)
	)
	(zone
		(layers "In1.Cu" "In2.Cu")
		(hatch none 0.5)
		(connect_pads
			(clearance 0)
		)
		(min_thickness 0.25)
		(keepout
			(tracks not_allowed)
			(vias allowed)
			(pads allowed)
			(copperpour not_allowed)
			(footprints allowed)
		)
		(placement
			(enabled no)
			(sheetname "")
		)
		(fill yes
			(thermal_gap 0.5)
			(thermal_bridge_width 0.5)
			(island_removal_mode 0)
		)
		(polygon
			(pts
				(arc
					(start 435.330346 -265.335004)
					(mid 434.669946 -265.335004)
					(end 435.330346 -265.335004)
				)
			)
		)
	)
	(zone
		(layers "In1.Cu" "In2.Cu")
		(hatch none 0.5)
		(connect_pads
			(clearance 0)
		)
		(min_thickness 0.25)
		(keepout
			(tracks not_allowed)
			(vias allowed)
			(pads allowed)
			(copperpour not_allowed)
			(footprints allowed)
		)
		(placement
			(enabled no)
			(sheetname "")
		)
		(fill yes
			(thermal_gap 0.5)
			(thermal_bridge_width 0.5)
			(island_removal_mode 0)
		)
		(polygon
			(pts
				(arc
					(start 194.934332 -213.485222)
					(mid 194.273932 -213.485222)
					(end 194.934332 -213.485222)
				)
			)
		)
	)
	(zone
		(layers "In1.Cu" "In2.Cu")
		(hatch none 0.5)
		(connect_pads
			(clearance 0)
		)
		(min_thickness 0.25)
		(keepout
			(tracks not_allowed)
			(vias allowed)
			(pads allowed)
			(copperpour not_allowed)
			(footprints allowed)
		)
		(placement
			(enabled no)
			(sheetname "")
		)
		(fill yes
			(thermal_gap 0.5)
			(thermal_bridge_width 0.5)
			(island_removal_mode 0)
		)
		(polygon
			(pts
				(arc
					(start 48.114204 -274.685252)
					(mid 47.453804 -274.685252)
					(end 48.114204 -274.685252)
				)
			)
		)
	)
	(zone
		(layers "In1.Cu" "In2.Cu")
		(hatch none 0.5)
		(connect_pads
			(clearance 0)
		)
		(min_thickness 0.25)
		(keepout
			(tracks not_allowed)
			(vias allowed)
			(pads allowed)
			(copperpour not_allowed)
			(footprints allowed)
		)
		(placement
			(enabled no)
			(sheetname "")
		)
		(fill yes
			(thermal_gap 0.5)
			(thermal_bridge_width 0.5)
			(island_removal_mode 0)
		)
		(polygon
			(pts
				(arc
					(start 40.57015 -308.685438)
					(mid 39.90975 -308.685438)
					(end 40.57015 -308.685438)
				)
			)
		)
	)
	(zone
		(layers "In1.Cu" "In2.Cu")
		(hatch none 0.5)
		(connect_pads
			(clearance 0)
		)
		(min_thickness 0.25)
		(keepout
			(tracks not_allowed)
			(vias allowed)
			(pads allowed)
			(copperpour not_allowed)
			(footprints allowed)
		)
		(placement
			(enabled no)
			(sheetname "")
		)
		(fill yes
			(thermal_gap 0.5)
			(thermal_bridge_width 0.5)
			(island_removal_mode 0)
		)
		(polygon
			(pts
				(arc
					(start 194.934332 -207.535272)
					(mid 194.273932 -207.535272)
					(end 194.934332 -207.535272)
				)
			)
		)
	)
	(zone
		(layers "In1.Cu" "In2.Cu")
		(hatch none 0.5)
		(connect_pads
			(clearance 0)
		)
		(min_thickness 0.25)
		(keepout
			(tracks not_allowed)
			(vias allowed)
			(pads allowed)
			(copperpour not_allowed)
			(footprints allowed)
		)
		(placement
			(enabled no)
			(sheetname "")
		)
		(fill yes
			(thermal_gap 0.5)
			(thermal_bridge_width 0.5)
			(island_removal_mode 0)
		)
		(polygon
			(pts
				(arc
					(start 48.114204 -232.18521)
					(mid 47.453804 -232.18521)
					(end 48.114204 -232.18521)
				)
			)
		)
	)
	(zone
		(layers "In1.Cu" "In2.Cu")
		(hatch none 0.5)
		(connect_pads
			(clearance 0)
		)
		(min_thickness 0.25)
		(keepout
			(tracks not_allowed)
			(vias allowed)
			(pads allowed)
			(copperpour not_allowed)
			(footprints allowed)
		)
		(placement
			(enabled no)
			(sheetname "")
		)
		(fill yes
			(thermal_gap 0.5)
			(thermal_bridge_width 0.5)
			(island_removal_mode 0)
		)
		(polygon
			(pts
				(arc
					(start 202.478132 -280.635202)
					(mid 201.817732 -280.635202)
					(end 202.478132 -280.635202)
				)
			)
		)
	)
	(zone
		(layers "In1.Cu" "In2.Cu")
		(hatch none 0.5)
		(connect_pads
			(clearance 0)
		)
		(min_thickness 0.25)
		(keepout
			(tracks not_allowed)
			(vias allowed)
			(pads allowed)
			(copperpour not_allowed)
			(footprints allowed)
		)
		(placement
			(enabled no)
			(sheetname "")
		)
		(fill yes
			(thermal_gap 0.5)
			(thermal_bridge_width 0.5)
			(island_removal_mode 0)
		)
		(polygon
			(pts
				(arc
					(start 442.8744 -310.384952)
					(mid 442.214 -310.384952)
					(end 442.8744 -310.384952)
				)
			)
		)
	)
	(zone
		(layers "In1.Cu" "In2.Cu")
		(hatch none 0.5)
		(connect_pads
			(clearance 0)
		)
		(min_thickness 0.25)
		(keepout
			(tracks not_allowed)
			(vias allowed)
			(pads allowed)
			(copperpour not_allowed)
			(footprints allowed)
		)
		(placement
			(enabled no)
			(sheetname "")
		)
		(fill yes
			(thermal_gap 0.5)
			(thermal_bridge_width 0.5)
			(island_removal_mode 0)
		)
		(polygon
			(pts
				(arc
					(start 40.57015 -313.78525)
					(mid 39.90975 -313.78525)
					(end 40.57015 -313.78525)
				)
			)
		)
	)
	(zone
		(layers "In1.Cu" "In2.Cu")
		(hatch none 0.5)
		(connect_pads
			(clearance 0)
		)
		(min_thickness 0.25)
		(keepout
			(tracks not_allowed)
			(vias allowed)
			(pads allowed)
			(copperpour not_allowed)
			(footprints allowed)
		)
		(placement
			(enabled no)
			(sheetname "")
		)
		(fill yes
			(thermal_gap 0.5)
			(thermal_bridge_width 0.5)
			(island_removal_mode 0)
		)
		(polygon
			(pts
				(arc
					(start 29.582364 -294.235378)
					(mid 28.921964 -294.235378)
					(end 29.582364 -294.235378)
				)
			)
		)
	)
	(zone
		(layers "In1.Cu" "In2.Cu")
		(hatch none 0.5)
		(connect_pads
			(clearance 0)
		)
		(min_thickness 0.25)
		(keepout
			(tracks not_allowed)
			(vias allowed)
			(pads allowed)
			(copperpour not_allowed)
			(footprints allowed)
		)
		(placement
			(enabled no)
			(sheetname "")
		)
		(fill yes
			(thermal_gap 0.5)
			(thermal_bridge_width 0.5)
			(island_removal_mode 0)
		)
		(polygon
			(pts
				(arc
					(start 296.054272 -301.034958)
					(mid 295.393872 -301.034958)
					(end 296.054272 -301.034958)
				)
			)
		)
	)
	(zone
		(layers "In1.Cu" "In2.Cu")
		(hatch none 0.5)
		(connect_pads
			(clearance 0)
		)
		(min_thickness 0.25)
		(keepout
			(tracks not_allowed)
			(vias allowed)
			(pads allowed)
			(copperpour not_allowed)
			(footprints allowed)
		)
		(placement
			(enabled no)
			(sheetname "")
		)
		(fill yes
			(thermal_gap 0.5)
			(thermal_bridge_width 0.5)
			(island_removal_mode 0)
		)
		(polygon
			(pts
				(arc
					(start 454.518268 -311.23509)
					(mid 453.857868 -311.23509)
					(end 454.518268 -311.23509)
				)
			)
		)
	)
	(zone
		(layers "In1.Cu" "In2.Cu")
		(hatch none 0.5)
		(connect_pads
			(clearance 0)
		)
		(min_thickness 0.25)
		(keepout
			(tracks not_allowed)
			(vias allowed)
			(pads allowed)
			(copperpour not_allowed)
			(footprints allowed)
		)
		(placement
			(enabled no)
			(sheetname "")
		)
		(fill yes
			(thermal_gap 0.5)
			(thermal_bridge_width 0.5)
			(island_removal_mode 0)
		)
		(polygon
			(pts
				(arc
					(start 40.56253 -7.672324)
					(mid 40.584848 -7.618442)
					(end 40.63873 -7.596124)
				)
				(arc
					(start 41.675304 -7.596124)
					(mid 41.729186 -7.618442)
					(end 41.751504 -7.672324)
				)
				(arc
					(start 41.751504 -9.071864)
					(mid 41.729186 -9.125746)
					(end 41.675304 -9.148064)
				)
				(arc
					(start 40.63873 -9.148064)
					(mid 40.584848 -9.125746)
					(end 40.56253 -9.071864)
				)
			)
		)
	)
	(zone
		(layers "In1.Cu" "In2.Cu")
		(hatch none 0.5)
		(connect_pads
			(clearance 0)
		)
		(min_thickness 0.25)
		(keepout
			(tracks not_allowed)
			(vias allowed)
			(pads allowed)
			(copperpour not_allowed)
			(footprints allowed)
		)
		(placement
			(enabled no)
			(sheetname "")
		)
		(fill yes
			(thermal_gap 0.5)
			(thermal_bridge_width 0.5)
			(island_removal_mode 0)
		)
		(polygon
			(pts
				(arc
					(start 450.4182 -308.685184)
					(mid 449.7578 -308.685184)
					(end 450.4182 -308.685184)
				)
			)
		)
	)
	(zone
		(layers "In1.Cu" "In2.Cu")
		(hatch none 0.5)
		(connect_pads
			(clearance 0)
		)
		(min_thickness 0.25)
		(keepout
			(tracks not_allowed)
			(vias allowed)
			(pads allowed)
			(copperpour not_allowed)
			(footprints allowed)
		)
		(placement
			(enabled no)
			(sheetname "")
		)
		(fill yes
			(thermal_gap 0.5)
			(thermal_bridge_width 0.5)
			(island_removal_mode 0)
		)
		(polygon
			(pts
				(arc
					(start 404.372572 -417.242244)
					(mid 404.39489 -417.296126)
					(end 404.448772 -417.318444)
				)
				(arc
					(start 404.644352 -417.318444)
					(mid 404.666228 -417.315312)
					(end 404.686262 -417.305998)
				)
				(arc
					(start 404.979886 -417.113466)
					(mid 405.021542 -417.101064)
					(end 405.063198 -417.113466)
				)
				(arc
					(start 405.358092 -417.305998)
					(mid 405.378016 -417.315234)
					(end 405.399748 -417.318444)
				)
				(arc
					(start 405.594312 -417.318444)
					(mid 405.648194 -417.296126)
					(end 405.670512 -417.242244)
				)
				(arc
					(start 405.670512 -416.556444)
					(mid 405.648194 -416.502562)
					(end 405.594312 -416.480244)
				)
				(arc
					(start 405.399748 -416.480244)
					(mid 405.378004 -416.483412)
					(end 405.358092 -416.49269)
				)
				(arc
					(start 405.061928 -416.685476)
					(mid 405.020244 -416.697698)
					(end 404.978616 -416.685222)
				)
				(arc
					(start 404.684992 -416.49269)
					(mid 404.665068 -416.483454)
					(end 404.643336 -416.480244)
				)
				(arc
					(start 404.448772 -416.480244)
					(mid 404.39489 -416.502562)
					(end 404.372572 -416.556444)
				)
			)
		)
	)
	(zone
		(layers "In1.Cu" "In2.Cu")
		(hatch none 0.5)
		(connect_pads
			(clearance 0)
		)
		(min_thickness 0.25)
		(keepout
			(tracks not_allowed)
			(vias allowed)
			(pads allowed)
			(copperpour not_allowed)
			(footprints allowed)
		)
		(placement
			(enabled no)
			(sheetname "")
		)
		(fill yes
			(thermal_gap 0.5)
			(thermal_bridge_width 0.5)
			(island_removal_mode 0)
		)
		(polygon
			(pts
				(arc
					(start 280.966164 -277.235158)
					(mid 280.305764 -277.235158)
					(end 280.966164 -277.235158)
				)
			)
		)
	)
	(zone
		(layers "In1.Cu" "In2.Cu")
		(hatch none 0.5)
		(connect_pads
			(clearance 0)
		)
		(min_thickness 0.25)
		(keepout
			(tracks not_allowed)
			(vias allowed)
			(pads allowed)
			(copperpour not_allowed)
			(footprints allowed)
		)
		(placement
			(enabled no)
			(sheetname "")
		)
		(fill yes
			(thermal_gap 0.5)
			(thermal_bridge_width 0.5)
			(island_removal_mode 0)
		)
		(polygon
			(pts
				(arc
					(start 288.510218 -229.63505)
					(mid 287.849818 -229.63505)
					(end 288.510218 -229.63505)
				)
			)
		)
	)
	(zone
		(layers "In1.Cu" "In2.Cu")
		(hatch none 0.5)
		(connect_pads
			(clearance 0)
		)
		(min_thickness 0.25)
		(keepout
			(tracks not_allowed)
			(vias allowed)
			(pads allowed)
			(copperpour not_allowed)
			(footprints allowed)
		)
		(placement
			(enabled no)
			(sheetname "")
		)
		(fill yes
			(thermal_gap 0.5)
			(thermal_bridge_width 0.5)
			(island_removal_mode 0)
		)
		(polygon
			(pts
				(arc
					(start 420.242238 -304.435002)
					(mid 419.581838 -304.435002)
					(end 420.242238 -304.435002)
				)
			)
		)
	)
	(zone
		(layers "In1.Cu" "In2.Cu")
		(hatch none 0.5)
		(connect_pads
			(clearance 0)
		)
		(min_thickness 0.25)
		(keepout
			(tracks not_allowed)
			(vias allowed)
			(pads allowed)
			(copperpour not_allowed)
			(footprints allowed)
		)
		(placement
			(enabled no)
			(sheetname "")
		)
		(fill yes
			(thermal_gap 0.5)
			(thermal_bridge_width 0.5)
			(island_removal_mode 0)
		)
		(polygon
			(pts
				(arc
					(start 108.094018 -30.169612)
					(mid 108.108897 -30.133691)
					(end 108.144818 -30.118812)
				)
				(arc
					(start 108.652818 -30.118812)
					(mid 108.688739 -30.133691)
					(end 108.703618 -30.169612)
				)
				(arc
					(start 108.703618 -30.825948)
					(mid 108.688739 -30.861869)
					(end 108.652818 -30.876748)
				)
				(arc
					(start 108.144818 -30.876748)
					(mid 108.108897 -30.861869)
					(end 108.094018 -30.825948)
				)
			)
		)
	)
	(zone
		(layers "In1.Cu" "In2.Cu")
		(hatch none 0.5)
		(connect_pads
			(clearance 0)
		)
		(min_thickness 0.25)
		(keepout
			(tracks not_allowed)
			(vias allowed)
			(pads allowed)
			(copperpour not_allowed)
			(footprints allowed)
		)
		(placement
			(enabled no)
			(sheetname "")
		)
		(fill yes
			(thermal_gap 0.5)
			(thermal_bridge_width 0.5)
			(island_removal_mode 0)
		)
		(polygon
			(pts
				(arc
					(start 288.510218 -205.834996)
					(mid 287.849818 -205.834996)
					(end 288.510218 -205.834996)
				)
			)
		)
	)
	(zone
		(layers "In1.Cu" "In2.Cu")
		(hatch none 0.5)
		(connect_pads
			(clearance 0)
		)
		(min_thickness 0.25)
		(keepout
			(tracks not_allowed)
			(vias allowed)
			(pads allowed)
			(copperpour not_allowed)
			(footprints allowed)
		)
		(placement
			(enabled no)
			(sheetname "")
		)
		(fill yes
			(thermal_gap 0.5)
			(thermal_bridge_width 0.5)
			(island_removal_mode 0)
		)
		(polygon
			(pts
				(arc
					(start 172.30217 -254.285242)
					(mid 171.64177 -254.285242)
					(end 172.30217 -254.285242)
				)
			)
		)
	)
	(zone
		(layers "In1.Cu" "In2.Cu")
		(hatch none 0.5)
		(connect_pads
			(clearance 0)
		)
		(min_thickness 0.25)
		(keepout
			(tracks not_allowed)
			(vias allowed)
			(pads allowed)
			(copperpour not_allowed)
			(footprints allowed)
		)
		(placement
			(enabled no)
			(sheetname "")
		)
		(fill yes
			(thermal_gap 0.5)
			(thermal_bridge_width 0.5)
			(island_removal_mode 0)
		)
		(polygon
			(pts
				(arc
					(start 431.88636 -283.185108)
					(mid 431.22596 -283.185108)
					(end 431.88636 -283.185108)
				)
			)
		)
	)
	(zone
		(layers "In1.Cu" "In2.Cu")
		(hatch none 0.5)
		(connect_pads
			(clearance 0)
		)
		(min_thickness 0.25)
		(keepout
			(tracks not_allowed)
			(vias allowed)
			(pads allowed)
			(copperpour not_allowed)
			(footprints allowed)
		)
		(placement
			(enabled no)
			(sheetname "")
		)
		(fill yes
			(thermal_gap 0.5)
			(thermal_bridge_width 0.5)
			(island_removal_mode 0)
		)
		(polygon
			(pts
				(arc
					(start 288.510218 -301.034958)
					(mid 287.849818 -301.034958)
					(end 288.510218 -301.034958)
				)
			)
		)
	)
	(zone
		(layers "In1.Cu" "In2.Cu")
		(hatch none 0.5)
		(connect_pads
			(clearance 0)
		)
		(min_thickness 0.25)
		(keepout
			(tracks not_allowed)
			(vias allowed)
			(pads allowed)
			(copperpour not_allowed)
			(footprints allowed)
		)
		(placement
			(enabled no)
			(sheetname "")
		)
		(fill yes
			(thermal_gap 0.5)
			(thermal_bridge_width 0.5)
			(island_removal_mode 0)
		)
		(polygon
			(pts
				(arc
					(start 29.582364 -289.135312)
					(mid 28.921964 -289.135312)
					(end 29.582364 -289.135312)
				)
			)
		)
	)
	(zone
		(layers "In1.Cu" "In2.Cu")
		(hatch none 0.5)
		(connect_pads
			(clearance 0)
		)
		(min_thickness 0.25)
		(keepout
			(tracks not_allowed)
			(vias allowed)
			(pads allowed)
			(copperpour not_allowed)
			(footprints allowed)
		)
		(placement
			(enabled no)
			(sheetname "")
		)
		(fill yes
			(thermal_gap 0.5)
			(thermal_bridge_width 0.5)
			(island_removal_mode 0)
		)
		(polygon
			(pts
				(arc
					(start 52.214272 -197.335394)
					(mid 51.553872 -197.335394)
					(end 52.214272 -197.335394)
				)
			)
		)
	)
	(zone
		(layers "In1.Cu" "In2.Cu")
		(hatch none 0.5)
		(connect_pads
			(clearance 0)
		)
		(min_thickness 0.25)
		(keepout
			(tracks not_allowed)
			(vias allowed)
			(pads allowed)
			(copperpour not_allowed)
			(footprints allowed)
		)
		(placement
			(enabled no)
			(sheetname "")
		)
		(fill yes
			(thermal_gap 0.5)
			(thermal_bridge_width 0.5)
			(island_removal_mode 0)
		)
		(polygon
			(pts
				(arc
					(start 172.30217 -277.235412)
					(mid 171.64177 -277.235412)
					(end 172.30217 -277.235412)
				)
			)
		)
	)
	(zone
		(layers "In1.Cu" "In2.Cu")
		(hatch none 0.5)
		(connect_pads
			(clearance 0)
		)
		(min_thickness 0.25)
		(keepout
			(tracks not_allowed)
			(vias allowed)
			(pads allowed)
			(copperpour not_allowed)
			(footprints allowed)
		)
		(placement
			(enabled no)
			(sheetname "")
		)
		(fill yes
			(thermal_gap 0.5)
			(thermal_bridge_width 0.5)
			(island_removal_mode 0)
		)
		(polygon
			(pts
				(arc
					(start 52.214272 -275.53539)
					(mid 51.553872 -275.53539)
					(end 52.214272 -275.53539)
				)
			)
		)
	)
	(zone
		(layers "In1.Cu" "In2.Cu")
		(hatch none 0.5)
		(connect_pads
			(clearance 0)
		)
		(min_thickness 0.25)
		(keepout
			(tracks not_allowed)
			(vias allowed)
			(pads allowed)
			(copperpour not_allowed)
			(footprints allowed)
		)
		(placement
			(enabled no)
			(sheetname "")
		)
		(fill yes
			(thermal_gap 0.5)
			(thermal_bridge_width 0.5)
			(island_removal_mode 0)
		)
		(polygon
			(pts
				(arc
					(start 285.066232 -278.085042)
					(mid 284.405832 -278.085042)
					(end 285.066232 -278.085042)
				)
			)
		)
	)
	(zone
		(layers "In1.Cu" "In2.Cu")
		(hatch none 0.5)
		(connect_pads
			(clearance 0)
		)
		(min_thickness 0.25)
		(keepout
			(tracks not_allowed)
			(vias allowed)
			(pads allowed)
			(copperpour not_allowed)
			(footprints allowed)
		)
		(placement
			(enabled no)
			(sheetname "")
		)
		(fill yes
			(thermal_gap 0.5)
			(thermal_bridge_width 0.5)
			(island_removal_mode 0)
		)
		(polygon
			(pts
				(arc
					(start 176.402238 -206.685388)
					(mid 175.741838 -206.685388)
					(end 176.402238 -206.685388)
				)
			)
		)
	)
	(zone
		(layers "In1.Cu" "In2.Cu")
		(hatch none 0.5)
		(connect_pads
			(clearance 0)
		)
		(min_thickness 0.25)
		(keepout
			(tracks not_allowed)
			(vias allowed)
			(pads allowed)
			(copperpour not_allowed)
			(footprints allowed)
		)
		(placement
			(enabled no)
			(sheetname "")
		)
		(fill yes
			(thermal_gap 0.5)
			(thermal_bridge_width 0.5)
			(island_removal_mode 0)
		)
		(polygon
			(pts
				(arc
					(start 48.114204 -220.28531)
					(mid 47.453804 -220.28531)
					(end 48.114204 -220.28531)
				)
			)
		)
	)
	(zone
		(layers "In1.Cu" "In2.Cu")
		(hatch none 0.5)
		(connect_pads
			(clearance 0)
		)
		(min_thickness 0.25)
		(keepout
			(tracks not_allowed)
			(vias allowed)
			(pads allowed)
			(copperpour not_allowed)
			(footprints allowed)
		)
		(placement
			(enabled no)
			(sheetname "")
		)
		(fill yes
			(thermal_gap 0.5)
			(thermal_bridge_width 0.5)
			(island_removal_mode 0)
		)
		(polygon
			(pts
				(arc
					(start 296.054272 -199.885046)
					(mid 295.393872 -199.885046)
					(end 296.054272 -199.885046)
				)
			)
		)
	)
	(zone
		(layers "In1.Cu" "In2.Cu")
		(hatch none 0.5)
		(connect_pads
			(clearance 0)
		)
		(min_thickness 0.25)
		(keepout
			(tracks not_allowed)
			(vias allowed)
			(pads allowed)
			(copperpour not_allowed)
			(footprints allowed)
		)
		(placement
			(enabled no)
			(sheetname "")
		)
		(fill yes
			(thermal_gap 0.5)
			(thermal_bridge_width 0.5)
			(island_removal_mode 0)
		)
		(polygon
			(pts
				(arc
					(start 25.482296 -226.23526)
					(mid 24.821896 -226.23526)
					(end 25.482296 -226.23526)
				)
			)
		)
	)
	(zone
		(layers "In1.Cu" "In2.Cu")
		(hatch none 0.5)
		(connect_pads
			(clearance 0)
		)
		(min_thickness 0.25)
		(keepout
			(tracks not_allowed)
			(vias allowed)
			(pads allowed)
			(copperpour not_allowed)
			(footprints allowed)
		)
		(placement
			(enabled no)
			(sheetname "")
		)
		(fill yes
			(thermal_gap 0.5)
			(thermal_bridge_width 0.5)
			(island_removal_mode 0)
		)
		(polygon
			(pts
				(arc
					(start 179.846224 -267.03528)
					(mid 179.185824 -267.03528)
					(end 179.846224 -267.03528)
				)
			)
		)
	)
	(zone
		(layers "In1.Cu" "In2.Cu")
		(hatch none 0.5)
		(connect_pads
			(clearance 0)
		)
		(min_thickness 0.25)
		(keepout
			(tracks not_allowed)
			(vias allowed)
			(pads allowed)
			(copperpour not_allowed)
			(footprints allowed)
		)
		(placement
			(enabled no)
			(sheetname "")
		)
		(fill yes
			(thermal_gap 0.5)
			(thermal_bridge_width 0.5)
			(island_removal_mode 0)
		)
		(polygon
			(pts
				(arc
					(start 454.518268 -275.535136)
					(mid 453.857868 -275.535136)
					(end 454.518268 -275.535136)
				)
			)
		)
	)
	(zone
		(layers "In1.Cu" "In2.Cu")
		(hatch none 0.5)
		(connect_pads
			(clearance 0)
		)
		(min_thickness 0.25)
		(keepout
			(tracks not_allowed)
			(vias allowed)
			(pads allowed)
			(copperpour not_allowed)
			(footprints allowed)
		)
		(placement
			(enabled no)
			(sheetname "")
		)
		(fill yes
			(thermal_gap 0.5)
			(thermal_bridge_width 0.5)
			(island_removal_mode 0)
		)
		(polygon
			(pts
				(arc
					(start 48.114204 -267.03528)
					(mid 47.453804 -267.03528)
					(end 48.114204 -267.03528)
				)
			)
		)
	)
	(zone
		(layers "In1.Cu" "In2.Cu")
		(hatch none 0.5)
		(connect_pads
			(clearance 0)
		)
		(min_thickness 0.25)
		(keepout
			(tracks not_allowed)
			(vias allowed)
			(pads allowed)
			(copperpour not_allowed)
			(footprints allowed)
		)
		(placement
			(enabled no)
			(sheetname "")
		)
		(fill yes
			(thermal_gap 0.5)
			(thermal_bridge_width 0.5)
			(island_removal_mode 0)
		)
		(polygon
			(pts
				(arc
					(start 183.946292 -249.18543)
					(mid 183.285892 -249.18543)
					(end 183.946292 -249.18543)
				)
			)
		)
	)
	(zone
		(layers "In1.Cu" "In2.Cu")
		(hatch none 0.5)
		(connect_pads
			(clearance 0)
		)
		(min_thickness 0.25)
		(keepout
			(tracks not_allowed)
			(vias allowed)
			(pads allowed)
			(copperpour not_allowed)
			(footprints allowed)
		)
		(placement
			(enabled no)
			(sheetname "")
		)
		(fill yes
			(thermal_gap 0.5)
			(thermal_bridge_width 0.5)
			(island_removal_mode 0)
		)
		(polygon
			(pts
				(arc
					(start 424.342306 -225.385122)
					(mid 423.681906 -225.385122)
					(end 424.342306 -225.385122)
				)
			)
		)
	)
	(zone
		(layers "In1.Cu" "In2.Cu")
		(hatch none 0.5)
		(connect_pads
			(clearance 0)
		)
		(min_thickness 0.25)
		(keepout
			(tracks not_allowed)
			(vias allowed)
			(pads allowed)
			(copperpour not_allowed)
			(footprints allowed)
		)
		(placement
			(enabled no)
			(sheetname "")
		)
		(fill yes
			(thermal_gap 0.5)
			(thermal_bridge_width 0.5)
			(island_removal_mode 0)
		)
		(polygon
			(pts
				(arc
					(start 33.026096 -238.985298)
					(mid 32.365696 -238.985298)
					(end 33.026096 -238.985298)
				)
			)
		)
	)
	(zone
		(layers "In1.Cu" "In2.Cu")
		(hatch none 0.5)
		(connect_pads
			(clearance 0)
		)
		(min_thickness 0.25)
		(keepout
			(tracks not_allowed)
			(vias allowed)
			(pads allowed)
			(copperpour not_allowed)
			(footprints allowed)
		)
		(placement
			(enabled no)
			(sheetname "")
		)
		(fill yes
			(thermal_gap 0.5)
			(thermal_bridge_width 0.5)
			(island_removal_mode 0)
		)
		(polygon
			(pts
				(arc
					(start 435.330346 -232.184956)
					(mid 434.669946 -232.184956)
					(end 435.330346 -232.184956)
				)
			)
		)
	)
	(zone
		(layers "In1.Cu" "In2.Cu")
		(hatch none 0.5)
		(connect_pads
			(clearance 0)
		)
		(min_thickness 0.25)
		(keepout
			(tracks not_allowed)
			(vias allowed)
			(pads allowed)
			(copperpour not_allowed)
			(footprints allowed)
		)
		(placement
			(enabled no)
			(sheetname "")
		)
		(fill yes
			(thermal_gap 0.5)
			(thermal_bridge_width 0.5)
			(island_removal_mode 0)
		)
		(polygon
			(pts
				(arc
					(start 395.403578 -16.443198)
					(mid 395.425896 -16.49708)
					(end 395.479778 -16.519398)
				)
				(arc
					(start 395.675358 -16.519398)
					(mid 395.697234 -16.516266)
					(end 395.717268 -16.506952)
				)
				(arc
					(start 396.010892 -16.31442)
					(mid 396.052548 -16.302018)
					(end 396.094204 -16.31442)
				)
				(arc
					(start 396.389098 -16.506952)
					(mid 396.409022 -16.516188)
					(end 396.430754 -16.519398)
				)
				(arc
					(start 396.625318 -16.519398)
					(mid 396.6792 -16.49708)
					(end 396.701518 -16.443198)
				)
				(arc
					(start 396.701518 -15.757398)
					(mid 396.6792 -15.703516)
					(end 396.625318 -15.681198)
				)
				(arc
					(start 396.430754 -15.681198)
					(mid 396.40901 -15.684366)
					(end 396.389098 -15.693644)
				)
				(arc
					(start 396.092934 -15.88643)
					(mid 396.05125 -15.898652)
					(end 396.009622 -15.886176)
				)
				(arc
					(start 395.715998 -15.693644)
					(mid 395.696074 -15.684408)
					(end 395.674342 -15.681198)
				)
				(arc
					(start 395.479778 -15.681198)
					(mid 395.425896 -15.703516)
					(end 395.403578 -15.757398)
				)
			)
		)
	)
	(zone
		(layers "In1.Cu" "In2.Cu")
		(hatch none 0.5)
		(connect_pads
			(clearance 0)
		)
		(min_thickness 0.25)
		(keepout
			(tracks not_allowed)
			(vias allowed)
			(pads allowed)
			(copperpour not_allowed)
			(footprints allowed)
		)
		(placement
			(enabled no)
			(sheetname "")
		)
		(fill yes
			(thermal_gap 0.5)
			(thermal_bridge_width 0.5)
			(island_removal_mode 0)
		)
		(polygon
			(pts
				(arc
					(start 280.966164 -316.335156)
					(mid 280.305764 -316.335156)
					(end 280.966164 -316.335156)
				)
			)
		)
	)
	(zone
		(layers "In1.Cu" "In2.Cu")
		(hatch none 0.5)
		(connect_pads
			(clearance 0)
		)
		(min_thickness 0.25)
		(keepout
			(tracks not_allowed)
			(vias allowed)
			(pads allowed)
			(copperpour not_allowed)
			(footprints allowed)
		)
		(placement
			(enabled no)
			(sheetname "")
		)
		(fill yes
			(thermal_gap 0.5)
			(thermal_bridge_width 0.5)
			(island_removal_mode 0)
		)
		(polygon
			(pts
				(arc
					(start 40.57015 -237.285276)
					(mid 39.90975 -237.285276)
					(end 40.57015 -237.285276)
				)
			)
		)
	)
	(zone
		(layers "In1.Cu" "In2.Cu")
		(hatch none 0.5)
		(connect_pads
			(clearance 0)
		)
		(min_thickness 0.25)
		(keepout
			(tracks not_allowed)
			(vias allowed)
			(pads allowed)
			(copperpour not_allowed)
			(footprints allowed)
		)
		(placement
			(enabled no)
			(sheetname "")
		)
		(fill yes
			(thermal_gap 0.5)
			(thermal_bridge_width 0.5)
			(island_removal_mode 0)
		)
		(polygon
			(pts
				(arc
					(start 183.946292 -276.385274)
					(mid 183.285892 -276.385274)
					(end 183.946292 -276.385274)
				)
			)
		)
	)
	(zone
		(layers "In1.Cu" "In2.Cu")
		(hatch none 0.5)
		(connect_pads
			(clearance 0)
		)
		(min_thickness 0.25)
		(keepout
			(tracks not_allowed)
			(vias allowed)
			(pads allowed)
			(copperpour not_allowed)
			(footprints allowed)
		)
		(placement
			(enabled no)
			(sheetname "")
		)
		(fill yes
			(thermal_gap 0.5)
			(thermal_bridge_width 0.5)
			(island_removal_mode 0)
		)
		(polygon
			(pts
				(arc
					(start 446.974468 -245.785132)
					(mid 446.314068 -245.785132)
					(end 446.974468 -245.785132)
				)
			)
		)
	)
	(zone
		(layers "In1.Cu" "In2.Cu")
		(hatch none 0.5)
		(connect_pads
			(clearance 0)
		)
		(min_thickness 0.25)
		(keepout
			(tracks not_allowed)
			(vias allowed)
			(pads allowed)
			(copperpour not_allowed)
			(footprints allowed)
		)
		(placement
			(enabled no)
			(sheetname "")
		)
		(fill yes
			(thermal_gap 0.5)
			(thermal_bridge_width 0.5)
			(island_removal_mode 0)
		)
		(polygon
			(pts
				(arc
					(start 48.114204 -276.385274)
					(mid 47.453804 -276.385274)
					(end 48.114204 -276.385274)
				)
			)
		)
	)
	(zone
		(layers "In1.Cu" "In2.Cu")
		(hatch none 0.5)
		(connect_pads
			(clearance 0)
		)
		(min_thickness 0.25)
		(keepout
			(tracks not_allowed)
			(vias allowed)
			(pads allowed)
			(copperpour not_allowed)
			(footprints allowed)
		)
		(placement
			(enabled no)
			(sheetname "")
		)
		(fill yes
			(thermal_gap 0.5)
			(thermal_bridge_width 0.5)
			(island_removal_mode 0)
		)
		(polygon
			(pts
				(arc
					(start 22.03831 -309.535322)
					(mid 21.37791 -309.535322)
					(end 22.03831 -309.535322)
				)
			)
		)
	)
	(zone
		(layers "In1.Cu" "In2.Cu")
		(hatch none 0.5)
		(connect_pads
			(clearance 0)
		)
		(min_thickness 0.25)
		(keepout
			(tracks not_allowed)
			(vias allowed)
			(pads allowed)
			(copperpour not_allowed)
			(footprints allowed)
		)
		(placement
			(enabled no)
			(sheetname "")
		)
		(fill yes
			(thermal_gap 0.5)
			(thermal_bridge_width 0.5)
			(island_removal_mode 0)
		)
		(polygon
			(pts
				(arc
					(start 44.670218 -281.48534)
					(mid 44.009818 -281.48534)
					(end 44.670218 -281.48534)
				)
			)
		)
	)
	(zone
		(layers "In1.Cu" "In2.Cu")
		(hatch none 0.5)
		(connect_pads
			(clearance 0)
		)
		(min_thickness 0.25)
		(keepout
			(tracks not_allowed)
			(vias allowed)
			(pads allowed)
			(copperpour not_allowed)
			(footprints allowed)
		)
		(placement
			(enabled no)
			(sheetname "")
		)
		(fill yes
			(thermal_gap 0.5)
			(thermal_bridge_width 0.5)
			(island_removal_mode 0)
		)
		(polygon
			(pts
				(arc
					(start 191.490346 -210.935316)
					(mid 190.829946 -210.935316)
					(end 191.490346 -210.935316)
				)
			)
		)
	)
	(zone
		(layers "In1.Cu" "In2.Cu")
		(hatch none 0.5)
		(connect_pads
			(clearance 0)
		)
		(min_thickness 0.25)
		(keepout
			(tracks not_allowed)
			(vias allowed)
			(pads allowed)
			(copperpour not_allowed)
			(footprints allowed)
		)
		(placement
			(enabled no)
			(sheetname "")
		)
		(fill yes
			(thermal_gap 0.5)
			(thermal_bridge_width 0.5)
			(island_removal_mode 0)
		)
		(polygon
			(pts
				(arc
					(start 22.03831 -244.08511)
					(mid 21.37791 -244.08511)
					(end 22.03831 -244.08511)
				)
			)
		)
	)
	(zone
		(layers "In1.Cu" "In2.Cu")
		(hatch none 0.5)
		(connect_pads
			(clearance 0)
		)
		(min_thickness 0.25)
		(keepout
			(tracks not_allowed)
			(vias allowed)
			(pads allowed)
			(copperpour not_allowed)
			(footprints allowed)
		)
		(placement
			(enabled no)
			(sheetname "")
		)
		(fill yes
			(thermal_gap 0.5)
			(thermal_bridge_width 0.5)
			(island_removal_mode 0)
		)
		(polygon
			(pts
				(arc
					(start 300.15434 -292.535102)
					(mid 299.49394 -292.535102)
					(end 300.15434 -292.535102)
				)
			)
		)
	)
	(zone
		(layers "In1.Cu" "In2.Cu")
		(hatch none 0.5)
		(connect_pads
			(clearance 0)
		)
		(min_thickness 0.25)
		(keepout
			(tracks not_allowed)
			(vias allowed)
			(pads allowed)
			(copperpour not_allowed)
			(footprints allowed)
		)
		(placement
			(enabled no)
			(sheetname "")
		)
		(fill yes
			(thermal_gap 0.5)
			(thermal_bridge_width 0.5)
			(island_removal_mode 0)
		)
		(polygon
			(pts
				(arc
					(start 52.214272 -247.485408)
					(mid 51.553872 -247.485408)
					(end 52.214272 -247.485408)
				)
			)
		)
	)
	(zone
		(layers "In1.Cu" "In2.Cu")
		(hatch none 0.5)
		(connect_pads
			(clearance 0)
		)
		(min_thickness 0.25)
		(keepout
			(tracks not_allowed)
			(vias allowed)
			(pads allowed)
			(copperpour not_allowed)
			(footprints allowed)
		)
		(placement
			(enabled no)
			(sheetname "")
		)
		(fill yes
			(thermal_gap 0.5)
			(thermal_bridge_width 0.5)
			(island_removal_mode 0)
		)
		(polygon
			(pts
				(arc
					(start 296.054272 -299.33519)
					(mid 295.393872 -299.33519)
					(end 296.054272 -299.33519)
				)
			)
		)
	)
	(zone
		(layers "In1.Cu" "In2.Cu")
		(hatch none 0.5)
		(connect_pads
			(clearance 0)
		)
		(min_thickness 0.25)
		(keepout
			(tracks not_allowed)
			(vias allowed)
			(pads allowed)
			(copperpour not_allowed)
			(footprints allowed)
		)
		(placement
			(enabled no)
			(sheetname "")
		)
		(fill yes
			(thermal_gap 0.5)
			(thermal_bridge_width 0.5)
			(island_removal_mode 0)
		)
		(polygon
			(pts
				(arc
					(start 48.114204 -278.935434)
					(mid 47.453804 -278.935434)
					(end 48.114204 -278.935434)
				)
			)
		)
	)
	(zone
		(layers "In1.Cu" "In2.Cu")
		(hatch none 0.5)
		(connect_pads
			(clearance 0)
		)
		(min_thickness 0.25)
		(keepout
			(tracks not_allowed)
			(vias allowed)
			(pads allowed)
			(copperpour not_allowed)
			(footprints allowed)
		)
		(placement
			(enabled no)
			(sheetname "")
		)
		(fill yes
			(thermal_gap 0.5)
			(thermal_bridge_width 0.5)
			(island_removal_mode 0)
		)
		(polygon
			(pts
				(arc
					(start 285.066232 -250.884944)
					(mid 284.405832 -250.884944)
					(end 285.066232 -250.884944)
				)
			)
		)
	)
	(zone
		(layers "In1.Cu" "In2.Cu")
		(hatch none 0.5)
		(connect_pads
			(clearance 0)
		)
		(min_thickness 0.25)
		(keepout
			(tracks not_allowed)
			(vias allowed)
			(pads allowed)
			(copperpour not_allowed)
			(footprints allowed)
		)
		(placement
			(enabled no)
			(sheetname "")
		)
		(fill yes
			(thermal_gap 0.5)
			(thermal_bridge_width 0.5)
			(island_removal_mode 0)
		)
		(polygon
			(pts
				(arc
					(start 29.582364 -276.385274)
					(mid 28.921964 -276.385274)
					(end 29.582364 -276.385274)
				)
			)
		)
	)
	(zone
		(layers "In1.Cu" "In2.Cu")
		(hatch none 0.5)
		(connect_pads
			(clearance 0)
		)
		(min_thickness 0.25)
		(keepout
			(tracks not_allowed)
			(vias allowed)
			(pads allowed)
			(copperpour not_allowed)
			(footprints allowed)
		)
		(placement
			(enabled no)
			(sheetname "")
		)
		(fill yes
			(thermal_gap 0.5)
			(thermal_bridge_width 0.5)
			(island_removal_mode 0)
		)
		(polygon
			(pts
				(arc
					(start 454.518268 -254.284988)
					(mid 453.857868 -254.284988)
					(end 454.518268 -254.284988)
				)
			)
		)
	)
	(zone
		(layers "In1.Cu" "In2.Cu")
		(hatch none 0.5)
		(connect_pads
			(clearance 0)
		)
		(min_thickness 0.25)
		(keepout
			(tracks not_allowed)
			(vias allowed)
			(pads allowed)
			(copperpour not_allowed)
			(footprints allowed)
		)
		(placement
			(enabled no)
			(sheetname "")
		)
		(fill yes
			(thermal_gap 0.5)
			(thermal_bridge_width 0.5)
			(island_removal_mode 0)
		)
		(polygon
			(pts
				(arc
					(start 179.846224 -274.685252)
					(mid 179.185824 -274.685252)
					(end 179.846224 -274.685252)
				)
			)
		)
	)
	(zone
		(layers "In1.Cu" "In2.Cu")
		(hatch none 0.5)
		(connect_pads
			(clearance 0)
		)
		(min_thickness 0.25)
		(keepout
			(tracks not_allowed)
			(vias allowed)
			(pads allowed)
			(copperpour not_allowed)
			(footprints allowed)
		)
		(placement
			(enabled no)
			(sheetname "")
		)
		(fill yes
			(thermal_gap 0.5)
			(thermal_bridge_width 0.5)
			(island_removal_mode 0)
		)
		(polygon
			(pts
				(arc
					(start 40.57015 -246.63527)
					(mid 39.90975 -246.63527)
					(end 40.57015 -246.63527)
				)
			)
		)
	)
	(zone
		(layers "In1.Cu" "In2.Cu")
		(hatch none 0.5)
		(connect_pads
			(clearance 0)
		)
		(min_thickness 0.25)
		(keepout
			(tracks not_allowed)
			(vias allowed)
			(pads allowed)
			(copperpour not_allowed)
			(footprints allowed)
		)
		(placement
			(enabled no)
			(sheetname "")
		)
		(fill yes
			(thermal_gap 0.5)
			(thermal_bridge_width 0.5)
			(island_removal_mode 0)
		)
		(polygon
			(pts
				(arc
					(start 300.15434 -203.28509)
					(mid 299.49394 -203.28509)
					(end 300.15434 -203.28509)
				)
			)
		)
	)
	(zone
		(layers "In1.Cu" "In2.Cu")
		(hatch none 0.5)
		(connect_pads
			(clearance 0)
		)
		(min_thickness 0.25)
		(keepout
			(tracks not_allowed)
			(vias allowed)
			(pads allowed)
			(copperpour not_allowed)
			(footprints allowed)
		)
		(placement
			(enabled no)
			(sheetname "")
		)
		(fill yes
			(thermal_gap 0.5)
			(thermal_bridge_width 0.5)
			(island_removal_mode 0)
		)
		(polygon
			(pts
				(arc
					(start 442.8744 -207.535018)
					(mid 442.214 -207.535018)
					(end 442.8744 -207.535018)
				)
			)
		)
	)
	(zone
		(layers "In1.Cu" "In2.Cu")
		(hatch none 0.5)
		(connect_pads
			(clearance 0)
		)
		(min_thickness 0.25)
		(keepout
			(tracks not_allowed)
			(vias allowed)
			(pads allowed)
			(copperpour not_allowed)
			(footprints allowed)
		)
		(placement
			(enabled no)
			(sheetname "")
		)
		(fill yes
			(thermal_gap 0.5)
			(thermal_bridge_width 0.5)
			(island_removal_mode 0)
		)
		(polygon
			(pts
				(arc
					(start 292.610286 -262.785098)
					(mid 291.949886 -262.785098)
					(end 292.610286 -262.785098)
				)
			)
		)
	)
	(zone
		(layers "In1.Cu" "In2.Cu")
		(hatch none 0.5)
		(connect_pads
			(clearance 0)
		)
		(min_thickness 0.25)
		(keepout
			(tracks not_allowed)
			(vias allowed)
			(pads allowed)
			(copperpour not_allowed)
			(footprints allowed)
		)
		(placement
			(enabled no)
			(sheetname "")
		)
		(fill yes
			(thermal_gap 0.5)
			(thermal_bridge_width 0.5)
			(island_removal_mode 0)
		)
		(polygon
			(pts
				(arc
					(start 187.390278 -207.535272)
					(mid 186.729878 -207.535272)
					(end 187.390278 -207.535272)
				)
			)
		)
	)
	(zone
		(layers "In1.Cu" "In2.Cu")
		(hatch none 0.5)
		(connect_pads
			(clearance 0)
		)
		(min_thickness 0.25)
		(keepout
			(tracks not_allowed)
			(vias allowed)
			(pads allowed)
			(copperpour not_allowed)
			(footprints allowed)
		)
		(placement
			(enabled no)
			(sheetname "")
		)
		(fill yes
			(thermal_gap 0.5)
			(thermal_bridge_width 0.5)
			(island_removal_mode 0)
		)
		(polygon
			(pts
				(arc
					(start 89.925652 -373.442484)
					(mid 89.945576 -373.45172)
					(end 89.967308 -373.45493)
				)
				(arc
					(start 90.161872 -373.45493)
					(mid 90.215754 -373.432612)
					(end 90.238072 -373.37873)
				)
				(arc
					(start 90.238072 -372.69293)
					(mid 90.215754 -372.639048)
					(end 90.161872 -372.61673)
				)
				(arc
					(start 89.967308 -372.61673)
					(mid 89.945564 -372.619898)
					(end 89.925652 -372.629176)
				)
				(arc
					(start 89.629488 -372.821962)
					(mid 89.587804 -372.834184)
					(end 89.546176 -372.821708)
				)
				(arc
					(start 89.252552 -372.629176)
					(mid 89.232628 -372.61994)
					(end 89.210896 -372.61673)
				)
				(arc
					(start 89.016332 -372.61673)
					(mid 88.96245 -372.639048)
					(end 88.940132 -372.69293)
				)
				(arc
					(start 88.940132 -373.37873)
					(mid 88.96245 -373.432612)
					(end 89.016332 -373.45493)
				)
				(arc
					(start 89.212166 -373.45493)
					(mid 89.23391 -373.451762)
					(end 89.253822 -373.442484)
				)
				(arc
					(start 89.547446 -373.249952)
					(mid 89.589102 -373.23755)
					(end 89.630758 -373.249952)
				)
			)
		)
	)
	(zone
		(layers "In1.Cu" "In2.Cu")
		(hatch none 0.5)
		(connect_pads
			(clearance 0)
		)
		(min_thickness 0.25)
		(keepout
			(tracks not_allowed)
			(vias allowed)
			(pads allowed)
			(copperpour not_allowed)
			(footprints allowed)
		)
		(placement
			(enabled no)
			(sheetname "")
		)
		(fill yes
			(thermal_gap 0.5)
			(thermal_bridge_width 0.5)
			(island_removal_mode 0)
		)
		(polygon
			(pts
				(arc
					(start 33.026096 -222.835216)
					(mid 32.365696 -222.835216)
					(end 33.026096 -222.835216)
				)
			)
		)
	)
	(zone
		(layers "In1.Cu" "In2.Cu")
		(hatch none 0.5)
		(connect_pads
			(clearance 0)
		)
		(min_thickness 0.25)
		(keepout
			(tracks not_allowed)
			(vias allowed)
			(pads allowed)
			(copperpour not_allowed)
			(footprints allowed)
		)
		(placement
			(enabled no)
			(sheetname "")
		)
		(fill yes
			(thermal_gap 0.5)
			(thermal_bridge_width 0.5)
			(island_removal_mode 0)
		)
		(polygon
			(pts
				(arc
					(start 292.610286 -228.785166)
					(mid 291.949886 -228.785166)
					(end 292.610286 -228.785166)
				)
			)
		)
	)
	(zone
		(layers "In1.Cu" "In2.Cu")
		(hatch none 0.5)
		(connect_pads
			(clearance 0)
		)
		(min_thickness 0.25)
		(keepout
			(tracks not_allowed)
			(vias allowed)
			(pads allowed)
			(copperpour not_allowed)
			(footprints allowed)
		)
		(placement
			(enabled no)
			(sheetname "")
		)
		(fill yes
			(thermal_gap 0.5)
			(thermal_bridge_width 0.5)
			(island_removal_mode 0)
		)
		(polygon
			(pts
				(arc
					(start 442.8744 -265.335004)
					(mid 442.214 -265.335004)
					(end 442.8744 -265.335004)
				)
			)
		)
	)
	(zone
		(layers "In1.Cu" "In2.Cu")
		(hatch none 0.5)
		(connect_pads
			(clearance 0)
		)
		(min_thickness 0.25)
		(keepout
			(tracks not_allowed)
			(vias allowed)
			(pads allowed)
			(copperpour not_allowed)
			(footprints allowed)
		)
		(placement
			(enabled no)
			(sheetname "")
		)
		(fill yes
			(thermal_gap 0.5)
			(thermal_bridge_width 0.5)
			(island_removal_mode 0)
		)
		(polygon
			(pts
				(arc
					(start 382.929892 -417.242244)
					(mid 382.95221 -417.296126)
					(end 383.006092 -417.318444)
				)
				(arc
					(start 383.201672 -417.318444)
					(mid 383.223548 -417.315312)
					(end 383.243582 -417.305998)
				)
				(arc
					(start 383.537206 -417.113466)
					(mid 383.578862 -417.101064)
					(end 383.620518 -417.113466)
				)
				(arc
					(start 383.915412 -417.305998)
					(mid 383.935336 -417.315234)
					(end 383.957068 -417.318444)
				)
				(arc
					(start 384.151632 -417.318444)
					(mid 384.205514 -417.296126)
					(end 384.227832 -417.242244)
				)
				(arc
					(start 384.227832 -416.556444)
					(mid 384.205514 -416.502562)
					(end 384.151632 -416.480244)
				)
				(arc
					(start 383.957068 -416.480244)
					(mid 383.935324 -416.483412)
					(end 383.915412 -416.49269)
				)
				(arc
					(start 383.619248 -416.685476)
					(mid 383.577564 -416.697698)
					(end 383.535936 -416.685222)
				)
				(arc
					(start 383.242312 -416.49269)
					(mid 383.222388 -416.483454)
					(end 383.200656 -416.480244)
				)
				(arc
					(start 383.006092 -416.480244)
					(mid 382.95221 -416.502562)
					(end 382.929892 -416.556444)
				)
			)
		)
	)
	(zone
		(layers "In1.Cu" "In2.Cu")
		(hatch none 0.5)
		(connect_pads
			(clearance 0)
		)
		(min_thickness 0.25)
		(keepout
			(tracks not_allowed)
			(vias allowed)
			(pads allowed)
			(copperpour not_allowed)
			(footprints allowed)
		)
		(placement
			(enabled no)
			(sheetname "")
		)
		(fill yes
			(thermal_gap 0.5)
			(thermal_bridge_width 0.5)
			(island_removal_mode 0)
		)
		(polygon
			(pts
				(arc
					(start 187.390278 -251.735336)
					(mid 186.729878 -251.735336)
					(end 187.390278 -251.735336)
				)
			)
		)
	)
	(zone
		(layers "In1.Cu" "In2.Cu")
		(hatch none 0.5)
		(connect_pads
			(clearance 0)
		)
		(min_thickness 0.25)
		(keepout
			(tracks not_allowed)
			(vias allowed)
			(pads allowed)
			(copperpour not_allowed)
			(footprints allowed)
		)
		(placement
			(enabled no)
			(sheetname "")
		)
		(fill yes
			(thermal_gap 0.5)
			(thermal_bridge_width 0.5)
			(island_removal_mode 0)
		)
		(polygon
			(pts
				(arc
					(start 40.57015 -295.085262)
					(mid 39.90975 -295.085262)
					(end 40.57015 -295.085262)
				)
			)
		)
	)
	(zone
		(layers "In1.Cu" "In2.Cu")
		(hatch none 0.5)
		(connect_pads
			(clearance 0)
		)
		(min_thickness 0.25)
		(keepout
			(tracks not_allowed)
			(vias allowed)
			(pads allowed)
			(copperpour not_allowed)
			(footprints allowed)
		)
		(placement
			(enabled no)
			(sheetname "")
		)
		(fill yes
			(thermal_gap 0.5)
			(thermal_bridge_width 0.5)
			(island_removal_mode 0)
		)
		(polygon
			(pts
				(arc
					(start 300.15434 -267.885164)
					(mid 299.49394 -267.885164)
					(end 300.15434 -267.885164)
				)
			)
		)
	)
	(zone
		(layers "In1.Cu" "In2.Cu")
		(hatch none 0.5)
		(connect_pads
			(clearance 0)
		)
		(min_thickness 0.25)
		(keepout
			(tracks not_allowed)
			(vias allowed)
			(pads allowed)
			(copperpour not_allowed)
			(footprints allowed)
		)
		(placement
			(enabled no)
			(sheetname "")
		)
		(fill yes
			(thermal_gap 0.5)
			(thermal_bridge_width 0.5)
			(island_removal_mode 0)
		)
		(polygon
			(pts
				(arc
					(start 420.242238 -238.985044)
					(mid 419.581838 -238.985044)
					(end 420.242238 -238.985044)
				)
			)
		)
	)
	(zone
		(layers "In1.Cu" "In2.Cu")
		(hatch none 0.5)
		(connect_pads
			(clearance 0)
		)
		(min_thickness 0.25)
		(keepout
			(tracks not_allowed)
			(vias allowed)
			(pads allowed)
			(copperpour not_allowed)
			(footprints allowed)
		)
		(placement
			(enabled no)
			(sheetname "")
		)
		(fill yes
			(thermal_gap 0.5)
			(thermal_bridge_width 0.5)
			(island_removal_mode 0)
		)
		(polygon
			(pts
				(arc
					(start 22.03831 -252.58522)
					(mid 21.37791 -252.58522)
					(end 22.03831 -252.58522)
				)
			)
		)
	)
	(zone
		(layers "In1.Cu" "In2.Cu")
		(hatch none 0.5)
		(connect_pads
			(clearance 0)
		)
		(min_thickness 0.25)
		(keepout
			(tracks not_allowed)
			(vias allowed)
			(pads allowed)
			(copperpour not_allowed)
			(footprints allowed)
		)
		(placement
			(enabled no)
			(sheetname "")
		)
		(fill yes
			(thermal_gap 0.5)
			(thermal_bridge_width 0.5)
			(island_removal_mode 0)
		)
		(polygon
			(pts
				(arc
					(start 29.582364 -306.135278)
					(mid 28.921964 -306.135278)
					(end 29.582364 -306.135278)
				)
			)
		)
	)
	(zone
		(layers "In1.Cu" "In2.Cu")
		(hatch none 0.5)
		(connect_pads
			(clearance 0)
		)
		(min_thickness 0.25)
		(keepout
			(tracks not_allowed)
			(vias allowed)
			(pads allowed)
			(copperpour not_allowed)
			(footprints allowed)
		)
		(placement
			(enabled no)
			(sheetname "")
		)
		(fill yes
			(thermal_gap 0.5)
			(thermal_bridge_width 0.5)
			(island_removal_mode 0)
		)
		(polygon
			(pts
				(arc
					(start 435.330346 -301.034958)
					(mid 434.669946 -301.034958)
					(end 435.330346 -301.034958)
				)
			)
		)
	)
	(zone
		(layers "In1.Cu" "In2.Cu")
		(hatch none 0.5)
		(connect_pads
			(clearance 0)
		)
		(min_thickness 0.25)
		(keepout
			(tracks not_allowed)
			(vias allowed)
			(pads allowed)
			(copperpour not_allowed)
			(footprints allowed)
		)
		(placement
			(enabled no)
			(sheetname "")
		)
		(fill yes
			(thermal_gap 0.5)
			(thermal_bridge_width 0.5)
			(island_removal_mode 0)
		)
		(polygon
			(pts
				(arc
					(start 285.066232 -309.535068)
					(mid 284.405832 -309.535068)
					(end 285.066232 -309.535068)
				)
			)
		)
	)
	(zone
		(layers "In1.Cu" "In2.Cu")
		(hatch none 0.5)
		(connect_pads
			(clearance 0)
		)
		(min_thickness 0.25)
		(keepout
			(tracks not_allowed)
			(vias allowed)
			(pads allowed)
			(copperpour not_allowed)
			(footprints allowed)
		)
		(placement
			(enabled no)
			(sheetname "")
		)
		(fill yes
			(thermal_gap 0.5)
			(thermal_bridge_width 0.5)
			(island_removal_mode 0)
		)
		(polygon
			(pts
				(arc
					(start 202.478132 -232.18521)
					(mid 201.817732 -232.18521)
					(end 202.478132 -232.18521)
				)
			)
		)
	)
	(zone
		(layers "In1.Cu" "In2.Cu")
		(hatch none 0.5)
		(connect_pads
			(clearance 0)
		)
		(min_thickness 0.25)
		(keepout
			(tracks not_allowed)
			(vias allowed)
			(pads allowed)
			(copperpour not_allowed)
			(footprints allowed)
		)
		(placement
			(enabled no)
			(sheetname "")
		)
		(fill yes
			(thermal_gap 0.5)
			(thermal_bridge_width 0.5)
			(island_removal_mode 0)
		)
		(polygon
			(pts
				(arc
					(start 33.026096 -297.635422)
					(mid 32.365696 -297.635422)
					(end 33.026096 -297.635422)
				)
			)
		)
	)
	(zone
		(layers "In1.Cu" "In2.Cu")
		(hatch none 0.5)
		(connect_pads
			(clearance 0)
		)
		(min_thickness 0.25)
		(keepout
			(tracks not_allowed)
			(vias allowed)
			(pads allowed)
			(copperpour not_allowed)
			(footprints allowed)
		)
		(placement
			(enabled no)
			(sheetname "")
		)
		(fill yes
			(thermal_gap 0.5)
			(thermal_bridge_width 0.5)
			(island_removal_mode 0)
		)
		(polygon
			(pts
				(arc
					(start 439.430414 -225.385122)
					(mid 438.770014 -225.385122)
					(end 439.430414 -225.385122)
				)
			)
		)
	)
	(zone
		(layers "In1.Cu" "In2.Cu")
		(hatch none 0.5)
		(connect_pads
			(clearance 0)
		)
		(min_thickness 0.25)
		(keepout
			(tracks not_allowed)
			(vias allowed)
			(pads allowed)
			(copperpour not_allowed)
			(footprints allowed)
		)
		(placement
			(enabled no)
			(sheetname "")
		)
		(fill yes
			(thermal_gap 0.5)
			(thermal_bridge_width 0.5)
			(island_removal_mode 0)
		)
		(polygon
			(pts
				(arc
					(start 439.430414 -244.08511)
					(mid 438.770014 -244.08511)
					(end 439.430414 -244.08511)
				)
			)
		)
	)
	(zone
		(layers "In1.Cu" "In2.Cu")
		(hatch none 0.5)
		(connect_pads
			(clearance 0)
		)
		(min_thickness 0.25)
		(keepout
			(tracks not_allowed)
			(vias allowed)
			(pads allowed)
			(copperpour not_allowed)
			(footprints allowed)
		)
		(placement
			(enabled no)
			(sheetname "")
		)
		(fill yes
			(thermal_gap 0.5)
			(thermal_bridge_width 0.5)
			(island_removal_mode 0)
		)
		(polygon
			(pts
				(arc
					(start 296.054272 -241.53495)
					(mid 295.393872 -241.53495)
					(end 296.054272 -241.53495)
				)
			)
		)
	)
	(zone
		(layers "In1.Cu" "In2.Cu")
		(hatch none 0.5)
		(connect_pads
			(clearance 0)
		)
		(min_thickness 0.25)
		(keepout
			(tracks not_allowed)
			(vias allowed)
			(pads allowed)
			(copperpour not_allowed)
			(footprints allowed)
		)
		(placement
			(enabled no)
			(sheetname "")
		)
		(fill yes
			(thermal_gap 0.5)
			(thermal_bridge_width 0.5)
			(island_removal_mode 0)
		)
		(polygon
			(pts
				(arc
					(start 172.30217 -285.735268)
					(mid 171.64177 -285.735268)
					(end 172.30217 -285.735268)
				)
			)
		)
	)
	(zone
		(layers "In1.Cu" "In2.Cu")
		(hatch none 0.5)
		(connect_pads
			(clearance 0)
		)
		(min_thickness 0.25)
		(keepout
			(tracks not_allowed)
			(vias allowed)
			(pads allowed)
			(copperpour not_allowed)
			(footprints allowed)
		)
		(placement
			(enabled no)
			(sheetname "")
		)
		(fill yes
			(thermal_gap 0.5)
			(thermal_bridge_width 0.5)
			(island_removal_mode 0)
		)
		(polygon
			(pts
				(arc
					(start 439.430414 -206.685134)
					(mid 438.770014 -206.685134)
					(end 439.430414 -206.685134)
				)
			)
		)
	)
	(zone
		(layers "In1.Cu" "In2.Cu")
		(hatch none 0.5)
		(connect_pads
			(clearance 0)
		)
		(min_thickness 0.25)
		(keepout
			(tracks not_allowed)
			(vias allowed)
			(pads allowed)
			(copperpour not_allowed)
			(footprints allowed)
		)
		(placement
			(enabled no)
			(sheetname "")
		)
		(fill yes
			(thermal_gap 0.5)
			(thermal_bridge_width 0.5)
			(island_removal_mode 0)
		)
		(polygon
			(pts
				(arc
					(start 435.330346 -306.985162)
					(mid 434.669946 -306.985162)
					(end 435.330346 -306.985162)
				)
			)
		)
	)
	(zone
		(layers "In1.Cu" "In2.Cu")
		(hatch none 0.5)
		(connect_pads
			(clearance 0)
		)
		(min_thickness 0.25)
		(keepout
			(tracks not_allowed)
			(vias allowed)
			(pads allowed)
			(copperpour not_allowed)
			(footprints allowed)
		)
		(placement
			(enabled no)
			(sheetname "")
		)
		(fill yes
			(thermal_gap 0.5)
			(thermal_bridge_width 0.5)
			(island_removal_mode 0)
		)
		(polygon
			(pts
				(arc
					(start 44.670218 -296.785284)
					(mid 44.009818 -296.785284)
					(end 44.670218 -296.785284)
				)
			)
		)
	)
	(zone
		(layers "In1.Cu" "In2.Cu")
		(hatch none 0.5)
		(connect_pads
			(clearance 0)
		)
		(min_thickness 0.25)
		(keepout
			(tracks not_allowed)
			(vias allowed)
			(pads allowed)
			(copperpour not_allowed)
			(footprints allowed)
		)
		(placement
			(enabled no)
			(sheetname "")
		)
		(fill yes
			(thermal_gap 0.5)
			(thermal_bridge_width 0.5)
			(island_removal_mode 0)
		)
		(polygon
			(pts
				(arc
					(start 300.15434 -287.435036)
					(mid 299.49394 -287.435036)
					(end 300.15434 -287.435036)
				)
			)
		)
	)
	(zone
		(layers "In1.Cu" "In2.Cu")
		(hatch none 0.5)
		(connect_pads
			(clearance 0)
		)
		(min_thickness 0.25)
		(keepout
			(tracks not_allowed)
			(vias allowed)
			(pads allowed)
			(copperpour not_allowed)
			(footprints allowed)
		)
		(placement
			(enabled no)
			(sheetname "")
		)
		(fill yes
			(thermal_gap 0.5)
			(thermal_bridge_width 0.5)
			(island_removal_mode 0)
		)
		(polygon
			(pts
				(arc
					(start 17.938242 -220.28531)
					(mid 17.277842 -220.28531)
					(end 17.938242 -220.28531)
				)
			)
		)
	)
	(zone
		(layers "In1.Cu" "In2.Cu")
		(hatch none 0.5)
		(connect_pads
			(clearance 0)
		)
		(min_thickness 0.25)
		(keepout
			(tracks not_allowed)
			(vias allowed)
			(pads allowed)
			(copperpour not_allowed)
			(footprints allowed)
		)
		(placement
			(enabled no)
			(sheetname "")
		)
		(fill yes
			(thermal_gap 0.5)
			(thermal_bridge_width 0.5)
			(island_removal_mode 0)
		)
		(polygon
			(pts
				(arc
					(start 183.946292 -217.735404)
					(mid 183.285892 -217.735404)
					(end 183.946292 -217.735404)
				)
			)
		)
	)
	(zone
		(layers "In1.Cu" "In2.Cu")
		(hatch none 0.5)
		(connect_pads
			(clearance 0)
		)
		(min_thickness 0.25)
		(keepout
			(tracks not_allowed)
			(vias allowed)
			(pads allowed)
			(copperpour not_allowed)
			(footprints allowed)
		)
		(placement
			(enabled no)
			(sheetname "")
		)
		(fill yes
			(thermal_gap 0.5)
			(thermal_bridge_width 0.5)
			(island_removal_mode 0)
		)
		(polygon
			(pts
				(arc
					(start 446.974468 -301.885096)
					(mid 446.314068 -301.885096)
					(end 446.974468 -301.885096)
				)
			)
		)
	)
	(zone
		(layers "In1.Cu" "In2.Cu")
		(hatch none 0.5)
		(connect_pads
			(clearance 0)
		)
		(min_thickness 0.25)
		(keepout
			(tracks not_allowed)
			(vias allowed)
			(pads allowed)
			(copperpour not_allowed)
			(footprints allowed)
		)
		(placement
			(enabled no)
			(sheetname "")
		)
		(fill yes
			(thermal_gap 0.5)
			(thermal_bridge_width 0.5)
			(island_removal_mode 0)
		)
		(polygon
			(pts
				(arc
					(start 52.214272 -289.135312)
					(mid 51.553872 -289.135312)
					(end 52.214272 -289.135312)
				)
			)
		)
	)
	(zone
		(layers "In1.Cu" "In2.Cu")
		(hatch none 0.5)
		(connect_pads
			(clearance 0)
		)
		(min_thickness 0.25)
		(keepout
			(tracks not_allowed)
			(vias allowed)
			(pads allowed)
			(copperpour not_allowed)
			(footprints allowed)
		)
		(placement
			(enabled no)
			(sheetname "")
		)
		(fill yes
			(thermal_gap 0.5)
			(thermal_bridge_width 0.5)
			(island_removal_mode 0)
		)
		(polygon
			(pts
				(arc
					(start 202.478132 -293.38524)
					(mid 201.817732 -293.38524)
					(end 202.478132 -293.38524)
				)
			)
		)
	)
	(zone
		(layers "In1.Cu" "In2.Cu")
		(hatch none 0.5)
		(connect_pads
			(clearance 0)
		)
		(min_thickness 0.25)
		(keepout
			(tracks not_allowed)
			(vias allowed)
			(pads allowed)
			(copperpour not_allowed)
			(footprints allowed)
		)
		(placement
			(enabled no)
			(sheetname "")
		)
		(fill yes
			(thermal_gap 0.5)
			(thermal_bridge_width 0.5)
			(island_removal_mode 0)
		)
		(polygon
			(pts
				(arc
					(start 292.610286 -287.435036)
					(mid 291.949886 -287.435036)
					(end 292.610286 -287.435036)
				)
			)
		)
	)
	(zone
		(layers "In1.Cu" "In2.Cu")
		(hatch none 0.5)
		(connect_pads
			(clearance 0)
		)
		(min_thickness 0.25)
		(keepout
			(tracks not_allowed)
			(vias allowed)
			(pads allowed)
			(copperpour not_allowed)
			(footprints allowed)
		)
		(placement
			(enabled no)
			(sheetname "")
		)
		(fill yes
			(thermal_gap 0.5)
			(thermal_bridge_width 0.5)
			(island_removal_mode 0)
		)
		(polygon
			(pts
				(arc
					(start 179.846224 -285.735268)
					(mid 179.185824 -285.735268)
					(end 179.846224 -285.735268)
				)
			)
		)
	)
	(zone
		(layers "In1.Cu" "In2.Cu")
		(hatch none 0.5)
		(connect_pads
			(clearance 0)
		)
		(min_thickness 0.25)
		(keepout
			(tracks not_allowed)
			(vias allowed)
			(pads allowed)
			(copperpour not_allowed)
			(footprints allowed)
		)
		(placement
			(enabled no)
			(sheetname "")
		)
		(fill yes
			(thermal_gap 0.5)
			(thermal_bridge_width 0.5)
			(island_removal_mode 0)
		)
		(polygon
			(pts
				(arc
					(start 292.610286 -285.735014)
					(mid 291.949886 -285.735014)
					(end 292.610286 -285.735014)
				)
			)
		)
	)
	(zone
		(layers "In1.Cu" "In2.Cu")
		(hatch none 0.5)
		(connect_pads
			(clearance 0)
		)
		(min_thickness 0.25)
		(keepout
			(tracks not_allowed)
			(vias allowed)
			(pads allowed)
			(copperpour not_allowed)
			(footprints allowed)
		)
		(placement
			(enabled no)
			(sheetname "")
		)
		(fill yes
			(thermal_gap 0.5)
			(thermal_bridge_width 0.5)
			(island_removal_mode 0)
		)
		(polygon
			(pts
				(arc
					(start 179.846224 -229.635304)
					(mid 179.185824 -229.635304)
					(end 179.846224 -229.635304)
				)
			)
		)
	)
	(zone
		(layers "In1.Cu" "In2.Cu")
		(hatch none 0.5)
		(connect_pads
			(clearance 0)
		)
		(min_thickness 0.25)
		(keepout
			(tracks not_allowed)
			(vias allowed)
			(pads allowed)
			(copperpour not_allowed)
			(footprints allowed)
		)
		(placement
			(enabled no)
			(sheetname "")
		)
		(fill yes
			(thermal_gap 0.5)
			(thermal_bridge_width 0.5)
			(island_removal_mode 0)
		)
		(polygon
			(pts
				(arc
					(start 199.0344 -264.485374)
					(mid 198.374 -264.485374)
					(end 199.0344 -264.485374)
				)
			)
		)
	)
	(zone
		(layers "In1.Cu" "In2.Cu")
		(hatch none 0.5)
		(connect_pads
			(clearance 0)
		)
		(min_thickness 0.25)
		(keepout
			(tracks not_allowed)
			(vias allowed)
			(pads allowed)
			(copperpour not_allowed)
			(footprints allowed)
		)
		(placement
			(enabled no)
			(sheetname "")
		)
		(fill yes
			(thermal_gap 0.5)
			(thermal_bridge_width 0.5)
			(island_removal_mode 0)
		)
		(polygon
			(pts
				(arc
					(start 292.610286 -216.035128)
					(mid 291.949886 -216.035128)
					(end 292.610286 -216.035128)
				)
			)
		)
	)
	(zone
		(layers "In1.Cu" "In2.Cu")
		(hatch none 0.5)
		(connect_pads
			(clearance 0)
		)
		(min_thickness 0.25)
		(keepout
			(tracks not_allowed)
			(vias allowed)
			(pads allowed)
			(copperpour not_allowed)
			(footprints allowed)
		)
		(placement
			(enabled no)
			(sheetname "")
		)
		(fill yes
			(thermal_gap 0.5)
			(thermal_bridge_width 0.5)
			(island_removal_mode 0)
		)
		(polygon
			(pts
				(arc
					(start 162.130994 -375.906284)
					(mid 162.150918 -375.91552)
					(end 162.17265 -375.91873)
				)
				(arc
					(start 162.367214 -375.91873)
					(mid 162.421096 -375.896412)
					(end 162.443414 -375.84253)
				)
				(arc
					(start 162.443414 -375.15673)
					(mid 162.421096 -375.102848)
					(end 162.367214 -375.08053)
				)
				(arc
					(start 162.17265 -375.08053)
					(mid 162.150906 -375.083698)
					(end 162.130994 -375.092976)
				)
				(arc
					(start 161.83483 -375.285762)
					(mid 161.793146 -375.297984)
					(end 161.751518 -375.285508)
				)
				(arc
					(start 161.457894 -375.092976)
					(mid 161.43797 -375.08374)
					(end 161.416238 -375.08053)
				)
				(arc
					(start 161.221674 -375.08053)
					(mid 161.167792 -375.102848)
					(end 161.145474 -375.15673)
				)
				(arc
					(start 161.145474 -375.84253)
					(mid 161.167792 -375.896412)
					(end 161.221674 -375.91873)
				)
				(arc
					(start 161.417508 -375.91873)
					(mid 161.439252 -375.915562)
					(end 161.459164 -375.906284)
				)
				(arc
					(start 161.752788 -375.713752)
					(mid 161.794444 -375.70135)
					(end 161.8361 -375.713752)
				)
			)
		)
	)
	(zone
		(layers "In1.Cu" "In2.Cu")
		(hatch none 0.5)
		(connect_pads
			(clearance 0)
		)
		(min_thickness 0.25)
		(keepout
			(tracks not_allowed)
			(vias allowed)
			(pads allowed)
			(copperpour not_allowed)
			(footprints allowed)
		)
		(placement
			(enabled no)
			(sheetname "")
		)
		(fill yes
			(thermal_gap 0.5)
			(thermal_bridge_width 0.5)
			(island_removal_mode 0)
		)
		(polygon
			(pts
				(arc
					(start 183.946292 -252.58522)
					(mid 183.285892 -252.58522)
					(end 183.946292 -252.58522)
				)
			)
		)
	)
	(zone
		(layers "In1.Cu" "In2.Cu")
		(hatch none 0.5)
		(connect_pads
			(clearance 0)
		)
		(min_thickness 0.25)
		(keepout
			(tracks not_allowed)
			(vias allowed)
			(pads allowed)
			(copperpour not_allowed)
			(footprints allowed)
		)
		(placement
			(enabled no)
			(sheetname "")
		)
		(fill yes
			(thermal_gap 0.5)
			(thermal_bridge_width 0.5)
			(island_removal_mode 0)
		)
		(polygon
			(pts
				(arc
					(start 40.57015 -310.385206)
					(mid 39.90975 -310.385206)
					(end 40.57015 -310.385206)
				)
			)
		)
	)
	(zone
		(layers "In1.Cu" "In2.Cu")
		(hatch none 0.5)
		(connect_pads
			(clearance 0)
		)
		(min_thickness 0.25)
		(keepout
			(tracks not_allowed)
			(vias allowed)
			(pads allowed)
			(copperpour not_allowed)
			(footprints allowed)
		)
		(placement
			(enabled no)
			(sheetname "")
		)
		(fill yes
			(thermal_gap 0.5)
			(thermal_bridge_width 0.5)
			(island_removal_mode 0)
		)
		(polygon
			(pts
				(arc
					(start 296.054272 -291.684964)
					(mid 295.393872 -291.684964)
					(end 296.054272 -291.684964)
				)
			)
		)
	)
	(zone
		(layers "In1.Cu" "In2.Cu")
		(hatch none 0.5)
		(connect_pads
			(clearance 0)
		)
		(min_thickness 0.25)
		(keepout
			(tracks not_allowed)
			(vias allowed)
			(pads allowed)
			(copperpour not_allowed)
			(footprints allowed)
		)
		(placement
			(enabled no)
			(sheetname "")
		)
		(fill yes
			(thermal_gap 0.5)
			(thermal_bridge_width 0.5)
			(island_removal_mode 0)
		)
		(polygon
			(pts
				(arc
					(start 435.330346 -299.33519)
					(mid 434.669946 -299.33519)
					(end 435.330346 -299.33519)
				)
			)
		)
	)
	(zone
		(layers "In1.Cu" "In2.Cu")
		(hatch none 0.5)
		(connect_pads
			(clearance 0)
		)
		(min_thickness 0.25)
		(keepout
			(tracks not_allowed)
			(vias allowed)
			(pads allowed)
			(copperpour not_allowed)
			(footprints allowed)
		)
		(placement
			(enabled no)
			(sheetname "")
		)
		(fill yes
			(thermal_gap 0.5)
			(thermal_bridge_width 0.5)
			(island_removal_mode 0)
		)
		(polygon
			(pts
				(arc
					(start 403.785578 -17.967198)
					(mid 403.807896 -18.02108)
					(end 403.861778 -18.043398)
				)
				(arc
					(start 404.057358 -18.043398)
					(mid 404.079234 -18.040266)
					(end 404.099268 -18.030952)
				)
				(arc
					(start 404.392892 -17.83842)
					(mid 404.434548 -17.826018)
					(end 404.476204 -17.83842)
				)
				(arc
					(start 404.771098 -18.030952)
					(mid 404.791022 -18.040188)
					(end 404.812754 -18.043398)
				)
				(arc
					(start 405.007318 -18.043398)
					(mid 405.0612 -18.02108)
					(end 405.083518 -17.967198)
				)
				(arc
					(start 405.083518 -17.281398)
					(mid 405.0612 -17.227516)
					(end 405.007318 -17.205198)
				)
				(arc
					(start 404.812754 -17.205198)
					(mid 404.79101 -17.208366)
					(end 404.771098 -17.217644)
				)
				(arc
					(start 404.474934 -17.41043)
					(mid 404.43325 -17.422652)
					(end 404.391622 -17.410176)
				)
				(arc
					(start 404.097998 -17.217644)
					(mid 404.078074 -17.208408)
					(end 404.056342 -17.205198)
				)
				(arc
					(start 403.861778 -17.205198)
					(mid 403.807896 -17.227516)
					(end 403.785578 -17.281398)
				)
			)
		)
	)
	(zone
		(layers "In1.Cu" "In2.Cu")
		(hatch none 0.5)
		(connect_pads
			(clearance 0)
		)
		(min_thickness 0.25)
		(keepout
			(tracks not_allowed)
			(vias allowed)
			(pads allowed)
			(copperpour not_allowed)
			(footprints allowed)
		)
		(placement
			(enabled no)
			(sheetname "")
		)
		(fill yes
			(thermal_gap 0.5)
			(thermal_bridge_width 0.5)
			(island_removal_mode 0)
		)
		(polygon
			(pts
				(arc
					(start 288.510218 -302.73498)
					(mid 287.849818 -302.73498)
					(end 288.510218 -302.73498)
				)
			)
		)
	)
	(zone
		(layers "In1.Cu" "In2.Cu")
		(hatch none 0.5)
		(connect_pads
			(clearance 0)
		)
		(min_thickness 0.25)
		(keepout
			(tracks not_allowed)
			(vias allowed)
			(pads allowed)
			(copperpour not_allowed)
			(footprints allowed)
		)
		(placement
			(enabled no)
			(sheetname "")
		)
		(fill yes
			(thermal_gap 0.5)
			(thermal_bridge_width 0.5)
			(island_removal_mode 0)
		)
		(polygon
			(pts
				(arc
					(start 288.510218 -233.884978)
					(mid 287.849818 -233.884978)
					(end 288.510218 -233.884978)
				)
			)
		)
	)
	(zone
		(layers "In1.Cu" "In2.Cu")
		(hatch none 0.5)
		(connect_pads
			(clearance 0)
		)
		(min_thickness 0.25)
		(keepout
			(tracks not_allowed)
			(vias allowed)
			(pads allowed)
			(copperpour not_allowed)
			(footprints allowed)
		)
		(placement
			(enabled no)
			(sheetname "")
		)
		(fill yes
			(thermal_gap 0.5)
			(thermal_bridge_width 0.5)
			(island_removal_mode 0)
		)
		(polygon
			(pts
				(arc
					(start 25.482296 -253.435358)
					(mid 24.821896 -253.435358)
					(end 25.482296 -253.435358)
				)
			)
		)
	)
	(zone
		(layers "In1.Cu" "In2.Cu")
		(hatch none 0.5)
		(connect_pads
			(clearance 0)
		)
		(min_thickness 0.25)
		(keepout
			(tracks not_allowed)
			(vias allowed)
			(pads allowed)
			(copperpour not_allowed)
			(footprints allowed)
		)
		(placement
			(enabled no)
			(sheetname "")
		)
		(fill yes
			(thermal_gap 0.5)
			(thermal_bridge_width 0.5)
			(island_removal_mode 0)
		)
		(polygon
			(pts
				(arc
					(start 300.15434 -262.785098)
					(mid 299.49394 -262.785098)
					(end 300.15434 -262.785098)
				)
			)
		)
	)
	(zone
		(layers "In1.Cu" "In2.Cu")
		(hatch none 0.5)
		(connect_pads
			(clearance 0)
		)
		(min_thickness 0.25)
		(keepout
			(tracks not_allowed)
			(vias allowed)
			(pads allowed)
			(copperpour not_allowed)
			(footprints allowed)
		)
		(placement
			(enabled no)
			(sheetname "")
		)
		(fill yes
			(thermal_gap 0.5)
			(thermal_bridge_width 0.5)
			(island_removal_mode 0)
		)
		(polygon
			(pts
				(arc
					(start 48.114204 -297.635422)
					(mid 47.453804 -297.635422)
					(end 48.114204 -297.635422)
				)
			)
		)
	)
	(zone
		(layers "In1.Cu" "In2.Cu")
		(hatch none 0.5)
		(connect_pads
			(clearance 0)
		)
		(min_thickness 0.25)
		(keepout
			(tracks not_allowed)
			(vias allowed)
			(pads allowed)
			(copperpour not_allowed)
			(footprints allowed)
		)
		(placement
			(enabled no)
			(sheetname "")
		)
		(fill yes
			(thermal_gap 0.5)
			(thermal_bridge_width 0.5)
			(island_removal_mode 0)
		)
		(polygon
			(pts
				(arc
					(start 25.482296 -201.585322)
					(mid 24.821896 -201.585322)
					(end 25.482296 -201.585322)
				)
			)
		)
	)
	(zone
		(layers "In1.Cu" "In2.Cu")
		(hatch none 0.5)
		(connect_pads
			(clearance 0)
		)
		(min_thickness 0.25)
		(keepout
			(tracks not_allowed)
			(vias allowed)
			(pads allowed)
			(copperpour not_allowed)
			(footprints allowed)
		)
		(placement
			(enabled no)
			(sheetname "")
		)
		(fill yes
			(thermal_gap 0.5)
			(thermal_bridge_width 0.5)
			(island_removal_mode 0)
		)
		(polygon
			(pts
				(arc
					(start 179.846224 -313.78525)
					(mid 179.185824 -313.78525)
					(end 179.846224 -313.78525)
				)
			)
		)
	)
	(zone
		(layers "In1.Cu" "In2.Cu")
		(hatch none 0.5)
		(connect_pads
			(clearance 0)
		)
		(min_thickness 0.25)
		(keepout
			(tracks not_allowed)
			(vias allowed)
			(pads allowed)
			(copperpour not_allowed)
			(footprints allowed)
		)
		(placement
			(enabled no)
			(sheetname "")
		)
		(fill yes
			(thermal_gap 0.5)
			(thermal_bridge_width 0.5)
			(island_removal_mode 0)
		)
		(polygon
			(pts
				(arc
					(start 187.390278 -295.9354)
					(mid 186.729878 -295.9354)
					(end 187.390278 -295.9354)
				)
			)
		)
	)
	(zone
		(layers "In1.Cu" "In2.Cu")
		(hatch none 0.5)
		(connect_pads
			(clearance 0)
		)
		(min_thickness 0.25)
		(keepout
			(tracks not_allowed)
			(vias allowed)
			(pads allowed)
			(copperpour not_allowed)
			(footprints allowed)
		)
		(placement
			(enabled no)
			(sheetname "")
		)
		(fill yes
			(thermal_gap 0.5)
			(thermal_bridge_width 0.5)
			(island_removal_mode 0)
		)
		(polygon
			(pts
				(arc
					(start 296.054272 -226.235006)
					(mid 295.393872 -226.235006)
					(end 296.054272 -226.235006)
				)
			)
		)
	)
	(zone
		(layers "In1.Cu" "In2.Cu")
		(hatch none 0.5)
		(connect_pads
			(clearance 0)
		)
		(min_thickness 0.25)
		(keepout
			(tracks not_allowed)
			(vias allowed)
			(pads allowed)
			(copperpour not_allowed)
			(footprints allowed)
		)
		(placement
			(enabled no)
			(sheetname "")
		)
		(fill yes
			(thermal_gap 0.5)
			(thermal_bridge_width 0.5)
			(island_removal_mode 0)
		)
		(polygon
			(pts
				(arc
					(start 420.242238 -265.335004)
					(mid 419.581838 -265.335004)
					(end 420.242238 -265.335004)
				)
			)
		)
	)
	(zone
		(layers "In1.Cu" "In2.Cu")
		(hatch none 0.5)
		(connect_pads
			(clearance 0)
		)
		(min_thickness 0.25)
		(keepout
			(tracks not_allowed)
			(vias allowed)
			(pads allowed)
			(copperpour not_allowed)
			(footprints allowed)
		)
		(placement
			(enabled no)
			(sheetname "")
		)
		(fill yes
			(thermal_gap 0.5)
			(thermal_bridge_width 0.5)
			(island_removal_mode 0)
		)
		(polygon
			(pts
				(arc
					(start 280.966164 -272.984976)
					(mid 280.305764 -272.984976)
					(end 280.966164 -272.984976)
				)
			)
		)
	)
	(zone
		(layers "In1.Cu" "In2.Cu")
		(hatch none 0.5)
		(connect_pads
			(clearance 0)
		)
		(min_thickness 0.25)
		(keepout
			(tracks not_allowed)
			(vias allowed)
			(pads allowed)
			(copperpour not_allowed)
			(footprints allowed)
		)
		(placement
			(enabled no)
			(sheetname "")
		)
		(fill yes
			(thermal_gap 0.5)
			(thermal_bridge_width 0.5)
			(island_removal_mode 0)
		)
		(polygon
			(pts
				(arc
					(start 269.978378 -212.635084)
					(mid 269.317978 -212.635084)
					(end 269.978378 -212.635084)
				)
			)
		)
	)
	(zone
		(layers "In1.Cu" "In2.Cu")
		(hatch none 0.5)
		(connect_pads
			(clearance 0)
		)
		(min_thickness 0.25)
		(keepout
			(tracks not_allowed)
			(vias allowed)
			(pads allowed)
			(copperpour not_allowed)
			(footprints allowed)
		)
		(placement
			(enabled no)
			(sheetname "")
		)
		(fill yes
			(thermal_gap 0.5)
			(thermal_bridge_width 0.5)
			(island_removal_mode 0)
		)
		(polygon
			(pts
				(arc
					(start 296.054272 -211.784946)
					(mid 295.393872 -211.784946)
					(end 296.054272 -211.784946)
				)
			)
		)
	)
	(zone
		(layers "In1.Cu" "In2.Cu")
		(hatch none 0.5)
		(connect_pads
			(clearance 0)
		)
		(min_thickness 0.25)
		(keepout
			(tracks not_allowed)
			(vias allowed)
			(pads allowed)
			(copperpour not_allowed)
			(footprints allowed)
		)
		(placement
			(enabled no)
			(sheetname "")
		)
		(fill yes
			(thermal_gap 0.5)
			(thermal_bridge_width 0.5)
			(island_removal_mode 0)
		)
		(polygon
			(pts
				(arc
					(start 44.670218 -210.085432)
					(mid 44.009818 -210.085432)
					(end 44.670218 -210.085432)
				)
			)
		)
	)
	(zone
		(layers "In1.Cu" "In2.Cu")
		(hatch none 0.5)
		(connect_pads
			(clearance 0)
		)
		(min_thickness 0.25)
		(keepout
			(tracks not_allowed)
			(vias allowed)
			(pads allowed)
			(copperpour not_allowed)
			(footprints allowed)
		)
		(placement
			(enabled no)
			(sheetname "")
		)
		(fill yes
			(thermal_gap 0.5)
			(thermal_bridge_width 0.5)
			(island_removal_mode 0)
		)
		(polygon
			(pts
				(arc
					(start 446.974468 -296.78503)
					(mid 446.314068 -296.78503)
					(end 446.974468 -296.78503)
				)
			)
		)
	)
	(zone
		(layers "In1.Cu" "In2.Cu")
		(hatch none 0.5)
		(connect_pads
			(clearance 0)
		)
		(min_thickness 0.25)
		(keepout
			(tracks not_allowed)
			(vias allowed)
			(pads allowed)
			(copperpour not_allowed)
			(footprints allowed)
		)
		(placement
			(enabled no)
			(sheetname "")
		)
		(fill yes
			(thermal_gap 0.5)
			(thermal_bridge_width 0.5)
			(island_removal_mode 0)
		)
		(polygon
			(pts
				(arc
					(start 87.399114 -408.860244)
					(mid 87.421432 -408.914126)
					(end 87.475314 -408.936444)
				)
				(arc
					(start 87.670894 -408.936444)
					(mid 87.69277 -408.933312)
					(end 87.712804 -408.923998)
				)
				(arc
					(start 88.006428 -408.731466)
					(mid 88.048084 -408.719064)
					(end 88.08974 -408.731466)
				)
				(arc
					(start 88.384634 -408.923998)
					(mid 88.404558 -408.933234)
					(end 88.42629 -408.936444)
				)
				(arc
					(start 88.620854 -408.936444)
					(mid 88.674736 -408.914126)
					(end 88.697054 -408.860244)
				)
				(arc
					(start 88.697054 -408.174444)
					(mid 88.674736 -408.120562)
					(end 88.620854 -408.098244)
				)
				(arc
					(start 88.42629 -408.098244)
					(mid 88.404546 -408.101412)
					(end 88.384634 -408.11069)
				)
				(arc
					(start 88.08847 -408.303476)
					(mid 88.046786 -408.315698)
					(end 88.005158 -408.303222)
				)
				(arc
					(start 87.711534 -408.11069)
					(mid 87.69161 -408.101454)
					(end 87.669878 -408.098244)
				)
				(arc
					(start 87.475314 -408.098244)
					(mid 87.421432 -408.120562)
					(end 87.399114 -408.174444)
				)
			)
		)
	)
	(zone
		(layers "In1.Cu" "In2.Cu")
		(hatch none 0.5)
		(connect_pads
			(clearance 0)
		)
		(min_thickness 0.25)
		(keepout
			(tracks not_allowed)
			(vias allowed)
			(pads allowed)
			(copperpour not_allowed)
			(footprints allowed)
		)
		(placement
			(enabled no)
			(sheetname "")
		)
		(fill yes
			(thermal_gap 0.5)
			(thermal_bridge_width 0.5)
			(island_removal_mode 0)
		)
		(polygon
			(pts
				(arc
					(start 446.974468 -252.584966)
					(mid 446.314068 -252.584966)
					(end 446.974468 -252.584966)
				)
			)
		)
	)
	(zone
		(layers "In1.Cu" "In2.Cu")
		(hatch none 0.5)
		(connect_pads
			(clearance 0)
		)
		(min_thickness 0.25)
		(keepout
			(tracks not_allowed)
			(vias allowed)
			(pads allowed)
			(copperpour not_allowed)
			(footprints allowed)
		)
		(placement
			(enabled no)
			(sheetname "")
		)
		(fill yes
			(thermal_gap 0.5)
			(thermal_bridge_width 0.5)
			(island_removal_mode 0)
		)
		(polygon
			(pts
				(arc
					(start 202.478132 -305.285394)
					(mid 201.817732 -305.285394)
					(end 202.478132 -305.285394)
				)
			)
		)
	)
	(zone
		(layers "In1.Cu" "In2.Cu")
		(hatch none 0.5)
		(connect_pads
			(clearance 0)
		)
		(min_thickness 0.25)
		(keepout
			(tracks not_allowed)
			(vias allowed)
			(pads allowed)
			(copperpour not_allowed)
			(footprints allowed)
		)
		(placement
			(enabled no)
			(sheetname "")
		)
		(fill yes
			(thermal_gap 0.5)
			(thermal_bridge_width 0.5)
			(island_removal_mode 0)
		)
		(polygon
			(pts
				(arc
					(start 427.786292 -282.33497)
					(mid 427.125892 -282.33497)
					(end 427.786292 -282.33497)
				)
			)
		)
	)
	(zone
		(layers "In1.Cu" "In2.Cu")
		(hatch none 0.5)
		(connect_pads
			(clearance 0)
		)
		(min_thickness 0.25)
		(keepout
			(tracks not_allowed)
			(vias allowed)
			(pads allowed)
			(copperpour not_allowed)
			(footprints allowed)
		)
		(placement
			(enabled no)
			(sheetname "")
		)
		(fill yes
			(thermal_gap 0.5)
			(thermal_bridge_width 0.5)
			(island_removal_mode 0)
		)
		(polygon
			(pts
				(arc
					(start 439.430414 -306.135024)
					(mid 438.770014 -306.135024)
					(end 439.430414 -306.135024)
				)
			)
		)
	)
	(zone
		(layers "In1.Cu" "In2.Cu")
		(hatch none 0.5)
		(connect_pads
			(clearance 0)
		)
		(min_thickness 0.25)
		(keepout
			(tracks not_allowed)
			(vias allowed)
			(pads allowed)
			(copperpour not_allowed)
			(footprints allowed)
		)
		(placement
			(enabled no)
			(sheetname "")
		)
		(fill yes
			(thermal_gap 0.5)
			(thermal_bridge_width 0.5)
			(island_removal_mode 0)
		)
		(polygon
			(pts
				(arc
					(start 176.402238 -284.885384)
					(mid 175.741838 -284.885384)
					(end 176.402238 -284.885384)
				)
			)
		)
	)
	(zone
		(layers "In1.Cu" "In2.Cu")
		(hatch none 0.5)
		(connect_pads
			(clearance 0)
		)
		(min_thickness 0.25)
		(keepout
			(tracks not_allowed)
			(vias allowed)
			(pads allowed)
			(copperpour not_allowed)
			(footprints allowed)
		)
		(placement
			(enabled no)
			(sheetname "")
		)
		(fill yes
			(thermal_gap 0.5)
			(thermal_bridge_width 0.5)
			(island_removal_mode 0)
		)
		(polygon
			(pts
				(arc
					(start 199.0344 -289.135312)
					(mid 198.374 -289.135312)
					(end 199.0344 -289.135312)
				)
			)
		)
	)
	(zone
		(layers "In1.Cu" "In2.Cu")
		(hatch none 0.5)
		(connect_pads
			(clearance 0)
		)
		(min_thickness 0.25)
		(keepout
			(tracks not_allowed)
			(vias allowed)
			(pads allowed)
			(copperpour not_allowed)
			(footprints allowed)
		)
		(placement
			(enabled no)
			(sheetname "")
		)
		(fill yes
			(thermal_gap 0.5)
			(thermal_bridge_width 0.5)
			(island_removal_mode 0)
		)
		(polygon
			(pts
				(arc
					(start 454.518268 -197.33514)
					(mid 453.857868 -197.33514)
					(end 454.518268 -197.33514)
				)
			)
		)
	)
	(zone
		(layers "In1.Cu" "In2.Cu")
		(hatch none 0.5)
		(connect_pads
			(clearance 0)
		)
		(min_thickness 0.25)
		(keepout
			(tracks not_allowed)
			(vias allowed)
			(pads allowed)
			(copperpour not_allowed)
			(footprints allowed)
		)
		(placement
			(enabled no)
			(sheetname "")
		)
		(fill yes
			(thermal_gap 0.5)
			(thermal_bridge_width 0.5)
			(island_removal_mode 0)
		)
		(polygon
			(pts
				(arc
					(start 435.330346 -216.885012)
					(mid 434.669946 -216.885012)
					(end 435.330346 -216.885012)
				)
			)
		)
	)
	(zone
		(layers "In1.Cu" "In2.Cu")
		(hatch none 0.5)
		(connect_pads
			(clearance 0)
		)
		(min_thickness 0.25)
		(keepout
			(tracks not_allowed)
			(vias allowed)
			(pads allowed)
			(copperpour not_allowed)
			(footprints allowed)
		)
		(placement
			(enabled no)
			(sheetname "")
		)
		(fill yes
			(thermal_gap 0.5)
			(thermal_bridge_width 0.5)
			(island_removal_mode 0)
		)
		(polygon
			(pts
				(arc
					(start 288.510218 -201.585068)
					(mid 287.849818 -201.585068)
					(end 288.510218 -201.585068)
				)
			)
		)
	)
	(zone
		(layers "In1.Cu" "In2.Cu")
		(hatch none 0.5)
		(connect_pads
			(clearance 0)
		)
		(min_thickness 0.25)
		(keepout
			(tracks not_allowed)
			(vias allowed)
			(pads allowed)
			(copperpour not_allowed)
			(footprints allowed)
		)
		(placement
			(enabled no)
			(sheetname "")
		)
		(fill yes
			(thermal_gap 0.5)
			(thermal_bridge_width 0.5)
			(island_removal_mode 0)
		)
		(polygon
			(pts
				(arc
					(start 168.938194 -370.978684)
					(mid 168.958118 -370.98792)
					(end 168.97985 -370.99113)
				)
				(arc
					(start 169.174414 -370.99113)
					(mid 169.228296 -370.968812)
					(end 169.250614 -370.91493)
				)
				(arc
					(start 169.250614 -370.22913)
					(mid 169.228296 -370.175248)
					(end 169.174414 -370.15293)
				)
				(arc
					(start 168.97985 -370.15293)
					(mid 168.958106 -370.156098)
					(end 168.938194 -370.165376)
				)
				(arc
					(start 168.64203 -370.358162)
					(mid 168.600346 -370.370384)
					(end 168.558718 -370.357908)
				)
				(arc
					(start 168.265094 -370.165376)
					(mid 168.24517 -370.15614)
					(end 168.223438 -370.15293)
				)
				(arc
					(start 168.028874 -370.15293)
					(mid 167.974992 -370.175248)
					(end 167.952674 -370.22913)
				)
				(arc
					(start 167.952674 -370.91493)
					(mid 167.974992 -370.968812)
					(end 168.028874 -370.99113)
				)
				(arc
					(start 168.224708 -370.99113)
					(mid 168.246452 -370.987962)
					(end 168.266364 -370.978684)
				)
				(arc
					(start 168.559988 -370.786152)
					(mid 168.601644 -370.77375)
					(end 168.6433 -370.786152)
				)
			)
		)
	)
	(zone
		(layers "In1.Cu" "In2.Cu")
		(hatch none 0.5)
		(connect_pads
			(clearance 0)
		)
		(min_thickness 0.25)
		(keepout
			(tracks not_allowed)
			(vias allowed)
			(pads allowed)
			(copperpour not_allowed)
			(footprints allowed)
		)
		(placement
			(enabled no)
			(sheetname "")
		)
		(fill yes
			(thermal_gap 0.5)
			(thermal_bridge_width 0.5)
			(island_removal_mode 0)
		)
		(polygon
			(pts
				(arc
					(start 25.482296 -229.635304)
					(mid 24.821896 -229.635304)
					(end 25.482296 -229.635304)
				)
			)
		)
	)
	(zone
		(layers "In1.Cu" "In2.Cu")
		(hatch none 0.5)
		(connect_pads
			(clearance 0)
		)
		(min_thickness 0.25)
		(keepout
			(tracks not_allowed)
			(vias allowed)
			(pads allowed)
			(copperpour not_allowed)
			(footprints allowed)
		)
		(placement
			(enabled no)
			(sheetname "")
		)
		(fill yes
			(thermal_gap 0.5)
			(thermal_bridge_width 0.5)
			(island_removal_mode 0)
		)
		(polygon
			(pts
				(arc
					(start 232.558844 -53.672994)
					(mid 232.612726 -53.695312)
					(end 232.635044 -53.749194)
				)
				(arc
					(start 232.635044 -54.780942)
					(mid 232.612726 -54.834824)
					(end 232.558844 -54.857142)
				)
				(arc
					(start 231.441244 -54.857142)
					(mid 231.387362 -54.834824)
					(end 231.365044 -54.780942)
				)
				(arc
					(start 231.365044 -53.749194)
					(mid 231.387362 -53.695312)
					(end 231.441244 -53.672994)
				)
			)
		)
	)
	(zone
		(layers "In1.Cu" "In2.Cu")
		(hatch none 0.5)
		(connect_pads
			(clearance 0)
		)
		(min_thickness 0.25)
		(keepout
			(tracks not_allowed)
			(vias allowed)
			(pads allowed)
			(copperpour not_allowed)
			(footprints allowed)
		)
		(placement
			(enabled no)
			(sheetname "")
		)
		(fill yes
			(thermal_gap 0.5)
			(thermal_bridge_width 0.5)
			(island_removal_mode 0)
		)
		(polygon
			(pts
				(arc
					(start 25.482296 -306.985416)
					(mid 24.821896 -306.985416)
					(end 25.482296 -306.985416)
				)
			)
		)
	)
	(zone
		(layers "In1.Cu" "In2.Cu")
		(hatch none 0.5)
		(connect_pads
			(clearance 0)
		)
		(min_thickness 0.25)
		(keepout
			(tracks not_allowed)
			(vias allowed)
			(pads allowed)
			(copperpour not_allowed)
			(footprints allowed)
		)
		(placement
			(enabled no)
			(sheetname "")
		)
		(fill yes
			(thermal_gap 0.5)
			(thermal_bridge_width 0.5)
			(island_removal_mode 0)
		)
		(polygon
			(pts
				(arc
					(start 238.74603 -58.20664)
					(mid 238.736794 -58.226564)
					(end 238.733584 -58.248296)
				)
				(arc
					(start 238.733584 -58.44286)
					(mid 238.755902 -58.496742)
					(end 238.809784 -58.51906)
				)
				(arc
					(start 239.495584 -58.51906)
					(mid 239.549466 -58.496742)
					(end 239.571784 -58.44286)
				)
				(arc
					(start 239.571784 -58.248296)
					(mid 239.568616 -58.226552)
					(end 239.559338 -58.20664)
				)
				(arc
					(start 239.366552 -57.910476)
					(mid 239.35433 -57.868792)
					(end 239.366806 -57.827164)
				)
				(arc
					(start 239.559338 -57.53354)
					(mid 239.568574 -57.513616)
					(end 239.571784 -57.491884)
				)
				(arc
					(start 239.571784 -57.29732)
					(mid 239.549466 -57.243438)
					(end 239.495584 -57.22112)
				)
				(arc
					(start 238.809784 -57.22112)
					(mid 238.755902 -57.243438)
					(end 238.733584 -57.29732)
				)
				(arc
					(start 238.733584 -57.493154)
					(mid 238.736752 -57.514898)
					(end 238.74603 -57.53481)
				)
				(arc
					(start 238.938562 -57.828434)
					(mid 238.950964 -57.87009)
					(end 238.938562 -57.911746)
				)
			)
		)
	)
	(zone
		(layers "In1.Cu" "In2.Cu")
		(hatch none 0.5)
		(connect_pads
			(clearance 0)
		)
		(min_thickness 0.25)
		(keepout
			(tracks not_allowed)
			(vias allowed)
			(pads allowed)
			(copperpour not_allowed)
			(footprints allowed)
		)
		(placement
			(enabled no)
			(sheetname "")
		)
		(fill yes
			(thermal_gap 0.5)
			(thermal_bridge_width 0.5)
			(island_removal_mode 0)
		)
		(polygon
			(pts
				(arc
					(start 420.242238 -289.985196)
					(mid 419.581838 -289.985196)
					(end 420.242238 -289.985196)
				)
			)
		)
	)
	(zone
		(layers "In1.Cu" "In2.Cu")
		(hatch none 0.5)
		(connect_pads
			(clearance 0)
		)
		(min_thickness 0.25)
		(keepout
			(tracks not_allowed)
			(vias allowed)
			(pads allowed)
			(copperpour not_allowed)
			(footprints allowed)
		)
		(placement
			(enabled no)
			(sheetname "")
		)
		(fill yes
			(thermal_gap 0.5)
			(thermal_bridge_width 0.5)
			(island_removal_mode 0)
		)
		(polygon
			(pts
				(arc
					(start 424.342306 -247.485154)
					(mid 423.681906 -247.485154)
					(end 424.342306 -247.485154)
				)
			)
		)
	)
	(zone
		(layers "In1.Cu" "In2.Cu")
		(hatch none 0.5)
		(connect_pads
			(clearance 0)
		)
		(min_thickness 0.25)
		(keepout
			(tracks not_allowed)
			(vias allowed)
			(pads allowed)
			(copperpour not_allowed)
			(footprints allowed)
		)
		(placement
			(enabled no)
			(sheetname "")
		)
		(fill yes
			(thermal_gap 0.5)
			(thermal_bridge_width 0.5)
			(island_removal_mode 0)
		)
		(polygon
			(pts
				(arc
					(start 446.974468 -204.985112)
					(mid 446.314068 -204.985112)
					(end 446.974468 -204.985112)
				)
			)
		)
	)
	(zone
		(layers "In1.Cu" "In2.Cu")
		(hatch none 0.5)
		(connect_pads
			(clearance 0)
		)
		(min_thickness 0.25)
		(keepout
			(tracks not_allowed)
			(vias allowed)
			(pads allowed)
			(copperpour not_allowed)
			(footprints allowed)
		)
		(placement
			(enabled no)
			(sheetname "")
		)
		(fill yes
			(thermal_gap 0.5)
			(thermal_bridge_width 0.5)
			(island_removal_mode 0)
		)
		(polygon
			(pts
				(arc
					(start 194.934332 -302.735234)
					(mid 194.273932 -302.735234)
					(end 194.934332 -302.735234)
				)
			)
		)
	)
	(zone
		(layers "In1.Cu" "In2.Cu")
		(hatch none 0.5)
		(connect_pads
			(clearance 0)
		)
		(min_thickness 0.25)
		(keepout
			(tracks not_allowed)
			(vias allowed)
			(pads allowed)
			(copperpour not_allowed)
			(footprints allowed)
		)
		(placement
			(enabled no)
			(sheetname "")
		)
		(fill yes
			(thermal_gap 0.5)
			(thermal_bridge_width 0.5)
			(island_removal_mode 0)
		)
		(polygon
			(pts
				(arc
					(start 199.0344 -303.585372)
					(mid 198.374 -303.585372)
					(end 199.0344 -303.585372)
				)
			)
		)
	)
	(zone
		(layers "In1.Cu" "In2.Cu")
		(hatch none 0.5)
		(connect_pads
			(clearance 0)
		)
		(min_thickness 0.25)
		(keepout
			(tracks not_allowed)
			(vias allowed)
			(pads allowed)
			(copperpour not_allowed)
			(footprints allowed)
		)
		(placement
			(enabled no)
			(sheetname "")
		)
		(fill yes
			(thermal_gap 0.5)
			(thermal_bridge_width 0.5)
			(island_removal_mode 0)
		)
		(polygon
			(pts
				(arc
					(start 292.610286 -254.284988)
					(mid 291.949886 -254.284988)
					(end 292.610286 -254.284988)
				)
			)
		)
	)
	(zone
		(layers "In1.Cu" "In2.Cu")
		(hatch none 0.5)
		(connect_pads
			(clearance 0)
		)
		(min_thickness 0.25)
		(keepout
			(tracks not_allowed)
			(vias allowed)
			(pads allowed)
			(copperpour not_allowed)
			(footprints allowed)
		)
		(placement
			(enabled no)
			(sheetname "")
		)
		(fill yes
			(thermal_gap 0.5)
			(thermal_bridge_width 0.5)
			(island_removal_mode 0)
		)
		(polygon
			(pts
				(arc
					(start 191.490346 -223.685354)
					(mid 190.829946 -223.685354)
					(end 191.490346 -223.685354)
				)
			)
		)
	)
	(zone
		(layers "In1.Cu" "In2.Cu")
		(hatch none 0.5)
		(connect_pads
			(clearance 0)
		)
		(min_thickness 0.25)
		(keepout
			(tracks not_allowed)
			(vias allowed)
			(pads allowed)
			(copperpour not_allowed)
			(footprints allowed)
		)
		(placement
			(enabled no)
			(sheetname "")
		)
		(fill yes
			(thermal_gap 0.5)
			(thermal_bridge_width 0.5)
			(island_removal_mode 0)
		)
		(polygon
			(pts
				(arc
					(start 48.114204 -227.935282)
					(mid 47.453804 -227.935282)
					(end 48.114204 -227.935282)
				)
			)
		)
	)
	(zone
		(layers "In1.Cu" "In2.Cu")
		(hatch none 0.5)
		(connect_pads
			(clearance 0)
		)
		(min_thickness 0.25)
		(keepout
			(tracks not_allowed)
			(vias allowed)
			(pads allowed)
			(copperpour not_allowed)
			(footprints allowed)
		)
		(placement
			(enabled no)
			(sheetname "")
		)
		(fill yes
			(thermal_gap 0.5)
			(thermal_bridge_width 0.5)
			(island_removal_mode 0)
		)
		(polygon
			(pts
				(arc
					(start 40.57015 -215.185244)
					(mid 39.90975 -215.185244)
					(end 40.57015 -215.185244)
				)
			)
		)
	)
	(zone
		(layers "In1.Cu" "In2.Cu")
		(hatch none 0.5)
		(connect_pads
			(clearance 0)
		)
		(min_thickness 0.25)
		(keepout
			(tracks not_allowed)
			(vias allowed)
			(pads allowed)
			(copperpour not_allowed)
			(footprints allowed)
		)
		(placement
			(enabled no)
			(sheetname "")
		)
		(fill yes
			(thermal_gap 0.5)
			(thermal_bridge_width 0.5)
			(island_removal_mode 0)
		)
		(polygon
			(pts
				(arc
					(start 454.518268 -200.735184)
					(mid 453.857868 -200.735184)
					(end 454.518268 -200.735184)
				)
			)
		)
	)
	(zone
		(layers "In1.Cu" "In2.Cu")
		(hatch none 0.5)
		(connect_pads
			(clearance 0)
		)
		(min_thickness 0.25)
		(keepout
			(tracks not_allowed)
			(vias allowed)
			(pads allowed)
			(copperpour not_allowed)
			(footprints allowed)
		)
		(placement
			(enabled no)
			(sheetname "")
		)
		(fill yes
			(thermal_gap 0.5)
			(thermal_bridge_width 0.5)
			(island_removal_mode 0)
		)
		(polygon
			(pts
				(arc
					(start 37.126164 -287.43529)
					(mid 36.465764 -287.43529)
					(end 37.126164 -287.43529)
				)
			)
		)
	)
	(zone
		(layers "In1.Cu" "In2.Cu")
		(hatch none 0.5)
		(connect_pads
			(clearance 0)
		)
		(min_thickness 0.25)
		(keepout
			(tracks not_allowed)
			(vias allowed)
			(pads allowed)
			(copperpour not_allowed)
			(footprints allowed)
		)
		(placement
			(enabled no)
			(sheetname "")
		)
		(fill yes
			(thermal_gap 0.5)
			(thermal_bridge_width 0.5)
			(island_removal_mode 0)
		)
		(polygon
			(pts
				(arc
					(start 29.582364 -214.33536)
					(mid 28.921964 -214.33536)
					(end 29.582364 -214.33536)
				)
			)
		)
	)
	(zone
		(layers "In1.Cu" "In2.Cu")
		(hatch none 0.5)
		(connect_pads
			(clearance 0)
		)
		(min_thickness 0.25)
		(keepout
			(tracks not_allowed)
			(vias allowed)
			(pads allowed)
			(copperpour not_allowed)
			(footprints allowed)
		)
		(placement
			(enabled no)
			(sheetname "")
		)
		(fill yes
			(thermal_gap 0.5)
			(thermal_bridge_width 0.5)
			(island_removal_mode 0)
		)
		(polygon
			(pts
				(arc
					(start 52.214272 -231.335326)
					(mid 51.553872 -231.335326)
					(end 52.214272 -231.335326)
				)
			)
		)
	)
	(zone
		(layers "In1.Cu" "In2.Cu")
		(hatch none 0.5)
		(connect_pads
			(clearance 0)
		)
		(min_thickness 0.25)
		(keepout
			(tracks not_allowed)
			(vias allowed)
			(pads allowed)
			(copperpour not_allowed)
			(footprints allowed)
		)
		(placement
			(enabled no)
			(sheetname "")
		)
		(fill yes
			(thermal_gap 0.5)
			(thermal_bridge_width 0.5)
			(island_removal_mode 0)
		)
		(polygon
			(pts
				(arc
					(start 176.402238 -304.435256)
					(mid 175.741838 -304.435256)
					(end 176.402238 -304.435256)
				)
			)
		)
	)
	(zone
		(layers "In1.Cu" "In2.Cu")
		(hatch none 0.5)
		(connect_pads
			(clearance 0)
		)
		(min_thickness 0.25)
		(keepout
			(tracks not_allowed)
			(vias allowed)
			(pads allowed)
			(copperpour not_allowed)
			(footprints allowed)
		)
		(placement
			(enabled no)
			(sheetname "")
		)
		(fill yes
			(thermal_gap 0.5)
			(thermal_bridge_width 0.5)
			(island_removal_mode 0)
		)
		(polygon
			(pts
				(arc
					(start 285.066232 -287.435036)
					(mid 284.405832 -287.435036)
					(end 285.066232 -287.435036)
				)
			)
		)
	)
	(zone
		(layers "In1.Cu" "In2.Cu")
		(hatch none 0.5)
		(connect_pads
			(clearance 0)
		)
		(min_thickness 0.25)
		(keepout
			(tracks not_allowed)
			(vias allowed)
			(pads allowed)
			(copperpour not_allowed)
			(footprints allowed)
		)
		(placement
			(enabled no)
			(sheetname "")
		)
		(fill yes
			(thermal_gap 0.5)
			(thermal_bridge_width 0.5)
			(island_removal_mode 0)
		)
		(polygon
			(pts
				(arc
					(start 424.342306 -298.485052)
					(mid 423.681906 -298.485052)
					(end 424.342306 -298.485052)
				)
			)
		)
	)
	(zone
		(layers "In1.Cu" "In2.Cu")
		(hatch none 0.5)
		(connect_pads
			(clearance 0)
		)
		(min_thickness 0.25)
		(keepout
			(tracks not_allowed)
			(vias allowed)
			(pads allowed)
			(copperpour not_allowed)
			(footprints allowed)
		)
		(placement
			(enabled no)
			(sheetname "")
		)
		(fill yes
			(thermal_gap 0.5)
			(thermal_bridge_width 0.5)
			(island_removal_mode 0)
		)
		(polygon
			(pts
				(arc
					(start 52.214272 -210.935316)
					(mid 51.553872 -210.935316)
					(end 52.214272 -210.935316)
				)
			)
		)
	)
	(zone
		(layers "In1.Cu" "In2.Cu")
		(hatch none 0.5)
		(connect_pads
			(clearance 0)
		)
		(min_thickness 0.25)
		(keepout
			(tracks not_allowed)
			(vias allowed)
			(pads allowed)
			(copperpour not_allowed)
			(footprints allowed)
		)
		(placement
			(enabled no)
			(sheetname "")
		)
		(fill yes
			(thermal_gap 0.5)
			(thermal_bridge_width 0.5)
			(island_removal_mode 0)
		)
		(polygon
			(pts
				(arc
					(start 435.330346 -272.984976)
					(mid 434.669946 -272.984976)
					(end 435.330346 -272.984976)
				)
			)
		)
	)
	(zone
		(layers "In1.Cu" "In2.Cu")
		(hatch none 0.5)
		(connect_pads
			(clearance 0)
		)
		(min_thickness 0.25)
		(keepout
			(tracks not_allowed)
			(vias allowed)
			(pads allowed)
			(copperpour not_allowed)
			(footprints allowed)
		)
		(placement
			(enabled no)
			(sheetname "")
		)
		(fill yes
			(thermal_gap 0.5)
			(thermal_bridge_width 0.5)
			(island_removal_mode 0)
		)
		(polygon
			(pts
				(arc
					(start 194.934332 -306.985416)
					(mid 194.273932 -306.985416)
					(end 194.934332 -306.985416)
				)
			)
		)
	)
	(zone
		(layers "In1.Cu" "In2.Cu")
		(hatch none 0.5)
		(connect_pads
			(clearance 0)
		)
		(min_thickness 0.25)
		(keepout
			(tracks not_allowed)
			(vias allowed)
			(pads allowed)
			(copperpour not_allowed)
			(footprints allowed)
		)
		(placement
			(enabled no)
			(sheetname "")
		)
		(fill yes
			(thermal_gap 0.5)
			(thermal_bridge_width 0.5)
			(island_removal_mode 0)
		)
		(polygon
			(pts
				(arc
					(start 40.57015 -198.185278)
					(mid 39.90975 -198.185278)
					(end 40.57015 -198.185278)
				)
			)
		)
	)
	(zone
		(layers "In1.Cu" "In2.Cu")
		(hatch none 0.5)
		(connect_pads
			(clearance 0)
		)
		(min_thickness 0.25)
		(keepout
			(tracks not_allowed)
			(vias allowed)
			(pads allowed)
			(copperpour not_allowed)
			(footprints allowed)
		)
		(placement
			(enabled no)
			(sheetname "")
		)
		(fill yes
			(thermal_gap 0.5)
			(thermal_bridge_width 0.5)
			(island_removal_mode 0)
		)
		(polygon
			(pts
				(arc
					(start 33.026096 -286.585406)
					(mid 32.365696 -286.585406)
					(end 33.026096 -286.585406)
				)
			)
		)
	)
	(zone
		(layers "In1.Cu" "In2.Cu")
		(hatch none 0.5)
		(connect_pads
			(clearance 0)
		)
		(min_thickness 0.25)
		(keepout
			(tracks not_allowed)
			(vias allowed)
			(pads allowed)
			(copperpour not_allowed)
			(footprints allowed)
		)
		(placement
			(enabled no)
			(sheetname "")
		)
		(fill yes
			(thermal_gap 0.5)
			(thermal_bridge_width 0.5)
			(island_removal_mode 0)
		)
		(polygon
			(pts
				(arc
					(start 172.30217 -253.435358)
					(mid 171.64177 -253.435358)
					(end 172.30217 -253.435358)
				)
			)
		)
	)
	(zone
		(layers "In1.Cu" "In2.Cu")
		(hatch none 0.5)
		(connect_pads
			(clearance 0)
		)
		(min_thickness 0.25)
		(keepout
			(tracks not_allowed)
			(vias allowed)
			(pads allowed)
			(copperpour not_allowed)
			(footprints allowed)
		)
		(placement
			(enabled no)
			(sheetname "")
		)
		(fill yes
			(thermal_gap 0.5)
			(thermal_bridge_width 0.5)
			(island_removal_mode 0)
		)
		(polygon
			(pts
				(arc
					(start 427.786292 -209.23504)
					(mid 427.125892 -209.23504)
					(end 427.786292 -209.23504)
				)
			)
		)
	)
	(zone
		(layers "In1.Cu" "In2.Cu")
		(hatch none 0.5)
		(connect_pads
			(clearance 0)
		)
		(min_thickness 0.25)
		(keepout
			(tracks not_allowed)
			(vias allowed)
			(pads allowed)
			(copperpour not_allowed)
			(footprints allowed)
		)
		(placement
			(enabled no)
			(sheetname "")
		)
		(fill yes
			(thermal_gap 0.5)
			(thermal_bridge_width 0.5)
			(island_removal_mode 0)
		)
		(polygon
			(pts
				(arc
					(start 154.499056 -408.860244)
					(mid 154.521374 -408.914126)
					(end 154.575256 -408.936444)
				)
				(arc
					(start 154.770836 -408.936444)
					(mid 154.792712 -408.933312)
					(end 154.812746 -408.923998)
				)
				(arc
					(start 155.10637 -408.731466)
					(mid 155.148026 -408.719064)
					(end 155.189682 -408.731466)
				)
				(arc
					(start 155.484576 -408.923998)
					(mid 155.5045 -408.933234)
					(end 155.526232 -408.936444)
				)
				(arc
					(start 155.720796 -408.936444)
					(mid 155.774678 -408.914126)
					(end 155.796996 -408.860244)
				)
				(arc
					(start 155.796996 -408.174444)
					(mid 155.774678 -408.120562)
					(end 155.720796 -408.098244)
				)
				(arc
					(start 155.526232 -408.098244)
					(mid 155.504488 -408.101412)
					(end 155.484576 -408.11069)
				)
				(arc
					(start 155.188412 -408.303476)
					(mid 155.146728 -408.315698)
					(end 155.1051 -408.303222)
				)
				(arc
					(start 154.811476 -408.11069)
					(mid 154.791552 -408.101454)
					(end 154.76982 -408.098244)
				)
				(arc
					(start 154.575256 -408.098244)
					(mid 154.521374 -408.120562)
					(end 154.499056 -408.174444)
				)
			)
		)
	)
	(zone
		(layers "In1.Cu" "In2.Cu")
		(hatch none 0.5)
		(connect_pads
			(clearance 0)
		)
		(min_thickness 0.25)
		(keepout
			(tracks not_allowed)
			(vias allowed)
			(pads allowed)
			(copperpour not_allowed)
			(footprints allowed)
		)
		(placement
			(enabled no)
			(sheetname "")
		)
		(fill yes
			(thermal_gap 0.5)
			(thermal_bridge_width 0.5)
			(island_removal_mode 0)
		)
		(polygon
			(pts
				(arc
					(start 277.522432 -245.785132)
					(mid 276.862032 -245.785132)
					(end 277.522432 -245.785132)
				)
			)
		)
	)
	(zone
		(layers "In1.Cu" "In2.Cu")
		(hatch none 0.5)
		(connect_pads
			(clearance 0)
		)
		(min_thickness 0.25)
		(keepout
			(tracks not_allowed)
			(vias allowed)
			(pads allowed)
			(copperpour not_allowed)
			(footprints allowed)
		)
		(placement
			(enabled no)
			(sheetname "")
		)
		(fill yes
			(thermal_gap 0.5)
			(thermal_bridge_width 0.5)
			(island_removal_mode 0)
		)
		(polygon
			(pts
				(arc
					(start 273.422364 -248.335038)
					(mid 272.761964 -248.335038)
					(end 273.422364 -248.335038)
				)
			)
		)
	)
	(zone
		(layers "In1.Cu" "In2.Cu")
		(hatch none 0.5)
		(connect_pads
			(clearance 0)
		)
		(min_thickness 0.25)
		(keepout
			(tracks not_allowed)
			(vias allowed)
			(pads allowed)
			(copperpour not_allowed)
			(footprints allowed)
		)
		(placement
			(enabled no)
			(sheetname "")
		)
		(fill yes
			(thermal_gap 0.5)
			(thermal_bridge_width 0.5)
			(island_removal_mode 0)
		)
		(polygon
			(pts
				(arc
					(start 407.435812 -417.242244)
					(mid 407.45813 -417.296126)
					(end 407.512012 -417.318444)
				)
				(arc
					(start 407.707592 -417.318444)
					(mid 407.729468 -417.315312)
					(end 407.749502 -417.305998)
				)
				(arc
					(start 408.043126 -417.113466)
					(mid 408.084782 -417.101064)
					(end 408.126438 -417.113466)
				)
				(arc
					(start 408.421332 -417.305998)
					(mid 408.441256 -417.315234)
					(end 408.462988 -417.318444)
				)
				(arc
					(start 408.657552 -417.318444)
					(mid 408.711434 -417.296126)
					(end 408.733752 -417.242244)
				)
				(arc
					(start 408.733752 -416.556444)
					(mid 408.711434 -416.502562)
					(end 408.657552 -416.480244)
				)
				(arc
					(start 408.462988 -416.480244)
					(mid 408.441244 -416.483412)
					(end 408.421332 -416.49269)
				)
				(arc
					(start 408.125168 -416.685476)
					(mid 408.083484 -416.697698)
					(end 408.041856 -416.685222)
				)
				(arc
					(start 407.748232 -416.49269)
					(mid 407.728308 -416.483454)
					(end 407.706576 -416.480244)
				)
				(arc
					(start 407.512012 -416.480244)
					(mid 407.45813 -416.502562)
					(end 407.435812 -416.556444)
				)
			)
		)
	)
	(zone
		(layers "In1.Cu" "In2.Cu")
		(hatch none 0.5)
		(connect_pads
			(clearance 0)
		)
		(min_thickness 0.25)
		(keepout
			(tracks not_allowed)
			(vias allowed)
			(pads allowed)
			(copperpour not_allowed)
			(footprints allowed)
		)
		(placement
			(enabled no)
			(sheetname "")
		)
		(fill yes
			(thermal_gap 0.5)
			(thermal_bridge_width 0.5)
			(island_removal_mode 0)
		)
		(polygon
			(pts
				(arc
					(start 40.57015 -288.285428)
					(mid 39.90975 -288.285428)
					(end 40.57015 -288.285428)
				)
			)
		)
	)
	(zone
		(layers "In1.Cu" "In2.Cu")
		(hatch none 0.5)
		(connect_pads
			(clearance 0)
		)
		(min_thickness 0.25)
		(keepout
			(tracks not_allowed)
			(vias allowed)
			(pads allowed)
			(copperpour not_allowed)
			(footprints allowed)
		)
		(placement
			(enabled no)
			(sheetname "")
		)
		(fill yes
			(thermal_gap 0.5)
			(thermal_bridge_width 0.5)
			(island_removal_mode 0)
		)
		(polygon
			(pts
				(arc
					(start 194.934332 -285.735268)
					(mid 194.273932 -285.735268)
					(end 194.934332 -285.735268)
				)
			)
		)
	)
	(zone
		(layers "In1.Cu" "In2.Cu")
		(hatch none 0.5)
		(connect_pads
			(clearance 0)
		)
		(min_thickness 0.25)
		(keepout
			(tracks not_allowed)
			(vias allowed)
			(pads allowed)
			(copperpour not_allowed)
			(footprints allowed)
		)
		(placement
			(enabled no)
			(sheetname "")
		)
		(fill yes
			(thermal_gap 0.5)
			(thermal_bridge_width 0.5)
			(island_removal_mode 0)
		)
		(polygon
			(pts
				(arc
					(start 25.482296 -301.035212)
					(mid 24.821896 -301.035212)
					(end 25.482296 -301.035212)
				)
			)
		)
	)
	(zone
		(layers "In1.Cu" "In2.Cu")
		(hatch none 0.5)
		(connect_pads
			(clearance 0)
		)
		(min_thickness 0.25)
		(keepout
			(tracks not_allowed)
			(vias allowed)
			(pads allowed)
			(copperpour not_allowed)
			(footprints allowed)
		)
		(placement
			(enabled no)
			(sheetname "")
		)
		(fill yes
			(thermal_gap 0.5)
			(thermal_bridge_width 0.5)
			(island_removal_mode 0)
		)
		(polygon
			(pts
				(arc
					(start 187.390278 -313.78525)
					(mid 186.729878 -313.78525)
					(end 187.390278 -313.78525)
				)
			)
		)
	)
	(zone
		(layers "In1.Cu" "In2.Cu")
		(hatch none 0.5)
		(connect_pads
			(clearance 0)
		)
		(min_thickness 0.25)
		(keepout
			(tracks not_allowed)
			(vias allowed)
			(pads allowed)
			(copperpour not_allowed)
			(footprints allowed)
		)
		(placement
			(enabled no)
			(sheetname "")
		)
		(fill yes
			(thermal_gap 0.5)
			(thermal_bridge_width 0.5)
			(island_removal_mode 0)
		)
		(polygon
			(pts
				(arc
					(start 57.397904 -373.442484)
					(mid 57.417828 -373.45172)
					(end 57.43956 -373.45493)
				)
				(arc
					(start 57.634124 -373.45493)
					(mid 57.688006 -373.432612)
					(end 57.710324 -373.37873)
				)
				(arc
					(start 57.710324 -372.69293)
					(mid 57.688006 -372.639048)
					(end 57.634124 -372.61673)
				)
				(arc
					(start 57.43956 -372.61673)
					(mid 57.417816 -372.619898)
					(end 57.397904 -372.629176)
				)
				(arc
					(start 57.10174 -372.821962)
					(mid 57.060056 -372.834184)
					(end 57.018428 -372.821708)
				)
				(arc
					(start 56.724804 -372.629176)
					(mid 56.70488 -372.61994)
					(end 56.683148 -372.61673)
				)
				(arc
					(start 56.488584 -372.61673)
					(mid 56.434702 -372.639048)
					(end 56.412384 -372.69293)
				)
				(arc
					(start 56.412384 -373.37873)
					(mid 56.434702 -373.432612)
					(end 56.488584 -373.45493)
				)
				(arc
					(start 56.684418 -373.45493)
					(mid 56.706162 -373.451762)
					(end 56.726074 -373.442484)
				)
				(arc
					(start 57.019698 -373.249952)
					(mid 57.061354 -373.23755)
					(end 57.10301 -373.249952)
				)
			)
		)
	)
	(zone
		(layers "In1.Cu" "In2.Cu")
		(hatch none 0.5)
		(connect_pads
			(clearance 0)
		)
		(min_thickness 0.25)
		(keepout
			(tracks not_allowed)
			(vias allowed)
			(pads allowed)
			(copperpour not_allowed)
			(footprints allowed)
		)
		(placement
			(enabled no)
			(sheetname "")
		)
		(fill yes
			(thermal_gap 0.5)
			(thermal_bridge_width 0.5)
			(island_removal_mode 0)
		)
		(polygon
			(pts
				(arc
					(start 439.430414 -300.185074)
					(mid 438.770014 -300.185074)
					(end 439.430414 -300.185074)
				)
			)
		)
	)
	(zone
		(layers "In1.Cu" "In2.Cu")
		(hatch none 0.5)
		(connect_pads
			(clearance 0)
		)
		(min_thickness 0.25)
		(keepout
			(tracks not_allowed)
			(vias allowed)
			(pads allowed)
			(copperpour not_allowed)
			(footprints allowed)
		)
		(placement
			(enabled no)
			(sheetname "")
		)
		(fill yes
			(thermal_gap 0.5)
			(thermal_bridge_width 0.5)
			(island_removal_mode 0)
		)
		(polygon
			(pts
				(arc
					(start 48.114204 -286.585406)
					(mid 47.453804 -286.585406)
					(end 48.114204 -286.585406)
				)
			)
		)
	)
	(zone
		(layers "In1.Cu" "In2.Cu")
		(hatch none 0.5)
		(connect_pads
			(clearance 0)
		)
		(min_thickness 0.25)
		(keepout
			(tracks not_allowed)
			(vias allowed)
			(pads allowed)
			(copperpour not_allowed)
			(footprints allowed)
		)
		(placement
			(enabled no)
			(sheetname "")
		)
		(fill yes
			(thermal_gap 0.5)
			(thermal_bridge_width 0.5)
			(island_removal_mode 0)
		)
		(polygon
			(pts
				(arc
					(start 44.670218 -249.18543)
					(mid 44.009818 -249.18543)
					(end 44.670218 -249.18543)
				)
			)
		)
	)
	(zone
		(layers "In1.Cu" "In2.Cu")
		(hatch none 0.5)
		(connect_pads
			(clearance 0)
		)
		(min_thickness 0.25)
		(keepout
			(tracks not_allowed)
			(vias allowed)
			(pads allowed)
			(copperpour not_allowed)
			(footprints allowed)
		)
		(placement
			(enabled no)
			(sheetname "")
		)
		(fill yes
			(thermal_gap 0.5)
			(thermal_bridge_width 0.5)
			(island_removal_mode 0)
		)
		(polygon
			(pts
				(arc
					(start 148.372576 -408.860244)
					(mid 148.394894 -408.914126)
					(end 148.448776 -408.936444)
				)
				(arc
					(start 148.644356 -408.936444)
					(mid 148.666232 -408.933312)
					(end 148.686266 -408.923998)
				)
				(arc
					(start 148.97989 -408.731466)
					(mid 149.021546 -408.719064)
					(end 149.063202 -408.731466)
				)
				(arc
					(start 149.358096 -408.923998)
					(mid 149.37802 -408.933234)
					(end 149.399752 -408.936444)
				)
				(arc
					(start 149.594316 -408.936444)
					(mid 149.648198 -408.914126)
					(end 149.670516 -408.860244)
				)
				(arc
					(start 149.670516 -408.174444)
					(mid 149.648198 -408.120562)
					(end 149.594316 -408.098244)
				)
				(arc
					(start 149.399752 -408.098244)
					(mid 149.378008 -408.101412)
					(end 149.358096 -408.11069)
				)
				(arc
					(start 149.061932 -408.303476)
					(mid 149.020248 -408.315698)
					(end 148.97862 -408.303222)
				)
				(arc
					(start 148.684996 -408.11069)
					(mid 148.665072 -408.101454)
					(end 148.64334 -408.098244)
				)
				(arc
					(start 148.448776 -408.098244)
					(mid 148.394894 -408.120562)
					(end 148.372576 -408.174444)
				)
			)
		)
	)
	(zone
		(layers "In1.Cu" "In2.Cu")
		(hatch none 0.5)
		(connect_pads
			(clearance 0)
		)
		(min_thickness 0.25)
		(keepout
			(tracks not_allowed)
			(vias allowed)
			(pads allowed)
			(copperpour not_allowed)
			(footprints allowed)
		)
		(placement
			(enabled no)
			(sheetname "")
		)
		(fill yes
			(thermal_gap 0.5)
			(thermal_bridge_width 0.5)
			(island_removal_mode 0)
		)
		(polygon
			(pts
				(arc
					(start 199.0344 -315.485272)
					(mid 198.374 -315.485272)
					(end 199.0344 -315.485272)
				)
			)
		)
	)
	(zone
		(layers "In1.Cu" "In2.Cu")
		(hatch none 0.5)
		(connect_pads
			(clearance 0)
		)
		(min_thickness 0.25)
		(keepout
			(tracks not_allowed)
			(vias allowed)
			(pads allowed)
			(copperpour not_allowed)
			(footprints allowed)
		)
		(placement
			(enabled no)
			(sheetname "")
		)
		(fill yes
			(thermal_gap 0.5)
			(thermal_bridge_width 0.5)
			(island_removal_mode 0)
		)
		(polygon
			(pts
				(arc
					(start 37.126164 -269.58544)
					(mid 36.465764 -269.58544)
					(end 37.126164 -269.58544)
				)
			)
		)
	)
	(zone
		(layers "In1.Cu" "In2.Cu")
		(hatch none 0.5)
		(connect_pads
			(clearance 0)
		)
		(min_thickness 0.25)
		(keepout
			(tracks not_allowed)
			(vias allowed)
			(pads allowed)
			(copperpour not_allowed)
			(footprints allowed)
		)
		(placement
			(enabled no)
			(sheetname "")
		)
		(fill yes
			(thermal_gap 0.5)
			(thermal_bridge_width 0.5)
			(island_removal_mode 0)
		)
		(polygon
			(pts
				(arc
					(start 187.390278 -314.635388)
					(mid 186.729878 -314.635388)
					(end 187.390278 -314.635388)
				)
			)
		)
	)
	(zone
		(layers "In1.Cu" "In2.Cu")
		(hatch none 0.5)
		(connect_pads
			(clearance 0)
		)
		(min_thickness 0.25)
		(keepout
			(tracks not_allowed)
			(vias allowed)
			(pads allowed)
			(copperpour not_allowed)
			(footprints allowed)
		)
		(placement
			(enabled no)
			(sheetname "")
		)
		(fill yes
			(thermal_gap 0.5)
			(thermal_bridge_width 0.5)
			(island_removal_mode 0)
		)
		(polygon
			(pts
				(arc
					(start 120.803416 -408.860244)
					(mid 120.825734 -408.914126)
					(end 120.879616 -408.936444)
				)
				(arc
					(start 121.075196 -408.936444)
					(mid 121.097072 -408.933312)
					(end 121.117106 -408.923998)
				)
				(arc
					(start 121.41073 -408.731466)
					(mid 121.452386 -408.719064)
					(end 121.494042 -408.731466)
				)
				(arc
					(start 121.788936 -408.923998)
					(mid 121.80886 -408.933234)
					(end 121.830592 -408.936444)
				)
				(arc
					(start 122.025156 -408.936444)
					(mid 122.079038 -408.914126)
					(end 122.101356 -408.860244)
				)
				(arc
					(start 122.101356 -408.174444)
					(mid 122.079038 -408.120562)
					(end 122.025156 -408.098244)
				)
				(arc
					(start 121.830592 -408.098244)
					(mid 121.808848 -408.101412)
					(end 121.788936 -408.11069)
				)
				(arc
					(start 121.492772 -408.303476)
					(mid 121.451088 -408.315698)
					(end 121.40946 -408.303222)
				)
				(arc
					(start 121.115836 -408.11069)
					(mid 121.095912 -408.101454)
					(end 121.07418 -408.098244)
				)
				(arc
					(start 120.879616 -408.098244)
					(mid 120.825734 -408.120562)
					(end 120.803416 -408.174444)
				)
			)
		)
	)
	(zone
		(layers "In1.Cu" "In2.Cu")
		(hatch none 0.5)
		(connect_pads
			(clearance 0)
		)
		(min_thickness 0.25)
		(keepout
			(tracks not_allowed)
			(vias allowed)
			(pads allowed)
			(copperpour not_allowed)
			(footprints allowed)
		)
		(placement
			(enabled no)
			(sheetname "")
		)
		(fill yes
			(thermal_gap 0.5)
			(thermal_bridge_width 0.5)
			(island_removal_mode 0)
		)
		(polygon
			(pts
				(arc
					(start 37.126164 -309.535322)
					(mid 36.465764 -309.535322)
					(end 37.126164 -309.535322)
				)
			)
		)
	)
	(zone
		(layers "In1.Cu" "In2.Cu")
		(hatch none 0.5)
		(connect_pads
			(clearance 0)
		)
		(min_thickness 0.25)
		(keepout
			(tracks not_allowed)
			(vias allowed)
			(pads allowed)
			(copperpour not_allowed)
			(footprints allowed)
		)
		(placement
			(enabled no)
			(sheetname "")
		)
		(fill yes
			(thermal_gap 0.5)
			(thermal_bridge_width 0.5)
			(island_removal_mode 0)
		)
		(polygon
			(pts
				(arc
					(start 288.510218 -246.635016)
					(mid 287.849818 -246.635016)
					(end 288.510218 -246.635016)
				)
			)
		)
	)
	(zone
		(layers "In1.Cu" "In2.Cu")
		(hatch none 0.5)
		(connect_pads
			(clearance 0)
		)
		(min_thickness 0.25)
		(keepout
			(tracks not_allowed)
			(vias allowed)
			(pads allowed)
			(copperpour not_allowed)
			(footprints allowed)
		)
		(placement
			(enabled no)
			(sheetname "")
		)
		(fill yes
			(thermal_gap 0.5)
			(thermal_bridge_width 0.5)
			(island_removal_mode 0)
		)
		(polygon
			(pts
				(arc
					(start 52.214272 -238.135414)
					(mid 51.553872 -238.135414)
					(end 52.214272 -238.135414)
				)
			)
		)
	)
	(zone
		(layers "In1.Cu" "In2.Cu")
		(hatch none 0.5)
		(connect_pads
			(clearance 0)
		)
		(min_thickness 0.25)
		(keepout
			(tracks not_allowed)
			(vias allowed)
			(pads allowed)
			(copperpour not_allowed)
			(footprints allowed)
		)
		(placement
			(enabled no)
			(sheetname "")
		)
		(fill yes
			(thermal_gap 0.5)
			(thermal_bridge_width 0.5)
			(island_removal_mode 0)
		)
		(polygon
			(pts
				(arc
					(start 17.938242 -276.385274)
					(mid 17.277842 -276.385274)
					(end 17.938242 -276.385274)
				)
			)
		)
	)
	(zone
		(layers "In1.Cu" "In2.Cu")
		(hatch none 0.5)
		(connect_pads
			(clearance 0)
		)
		(min_thickness 0.25)
		(keepout
			(tracks not_allowed)
			(vias allowed)
			(pads allowed)
			(copperpour not_allowed)
			(footprints allowed)
		)
		(placement
			(enabled no)
			(sheetname "")
		)
		(fill yes
			(thermal_gap 0.5)
			(thermal_bridge_width 0.5)
			(island_removal_mode 0)
		)
		(polygon
			(pts
				(arc
					(start 269.978378 -227.085144)
					(mid 269.317978 -227.085144)
					(end 269.978378 -227.085144)
				)
			)
		)
	)
	(zone
		(layers "In1.Cu" "In2.Cu")
		(hatch none 0.5)
		(connect_pads
			(clearance 0)
		)
		(min_thickness 0.25)
		(keepout
			(tracks not_allowed)
			(vias allowed)
			(pads allowed)
			(copperpour not_allowed)
			(footprints allowed)
		)
		(placement
			(enabled no)
			(sheetname "")
		)
		(fill yes
			(thermal_gap 0.5)
			(thermal_bridge_width 0.5)
			(island_removal_mode 0)
		)
		(polygon
			(pts
				(arc
					(start 292.610286 -250.884944)
					(mid 291.949886 -250.884944)
					(end 292.610286 -250.884944)
				)
			)
		)
	)
	(zone
		(layers "In1.Cu" "In2.Cu")
		(hatch none 0.5)
		(connect_pads
			(clearance 0)
		)
		(min_thickness 0.25)
		(keepout
			(tracks not_allowed)
			(vias allowed)
			(pads allowed)
			(copperpour not_allowed)
			(footprints allowed)
		)
		(placement
			(enabled no)
			(sheetname "")
		)
		(fill yes
			(thermal_gap 0.5)
			(thermal_bridge_width 0.5)
			(island_removal_mode 0)
		)
		(polygon
			(pts
				(arc
					(start 280.966164 -246.635016)
					(mid 280.305764 -246.635016)
					(end 280.966164 -246.635016)
				)
			)
		)
	)
	(zone
		(layers "In1.Cu" "In2.Cu")
		(hatch none 0.5)
		(connect_pads
			(clearance 0)
		)
		(min_thickness 0.25)
		(keepout
			(tracks not_allowed)
			(vias allowed)
			(pads allowed)
			(copperpour not_allowed)
			(footprints allowed)
		)
		(placement
			(enabled no)
			(sheetname "")
		)
		(fill yes
			(thermal_gap 0.5)
			(thermal_bridge_width 0.5)
			(island_removal_mode 0)
		)
		(polygon
			(pts
				(arc
					(start 431.88636 -304.435002)
					(mid 431.22596 -304.435002)
					(end 431.88636 -304.435002)
				)
			)
		)
	)
	(zone
		(layers "In1.Cu" "In2.Cu")
		(hatch none 0.5)
		(connect_pads
			(clearance 0)
		)
		(min_thickness 0.25)
		(keepout
			(tracks not_allowed)
			(vias allowed)
			(pads allowed)
			(copperpour not_allowed)
			(footprints allowed)
		)
		(placement
			(enabled no)
			(sheetname "")
		)
		(fill yes
			(thermal_gap 0.5)
			(thermal_bridge_width 0.5)
			(island_removal_mode 0)
		)
		(polygon
			(pts
				(arc
					(start 296.054272 -268.735048)
					(mid 295.393872 -268.735048)
					(end 296.054272 -268.735048)
				)
			)
		)
	)
	(zone
		(layers "In1.Cu" "In2.Cu")
		(hatch none 0.5)
		(connect_pads
			(clearance 0)
		)
		(min_thickness 0.25)
		(keepout
			(tracks not_allowed)
			(vias allowed)
			(pads allowed)
			(copperpour not_allowed)
			(footprints allowed)
		)
		(placement
			(enabled no)
			(sheetname "")
		)
		(fill yes
			(thermal_gap 0.5)
			(thermal_bridge_width 0.5)
			(island_removal_mode 0)
		)
		(polygon
			(pts
				(arc
					(start 288.510218 -297.635168)
					(mid 287.849818 -297.635168)
					(end 288.510218 -297.635168)
				)
			)
		)
	)
	(zone
		(layers "In1.Cu" "In2.Cu")
		(hatch none 0.5)
		(connect_pads
			(clearance 0)
		)
		(min_thickness 0.25)
		(keepout
			(tracks not_allowed)
			(vias allowed)
			(pads allowed)
			(copperpour not_allowed)
			(footprints allowed)
		)
		(placement
			(enabled no)
			(sheetname "")
		)
		(fill yes
			(thermal_gap 0.5)
			(thermal_bridge_width 0.5)
			(island_removal_mode 0)
		)
		(polygon
			(pts
				(arc
					(start 17.938242 -272.98523)
					(mid 17.277842 -272.98523)
					(end 17.938242 -272.98523)
				)
			)
		)
	)
	(zone
		(layers "In1.Cu" "In2.Cu")
		(hatch none 0.5)
		(connect_pads
			(clearance 0)
		)
		(min_thickness 0.25)
		(keepout
			(tracks not_allowed)
			(vias allowed)
			(pads allowed)
			(copperpour not_allowed)
			(footprints allowed)
		)
		(placement
			(enabled no)
			(sheetname "")
		)
		(fill yes
			(thermal_gap 0.5)
			(thermal_bridge_width 0.5)
			(island_removal_mode 0)
		)
		(polygon
			(pts
				(arc
					(start 435.330346 -202.434952)
					(mid 434.669946 -202.434952)
					(end 435.330346 -202.434952)
				)
			)
		)
	)
	(zone
		(layers "In1.Cu" "In2.Cu")
		(hatch none 0.5)
		(connect_pads
			(clearance 0)
		)
		(min_thickness 0.25)
		(keepout
			(tracks not_allowed)
			(vias allowed)
			(pads allowed)
			(copperpour not_allowed)
			(footprints allowed)
		)
		(placement
			(enabled no)
			(sheetname "")
		)
		(fill yes
			(thermal_gap 0.5)
			(thermal_bridge_width 0.5)
			(island_removal_mode 0)
		)
		(polygon
			(pts
				(arc
					(start 52.214272 -311.235344)
					(mid 51.553872 -311.235344)
					(end 52.214272 -311.235344)
				)
			)
		)
	)
	(zone
		(layers "In1.Cu" "In2.Cu")
		(hatch none 0.5)
		(connect_pads
			(clearance 0)
		)
		(min_thickness 0.25)
		(keepout
			(tracks not_allowed)
			(vias allowed)
			(pads allowed)
			(copperpour not_allowed)
			(footprints allowed)
		)
		(placement
			(enabled no)
			(sheetname "")
		)
		(fill yes
			(thermal_gap 0.5)
			(thermal_bridge_width 0.5)
			(island_removal_mode 0)
		)
		(polygon
			(pts
				(arc
					(start 442.8744 -221.13494)
					(mid 442.214 -221.13494)
					(end 442.8744 -221.13494)
				)
			)
		)
	)
	(zone
		(layers "In1.Cu" "In2.Cu")
		(hatch none 0.5)
		(connect_pads
			(clearance 0)
		)
		(min_thickness 0.25)
		(keepout
			(tracks not_allowed)
			(vias allowed)
			(pads allowed)
			(copperpour not_allowed)
			(footprints allowed)
		)
		(placement
			(enabled no)
			(sheetname "")
		)
		(fill yes
			(thermal_gap 0.5)
			(thermal_bridge_width 0.5)
			(island_removal_mode 0)
		)
		(polygon
			(pts
				(arc
					(start 446.974468 -212.635084)
					(mid 446.314068 -212.635084)
					(end 446.974468 -212.635084)
				)
			)
		)
	)
	(zone
		(layers "In1.Cu" "In2.Cu")
		(hatch none 0.5)
		(connect_pads
			(clearance 0)
		)
		(min_thickness 0.25)
		(keepout
			(tracks not_allowed)
			(vias allowed)
			(pads allowed)
			(copperpour not_allowed)
			(footprints allowed)
		)
		(placement
			(enabled no)
			(sheetname "")
		)
		(fill yes
			(thermal_gap 0.5)
			(thermal_bridge_width 0.5)
			(island_removal_mode 0)
		)
		(polygon
			(pts
				(arc
					(start 431.88636 -220.285056)
					(mid 431.22596 -220.285056)
					(end 431.88636 -220.285056)
				)
			)
		)
	)
	(zone
		(layers "In1.Cu" "In2.Cu")
		(hatch none 0.5)
		(connect_pads
			(clearance 0)
		)
		(min_thickness 0.25)
		(keepout
			(tracks not_allowed)
			(vias allowed)
			(pads allowed)
			(copperpour not_allowed)
			(footprints allowed)
		)
		(placement
			(enabled no)
			(sheetname "")
		)
		(fill yes
			(thermal_gap 0.5)
			(thermal_bridge_width 0.5)
			(island_removal_mode 0)
		)
		(polygon
			(pts
				(arc
					(start 292.610286 -200.735184)
					(mid 291.949886 -200.735184)
					(end 292.610286 -200.735184)
				)
			)
		)
	)
	(zone
		(layers "In1.Cu" "In2.Cu")
		(hatch none 0.5)
		(connect_pads
			(clearance 0)
		)
		(min_thickness 0.25)
		(keepout
			(tracks not_allowed)
			(vias allowed)
			(pads allowed)
			(copperpour not_allowed)
			(footprints allowed)
		)
		(placement
			(enabled no)
			(sheetname "")
		)
		(fill yes
			(thermal_gap 0.5)
			(thermal_bridge_width 0.5)
			(island_removal_mode 0)
		)
		(polygon
			(pts
				(arc
					(start 84.820252 -370.978684)
					(mid 84.840176 -370.98792)
					(end 84.861908 -370.99113)
				)
				(arc
					(start 85.056472 -370.99113)
					(mid 85.110354 -370.968812)
					(end 85.132672 -370.91493)
				)
				(arc
					(start 85.132672 -370.22913)
					(mid 85.110354 -370.175248)
					(end 85.056472 -370.15293)
				)
				(arc
					(start 84.861908 -370.15293)
					(mid 84.840164 -370.156098)
					(end 84.820252 -370.165376)
				)
				(arc
					(start 84.524088 -370.358162)
					(mid 84.482404 -370.370384)
					(end 84.440776 -370.357908)
				)
				(arc
					(start 84.147152 -370.165376)
					(mid 84.127228 -370.15614)
					(end 84.105496 -370.15293)
				)
				(arc
					(start 83.910932 -370.15293)
					(mid 83.85705 -370.175248)
					(end 83.834732 -370.22913)
				)
				(arc
					(start 83.834732 -370.91493)
					(mid 83.85705 -370.968812)
					(end 83.910932 -370.99113)
				)
				(arc
					(start 84.106766 -370.99113)
					(mid 84.12851 -370.987962)
					(end 84.148422 -370.978684)
				)
				(arc
					(start 84.442046 -370.786152)
					(mid 84.483702 -370.77375)
					(end 84.525358 -370.786152)
				)
			)
		)
	)
	(zone
		(layers "In1.Cu" "In2.Cu")
		(hatch none 0.5)
		(connect_pads
			(clearance 0)
		)
		(min_thickness 0.25)
		(keepout
			(tracks not_allowed)
			(vias allowed)
			(pads allowed)
			(copperpour not_allowed)
			(footprints allowed)
		)
		(placement
			(enabled no)
			(sheetname "")
		)
		(fill yes
			(thermal_gap 0.5)
			(thermal_bridge_width 0.5)
			(island_removal_mode 0)
		)
		(polygon
			(pts
				(arc
					(start 187.390278 -302.735234)
					(mid 186.729878 -302.735234)
					(end 187.390278 -302.735234)
				)
			)
		)
	)
	(zone
		(layers "In1.Cu" "In2.Cu")
		(hatch none 0.5)
		(connect_pads
			(clearance 0)
		)
		(min_thickness 0.25)
		(keepout
			(tracks not_allowed)
			(vias allowed)
			(pads allowed)
			(copperpour not_allowed)
			(footprints allowed)
		)
		(placement
			(enabled no)
			(sheetname "")
		)
		(fill yes
			(thermal_gap 0.5)
			(thermal_bridge_width 0.5)
			(island_removal_mode 0)
		)
		(polygon
			(pts
				(arc
					(start 33.026096 -207.535272)
					(mid 32.365696 -207.535272)
					(end 33.026096 -207.535272)
				)
			)
		)
	)
	(zone
		(layers "In1.Cu" "In2.Cu")
		(hatch none 0.5)
		(connect_pads
			(clearance 0)
		)
		(min_thickness 0.25)
		(keepout
			(tracks not_allowed)
			(vias allowed)
			(pads allowed)
			(copperpour not_allowed)
			(footprints allowed)
		)
		(placement
			(enabled no)
			(sheetname "")
		)
		(fill yes
			(thermal_gap 0.5)
			(thermal_bridge_width 0.5)
			(island_removal_mode 0)
		)
		(polygon
			(pts
				(arc
					(start 420.242238 -288.285174)
					(mid 419.581838 -288.285174)
					(end 420.242238 -288.285174)
				)
			)
		)
	)
	(zone
		(layers "In1.Cu" "In2.Cu")
		(hatch none 0.5)
		(connect_pads
			(clearance 0)
		)
		(min_thickness 0.25)
		(keepout
			(tracks not_allowed)
			(vias allowed)
			(pads allowed)
			(copperpour not_allowed)
			(footprints allowed)
		)
		(placement
			(enabled no)
			(sheetname "")
		)
		(fill yes
			(thermal_gap 0.5)
			(thermal_bridge_width 0.5)
			(island_removal_mode 0)
		)
		(polygon
			(pts
				(arc
					(start 194.934332 -274.685252)
					(mid 194.273932 -274.685252)
					(end 194.934332 -274.685252)
				)
			)
		)
	)
	(zone
		(layers "In1.Cu" "In2.Cu")
		(hatch none 0.5)
		(connect_pads
			(clearance 0)
		)
		(min_thickness 0.25)
		(keepout
			(tracks not_allowed)
			(vias allowed)
			(pads allowed)
			(copperpour not_allowed)
			(footprints allowed)
		)
		(placement
			(enabled no)
			(sheetname "")
		)
		(fill yes
			(thermal_gap 0.5)
			(thermal_bridge_width 0.5)
			(island_removal_mode 0)
		)
		(polygon
			(pts
				(arc
					(start 392.434318 -385.243578)
					(mid 392.425082 -385.263502)
					(end 392.421872 -385.285234)
				)
				(arc
					(start 392.421872 -385.479798)
					(mid 392.44419 -385.53368)
					(end 392.498072 -385.555998)
				)
				(arc
					(start 393.183872 -385.555998)
					(mid 393.237754 -385.53368)
					(end 393.260072 -385.479798)
				)
				(arc
					(start 393.260072 -385.285234)
					(mid 393.256904 -385.26349)
					(end 393.247626 -385.243578)
				)
				(arc
					(start 393.05484 -384.947414)
					(mid 393.042618 -384.90573)
					(end 393.055094 -384.864102)
				)
				(arc
					(start 393.247626 -384.570478)
					(mid 393.256862 -384.550554)
					(end 393.260072 -384.528822)
				)
				(arc
					(start 393.260072 -384.334258)
					(mid 393.237754 -384.280376)
					(end 393.183872 -384.258058)
				)
				(arc
					(start 392.498072 -384.258058)
					(mid 392.44419 -384.280376)
					(end 392.421872 -384.334258)
				)
				(arc
					(start 392.421872 -384.530092)
					(mid 392.42504 -384.551836)
					(end 392.434318 -384.571748)
				)
				(arc
					(start 392.62685 -384.865372)
					(mid 392.639252 -384.907028)
					(end 392.62685 -384.948684)
				)
			)
		)
	)
	(zone
		(layers "In1.Cu" "In2.Cu")
		(hatch none 0.5)
		(connect_pads
			(clearance 0)
		)
		(min_thickness 0.25)
		(keepout
			(tracks not_allowed)
			(vias allowed)
			(pads allowed)
			(copperpour not_allowed)
			(footprints allowed)
		)
		(placement
			(enabled no)
			(sheetname "")
		)
		(fill yes
			(thermal_gap 0.5)
			(thermal_bridge_width 0.5)
			(island_removal_mode 0)
		)
		(polygon
			(pts
				(arc
					(start 44.670218 -240.68532)
					(mid 44.009818 -240.68532)
					(end 44.670218 -240.68532)
				)
			)
		)
	)
	(zone
		(layers "In1.Cu" "In2.Cu")
		(hatch none 0.5)
		(connect_pads
			(clearance 0)
		)
		(min_thickness 0.25)
		(keepout
			(tracks not_allowed)
			(vias allowed)
			(pads allowed)
			(copperpour not_allowed)
			(footprints allowed)
		)
		(placement
			(enabled no)
			(sheetname "")
		)
		(fill yes
			(thermal_gap 0.5)
			(thermal_bridge_width 0.5)
			(island_removal_mode 0)
		)
		(polygon
			(pts
				(arc
					(start 280.966164 -314.635134)
					(mid 280.305764 -314.635134)
					(end 280.966164 -314.635134)
				)
			)
		)
	)
	(zone
		(layers "In1.Cu" "In2.Cu")
		(hatch none 0.5)
		(connect_pads
			(clearance 0)
		)
		(min_thickness 0.25)
		(keepout
			(tracks not_allowed)
			(vias allowed)
			(pads allowed)
			(copperpour not_allowed)
			(footprints allowed)
		)
		(placement
			(enabled no)
			(sheetname "")
		)
		(fill yes
			(thermal_gap 0.5)
			(thermal_bridge_width 0.5)
			(island_removal_mode 0)
		)
		(polygon
			(pts
				(arc
					(start 300.15434 -221.985078)
					(mid 299.49394 -221.985078)
					(end 300.15434 -221.985078)
				)
			)
		)
	)
	(zone
		(layers "In1.Cu" "In2.Cu")
		(hatch none 0.5)
		(connect_pads
			(clearance 0)
		)
		(min_thickness 0.25)
		(keepout
			(tracks not_allowed)
			(vias allowed)
			(pads allowed)
			(copperpour not_allowed)
			(footprints allowed)
		)
		(placement
			(enabled no)
			(sheetname "")
		)
		(fill yes
			(thermal_gap 0.5)
			(thermal_bridge_width 0.5)
			(island_removal_mode 0)
		)
		(polygon
			(pts
				(arc
					(start 285.066232 -281.485086)
					(mid 284.405832 -281.485086)
					(end 285.066232 -281.485086)
				)
			)
		)
	)
	(zone
		(layers "In1.Cu" "In2.Cu")
		(hatch none 0.5)
		(connect_pads
			(clearance 0)
		)
		(min_thickness 0.25)
		(keepout
			(tracks not_allowed)
			(vias allowed)
			(pads allowed)
			(copperpour not_allowed)
			(footprints allowed)
		)
		(placement
			(enabled no)
			(sheetname "")
		)
		(fill yes
			(thermal_gap 0.5)
			(thermal_bridge_width 0.5)
			(island_removal_mode 0)
		)
		(polygon
			(pts
				(arc
					(start 40.57015 -248.335292)
					(mid 39.90975 -248.335292)
					(end 40.57015 -248.335292)
				)
			)
		)
	)
	(zone
		(layers "In1.Cu" "In2.Cu")
		(hatch none 0.5)
		(connect_pads
			(clearance 0)
		)
		(min_thickness 0.25)
		(keepout
			(tracks not_allowed)
			(vias allowed)
			(pads allowed)
			(copperpour not_allowed)
			(footprints allowed)
		)
		(placement
			(enabled no)
			(sheetname "")
		)
		(fill yes
			(thermal_gap 0.5)
			(thermal_bridge_width 0.5)
			(island_removal_mode 0)
		)
		(polygon
			(pts
				(arc
					(start 17.938242 -268.735302)
					(mid 17.277842 -268.735302)
					(end 17.938242 -268.735302)
				)
			)
		)
	)
	(zone
		(layers "In1.Cu" "In2.Cu")
		(hatch none 0.5)
		(connect_pads
			(clearance 0)
		)
		(min_thickness 0.25)
		(keepout
			(tracks not_allowed)
			(vias allowed)
			(pads allowed)
			(copperpour not_allowed)
			(footprints allowed)
		)
		(placement
			(enabled no)
			(sheetname "")
		)
		(fill yes
			(thermal_gap 0.5)
			(thermal_bridge_width 0.5)
			(island_removal_mode 0)
		)
		(polygon
			(pts
				(arc
					(start 300.15434 -210.085178)
					(mid 299.49394 -210.085178)
					(end 300.15434 -210.085178)
				)
			)
		)
	)
	(zone
		(layers "In1.Cu" "In2.Cu")
		(hatch none 0.5)
		(connect_pads
			(clearance 0)
		)
		(min_thickness 0.25)
		(keepout
			(tracks not_allowed)
			(vias allowed)
			(pads allowed)
			(copperpour not_allowed)
			(footprints allowed)
		)
		(placement
			(enabled no)
			(sheetname "")
		)
		(fill yes
			(thermal_gap 0.5)
			(thermal_bridge_width 0.5)
			(island_removal_mode 0)
		)
		(polygon
			(pts
				(arc
					(start 420.242238 -233.884978)
					(mid 419.581838 -233.884978)
					(end 420.242238 -233.884978)
				)
			)
		)
	)
	(zone
		(layers "In1.Cu" "In2.Cu")
		(hatch none 0.5)
		(connect_pads
			(clearance 0)
		)
		(min_thickness 0.25)
		(keepout
			(tracks not_allowed)
			(vias allowed)
			(pads allowed)
			(copperpour not_allowed)
			(footprints allowed)
		)
		(placement
			(enabled no)
			(sheetname "")
		)
		(fill yes
			(thermal_gap 0.5)
			(thermal_bridge_width 0.5)
			(island_removal_mode 0)
		)
		(polygon
			(pts
				(arc
					(start 172.30217 -207.535272)
					(mid 171.64177 -207.535272)
					(end 172.30217 -207.535272)
				)
			)
		)
	)
	(zone
		(layers "In1.Cu" "In2.Cu")
		(hatch none 0.5)
		(connect_pads
			(clearance 0)
		)
		(min_thickness 0.25)
		(keepout
			(tracks not_allowed)
			(vias allowed)
			(pads allowed)
			(copperpour not_allowed)
			(footprints allowed)
		)
		(placement
			(enabled no)
			(sheetname "")
		)
		(fill yes
			(thermal_gap 0.5)
			(thermal_bridge_width 0.5)
			(island_removal_mode 0)
		)
		(polygon
			(pts
				(arc
					(start 157.562296 -408.860244)
					(mid 157.584614 -408.914126)
					(end 157.638496 -408.936444)
				)
				(arc
					(start 157.834076 -408.936444)
					(mid 157.855952 -408.933312)
					(end 157.875986 -408.923998)
				)
				(arc
					(start 158.16961 -408.731466)
					(mid 158.211266 -408.719064)
					(end 158.252922 -408.731466)
				)
				(arc
					(start 158.547816 -408.923998)
					(mid 158.56774 -408.933234)
					(end 158.589472 -408.936444)
				)
				(arc
					(start 158.784036 -408.936444)
					(mid 158.837918 -408.914126)
					(end 158.860236 -408.860244)
				)
				(arc
					(start 158.860236 -408.174444)
					(mid 158.837918 -408.120562)
					(end 158.784036 -408.098244)
				)
				(arc
					(start 158.589472 -408.098244)
					(mid 158.567728 -408.101412)
					(end 158.547816 -408.11069)
				)
				(arc
					(start 158.251652 -408.303476)
					(mid 158.209968 -408.315698)
					(end 158.16834 -408.303222)
				)
				(arc
					(start 157.874716 -408.11069)
					(mid 157.854792 -408.101454)
					(end 157.83306 -408.098244)
				)
				(arc
					(start 157.638496 -408.098244)
					(mid 157.584614 -408.120562)
					(end 157.562296 -408.174444)
				)
			)
		)
	)
	(zone
		(layers "In1.Cu" "In2.Cu")
		(hatch none 0.5)
		(connect_pads
			(clearance 0)
		)
		(min_thickness 0.25)
		(keepout
			(tracks not_allowed)
			(vias allowed)
			(pads allowed)
			(copperpour not_allowed)
			(footprints allowed)
		)
		(placement
			(enabled no)
			(sheetname "")
		)
		(fill yes
			(thermal_gap 0.5)
			(thermal_bridge_width 0.5)
			(island_removal_mode 0)
		)
		(polygon
			(pts
				(arc
					(start 454.518268 -284.88513)
					(mid 453.857868 -284.88513)
					(end 454.518268 -284.88513)
				)
			)
		)
	)
	(zone
		(layers "In1.Cu" "In2.Cu")
		(hatch none 0.5)
		(connect_pads
			(clearance 0)
		)
		(min_thickness 0.25)
		(keepout
			(tracks not_allowed)
			(vias allowed)
			(pads allowed)
			(copperpour not_allowed)
			(footprints allowed)
		)
		(placement
			(enabled no)
			(sheetname "")
		)
		(fill yes
			(thermal_gap 0.5)
			(thermal_bridge_width 0.5)
			(island_removal_mode 0)
		)
		(polygon
			(pts
				(arc
					(start 22.03831 -267.885418)
					(mid 21.37791 -267.885418)
					(end 22.03831 -267.885418)
				)
			)
		)
	)
	(zone
		(layers "In1.Cu" "In2.Cu")
		(hatch none 0.5)
		(connect_pads
			(clearance 0)
		)
		(min_thickness 0.25)
		(keepout
			(tracks not_allowed)
			(vias allowed)
			(pads allowed)
			(copperpour not_allowed)
			(footprints allowed)
		)
		(placement
			(enabled no)
			(sheetname "")
		)
		(fill yes
			(thermal_gap 0.5)
			(thermal_bridge_width 0.5)
			(island_removal_mode 0)
		)
		(polygon
			(pts
				(arc
					(start 18.852388 -7.672324)
					(mid 18.874706 -7.618442)
					(end 18.928588 -7.596124)
				)
				(arc
					(start 19.965162 -7.596124)
					(mid 20.019044 -7.618442)
					(end 20.041362 -7.672324)
				)
				(arc
					(start 20.041362 -9.071864)
					(mid 20.019044 -9.125746)
					(end 19.965162 -9.148064)
				)
				(arc
					(start 18.928588 -9.148064)
					(mid 18.874706 -9.125746)
					(end 18.852388 -9.071864)
				)
			)
		)
	)
	(zone
		(layers "In1.Cu" "In2.Cu")
		(hatch none 0.5)
		(connect_pads
			(clearance 0)
		)
		(min_thickness 0.25)
		(keepout
			(tracks not_allowed)
			(vias allowed)
			(pads allowed)
			(copperpour not_allowed)
			(footprints allowed)
		)
		(placement
			(enabled no)
			(sheetname "")
		)
		(fill yes
			(thermal_gap 0.5)
			(thermal_bridge_width 0.5)
			(island_removal_mode 0)
		)
		(polygon
			(pts
				(arc
					(start 424.342306 -292.535102)
					(mid 423.681906 -292.535102)
					(end 424.342306 -292.535102)
				)
			)
		)
	)
	(zone
		(layers "In1.Cu" "In2.Cu")
		(hatch none 0.5)
		(connect_pads
			(clearance 0)
		)
		(min_thickness 0.25)
		(keepout
			(tracks not_allowed)
			(vias allowed)
			(pads allowed)
			(copperpour not_allowed)
			(footprints allowed)
		)
		(placement
			(enabled no)
			(sheetname "")
		)
		(fill yes
			(thermal_gap 0.5)
			(thermal_bridge_width 0.5)
			(island_removal_mode 0)
		)
		(polygon
			(pts
				(arc
					(start 450.4182 -232.184956)
					(mid 449.7578 -232.184956)
					(end 450.4182 -232.184956)
				)
			)
		)
	)
	(zone
		(layers "In1.Cu" "In2.Cu")
		(hatch none 0.5)
		(connect_pads
			(clearance 0)
		)
		(min_thickness 0.25)
		(keepout
			(tracks not_allowed)
			(vias allowed)
			(pads allowed)
			(copperpour not_allowed)
			(footprints allowed)
		)
		(placement
			(enabled no)
			(sheetname "")
		)
		(fill yes
			(thermal_gap 0.5)
			(thermal_bridge_width 0.5)
			(island_removal_mode 0)
		)
		(polygon
			(pts
				(arc
					(start 273.422364 -244.934994)
					(mid 272.761964 -244.934994)
					(end 273.422364 -244.934994)
				)
			)
		)
	)
	(zone
		(layers "In1.Cu" "In2.Cu")
		(hatch none 0.5)
		(connect_pads
			(clearance 0)
		)
		(min_thickness 0.25)
		(keepout
			(tracks not_allowed)
			(vias allowed)
			(pads allowed)
			(copperpour not_allowed)
			(footprints allowed)
		)
		(placement
			(enabled no)
			(sheetname "")
		)
		(fill yes
			(thermal_gap 0.5)
			(thermal_bridge_width 0.5)
			(island_removal_mode 0)
		)
		(polygon
			(pts
				(arc
					(start 40.57015 -263.635236)
					(mid 39.90975 -263.635236)
					(end 40.57015 -263.635236)
				)
			)
		)
	)
	(zone
		(layers "In1.Cu" "In2.Cu")
		(hatch none 0.5)
		(connect_pads
			(clearance 0)
		)
		(min_thickness 0.25)
		(keepout
			(tracks not_allowed)
			(vias allowed)
			(pads allowed)
			(copperpour not_allowed)
			(footprints allowed)
		)
		(placement
			(enabled no)
			(sheetname "")
		)
		(fill yes
			(thermal_gap 0.5)
			(thermal_bridge_width 0.5)
			(island_removal_mode 0)
		)
		(polygon
			(pts
				(arc
					(start 269.978378 -228.785166)
					(mid 269.317978 -228.785166)
					(end 269.978378 -228.785166)
				)
			)
		)
	)
	(zone
		(layers "In1.Cu" "In2.Cu")
		(hatch none 0.5)
		(connect_pads
			(clearance 0)
		)
		(min_thickness 0.25)
		(keepout
			(tracks not_allowed)
			(vias allowed)
			(pads allowed)
			(copperpour not_allowed)
			(footprints allowed)
		)
		(placement
			(enabled no)
			(sheetname "")
		)
		(fill yes
			(thermal_gap 0.5)
			(thermal_bridge_width 0.5)
			(island_removal_mode 0)
		)
		(polygon
			(pts
				(arc
					(start 25.482296 -318.035432)
					(mid 24.821896 -318.035432)
					(end 25.482296 -318.035432)
				)
			)
		)
	)
	(zone
		(layers "In1.Cu" "In2.Cu")
		(hatch none 0.5)
		(connect_pads
			(clearance 0)
		)
		(min_thickness 0.25)
		(keepout
			(tracks not_allowed)
			(vias allowed)
			(pads allowed)
			(copperpour not_allowed)
			(footprints allowed)
		)
		(placement
			(enabled no)
			(sheetname "")
		)
		(fill yes
			(thermal_gap 0.5)
			(thermal_bridge_width 0.5)
			(island_removal_mode 0)
		)
		(polygon
			(pts
				(arc
					(start 431.88636 -298.485052)
					(mid 431.22596 -298.485052)
					(end 431.88636 -298.485052)
				)
			)
		)
	)
	(zone
		(layers "In1.Cu" "In2.Cu")
		(hatch none 0.5)
		(connect_pads
			(clearance 0)
		)
		(min_thickness 0.25)
		(keepout
			(tracks not_allowed)
			(vias allowed)
			(pads allowed)
			(copperpour not_allowed)
			(footprints allowed)
		)
		(placement
			(enabled no)
			(sheetname "")
		)
		(fill yes
			(thermal_gap 0.5)
			(thermal_bridge_width 0.5)
			(island_removal_mode 0)
		)
		(polygon
			(pts
				(arc
					(start 269.978378 -279.785064)
					(mid 269.317978 -279.785064)
					(end 269.978378 -279.785064)
				)
			)
		)
	)
	(zone
		(layers "In1.Cu" "In2.Cu")
		(hatch none 0.5)
		(connect_pads
			(clearance 0)
		)
		(min_thickness 0.25)
		(keepout
			(tracks not_allowed)
			(vias allowed)
			(pads allowed)
			(copperpour not_allowed)
			(footprints allowed)
		)
		(placement
			(enabled no)
			(sheetname "")
		)
		(fill yes
			(thermal_gap 0.5)
			(thermal_bridge_width 0.5)
			(island_removal_mode 0)
		)
		(polygon
			(pts
				(arc
					(start 427.786292 -198.185024)
					(mid 427.125892 -198.185024)
					(end 427.786292 -198.185024)
				)
			)
		)
	)
	(zone
		(layers "In1.Cu" "In2.Cu")
		(hatch none 0.5)
		(connect_pads
			(clearance 0)
		)
		(min_thickness 0.25)
		(keepout
			(tracks not_allowed)
			(vias allowed)
			(pads allowed)
			(copperpour not_allowed)
			(footprints allowed)
		)
		(placement
			(enabled no)
			(sheetname "")
		)
		(fill yes
			(thermal_gap 0.5)
			(thermal_bridge_width 0.5)
			(island_removal_mode 0)
		)
		(polygon
			(pts
				(arc
					(start 29.582364 -311.235344)
					(mid 28.921964 -311.235344)
					(end 29.582364 -311.235344)
				)
			)
		)
	)
	(zone
		(layers "In1.Cu" "In2.Cu")
		(hatch none 0.5)
		(connect_pads
			(clearance 0)
		)
		(min_thickness 0.25)
		(keepout
			(tracks not_allowed)
			(vias allowed)
			(pads allowed)
			(copperpour not_allowed)
			(footprints allowed)
		)
		(placement
			(enabled no)
			(sheetname "")
		)
		(fill yes
			(thermal_gap 0.5)
			(thermal_bridge_width 0.5)
			(island_removal_mode 0)
		)
		(polygon
			(pts
				(arc
					(start 202.478132 -248.335292)
					(mid 201.817732 -248.335292)
					(end 202.478132 -248.335292)
				)
			)
		)
	)
	(zone
		(layers "In1.Cu" "In2.Cu")
		(hatch none 0.5)
		(connect_pads
			(clearance 0)
		)
		(min_thickness 0.25)
		(keepout
			(tracks not_allowed)
			(vias allowed)
			(pads allowed)
			(copperpour not_allowed)
			(footprints allowed)
		)
		(placement
			(enabled no)
			(sheetname "")
		)
		(fill yes
			(thermal_gap 0.5)
			(thermal_bridge_width 0.5)
			(island_removal_mode 0)
		)
		(polygon
			(pts
				(arc
					(start 420.242238 -241.53495)
					(mid 419.581838 -241.53495)
					(end 420.242238 -241.53495)
				)
			)
		)
	)
	(zone
		(layers "In1.Cu" "In2.Cu")
		(hatch none 0.5)
		(connect_pads
			(clearance 0)
		)
		(min_thickness 0.25)
		(keepout
			(tracks not_allowed)
			(vias allowed)
			(pads allowed)
			(copperpour not_allowed)
			(footprints allowed)
		)
		(placement
			(enabled no)
			(sheetname "")
		)
		(fill yes
			(thermal_gap 0.5)
			(thermal_bridge_width 0.5)
			(island_removal_mode 0)
		)
		(polygon
			(pts
				(arc
					(start 450.4182 -237.285022)
					(mid 449.7578 -237.285022)
					(end 450.4182 -237.285022)
				)
			)
		)
	)
	(zone
		(layers "In1.Cu" "In2.Cu")
		(hatch none 0.5)
		(connect_pads
			(clearance 0)
		)
		(min_thickness 0.25)
		(keepout
			(tracks not_allowed)
			(vias allowed)
			(pads allowed)
			(copperpour not_allowed)
			(footprints allowed)
		)
		(placement
			(enabled no)
			(sheetname "")
		)
		(fill yes
			(thermal_gap 0.5)
			(thermal_bridge_width 0.5)
			(island_removal_mode 0)
		)
		(polygon
			(pts
				(arc
					(start 296.054272 -261.93496)
					(mid 295.393872 -261.93496)
					(end 296.054272 -261.93496)
				)
			)
		)
	)
	(zone
		(layers "In1.Cu" "In2.Cu")
		(hatch none 0.5)
		(connect_pads
			(clearance 0)
		)
		(min_thickness 0.25)
		(keepout
			(tracks not_allowed)
			(vias allowed)
			(pads allowed)
			(copperpour not_allowed)
			(footprints allowed)
		)
		(placement
			(enabled no)
			(sheetname "")
		)
		(fill yes
			(thermal_gap 0.5)
			(thermal_bridge_width 0.5)
			(island_removal_mode 0)
		)
		(polygon
			(pts
				(arc
					(start 191.490346 -317.185294)
					(mid 190.829946 -317.185294)
					(end 191.490346 -317.185294)
				)
			)
		)
	)
	(zone
		(layers "In1.Cu" "In2.Cu")
		(hatch none 0.5)
		(connect_pads
			(clearance 0)
		)
		(min_thickness 0.25)
		(keepout
			(tracks not_allowed)
			(vias allowed)
			(pads allowed)
			(copperpour not_allowed)
			(footprints allowed)
		)
		(placement
			(enabled no)
			(sheetname "")
		)
		(fill yes
			(thermal_gap 0.5)
			(thermal_bridge_width 0.5)
			(island_removal_mode 0)
		)
		(polygon
			(pts
				(arc
					(start 37.126164 -250.885198)
					(mid 36.465764 -250.885198)
					(end 37.126164 -250.885198)
				)
			)
		)
	)
	(zone
		(layers "In1.Cu" "In2.Cu")
		(hatch none 0.5)
		(connect_pads
			(clearance 0)
		)
		(min_thickness 0.25)
		(keepout
			(tracks not_allowed)
			(vias allowed)
			(pads allowed)
			(copperpour not_allowed)
			(footprints allowed)
		)
		(placement
			(enabled no)
			(sheetname "")
		)
		(fill yes
			(thermal_gap 0.5)
			(thermal_bridge_width 0.5)
			(island_removal_mode 0)
		)
		(polygon
			(pts
				(arc
					(start 424.342306 -303.585118)
					(mid 423.681906 -303.585118)
					(end 424.342306 -303.585118)
				)
			)
		)
	)
	(zone
		(layers "In1.Cu" "In2.Cu")
		(hatch none 0.5)
		(connect_pads
			(clearance 0)
		)
		(min_thickness 0.25)
		(keepout
			(tracks not_allowed)
			(vias allowed)
			(pads allowed)
			(copperpour not_allowed)
			(footprints allowed)
		)
		(placement
			(enabled no)
			(sheetname "")
		)
		(fill yes
			(thermal_gap 0.5)
			(thermal_bridge_width 0.5)
			(island_removal_mode 0)
		)
		(polygon
			(pts
				(arc
					(start 382.199642 -379.360684)
					(mid 382.219566 -379.36992)
					(end 382.241298 -379.37313)
				)
				(arc
					(start 382.435862 -379.37313)
					(mid 382.489744 -379.350812)
					(end 382.512062 -379.29693)
				)
				(arc
					(start 382.512062 -378.61113)
					(mid 382.489744 -378.557248)
					(end 382.435862 -378.53493)
				)
				(arc
					(start 382.241298 -378.53493)
					(mid 382.219554 -378.538098)
					(end 382.199642 -378.547376)
				)
				(arc
					(start 381.903478 -378.740162)
					(mid 381.861794 -378.752384)
					(end 381.820166 -378.739908)
				)
				(arc
					(start 381.526542 -378.547376)
					(mid 381.506618 -378.53814)
					(end 381.484886 -378.53493)
				)
				(arc
					(start 381.290322 -378.53493)
					(mid 381.23644 -378.557248)
					(end 381.214122 -378.61113)
				)
				(arc
					(start 381.214122 -379.29693)
					(mid 381.23644 -379.350812)
					(end 381.290322 -379.37313)
				)
				(arc
					(start 381.486156 -379.37313)
					(mid 381.5079 -379.369962)
					(end 381.527812 -379.360684)
				)
				(arc
					(start 381.821436 -379.168152)
					(mid 381.863092 -379.15575)
					(end 381.904748 -379.168152)
				)
			)
		)
	)
	(zone
		(layers "In1.Cu" "In2.Cu")
		(hatch none 0.5)
		(connect_pads
			(clearance 0)
		)
		(min_thickness 0.25)
		(keepout
			(tracks not_allowed)
			(vias allowed)
			(pads allowed)
			(copperpour not_allowed)
			(footprints allowed)
		)
		(placement
			(enabled no)
			(sheetname "")
		)
		(fill yes
			(thermal_gap 0.5)
			(thermal_bridge_width 0.5)
			(island_removal_mode 0)
		)
		(polygon
			(pts
				(arc
					(start 288.510218 -213.484968)
					(mid 287.849818 -213.484968)
					(end 288.510218 -213.484968)
				)
			)
		)
	)
	(zone
		(layers "In1.Cu" "In2.Cu")
		(hatch none 0.5)
		(connect_pads
			(clearance 0)
		)
		(min_thickness 0.25)
		(keepout
			(tracks not_allowed)
			(vias allowed)
			(pads allowed)
			(copperpour not_allowed)
			(footprints allowed)
		)
		(placement
			(enabled no)
			(sheetname "")
		)
		(fill yes
			(thermal_gap 0.5)
			(thermal_bridge_width 0.5)
			(island_removal_mode 0)
		)
		(polygon
			(pts
				(arc
					(start 398.188434 -385.11861)
					(mid 398.179198 -385.138534)
					(end 398.175988 -385.160266)
				)
				(arc
					(start 398.175988 -385.35483)
					(mid 398.198306 -385.408712)
					(end 398.252188 -385.43103)
				)
				(arc
					(start 398.937988 -385.43103)
					(mid 398.99187 -385.408712)
					(end 399.014188 -385.35483)
				)
				(arc
					(start 399.014188 -385.160266)
					(mid 399.01102 -385.138522)
					(end 399.001742 -385.11861)
				)
				(arc
					(start 398.808956 -384.822446)
					(mid 398.796734 -384.780762)
					(end 398.80921 -384.739134)
				)
				(arc
					(start 399.001742 -384.44551)
					(mid 399.010978 -384.425586)
					(end 399.014188 -384.403854)
				)
				(arc
					(start 399.014188 -384.20929)
					(mid 398.99187 -384.155408)
					(end 398.937988 -384.13309)
				)
				(arc
					(start 398.252188 -384.13309)
					(mid 398.198306 -384.155408)
					(end 398.175988 -384.20929)
				)
				(arc
					(start 398.175988 -384.405124)
					(mid 398.179156 -384.426868)
					(end 398.188434 -384.44678)
				)
				(arc
					(start 398.380966 -384.740404)
					(mid 398.393368 -384.78206)
					(end 398.380966 -384.823716)
				)
			)
		)
	)
	(zone
		(layers "In1.Cu" "In2.Cu")
		(hatch none 0.5)
		(connect_pads
			(clearance 0)
		)
		(min_thickness 0.25)
		(keepout
			(tracks not_allowed)
			(vias allowed)
			(pads allowed)
			(copperpour not_allowed)
			(footprints allowed)
		)
		(placement
			(enabled no)
			(sheetname "")
		)
		(fill yes
			(thermal_gap 0.5)
			(thermal_bridge_width 0.5)
			(island_removal_mode 0)
		)
		(polygon
			(pts
				(arc
					(start 29.652214 -7.672324)
					(mid 29.674532 -7.618442)
					(end 29.728414 -7.596124)
				)
				(arc
					(start 30.764988 -7.596124)
					(mid 30.81887 -7.618442)
					(end 30.841188 -7.672324)
				)
				(arc
					(start 30.841188 -9.071864)
					(mid 30.81887 -9.125746)
					(end 30.764988 -9.148064)
				)
				(arc
					(start 29.728414 -9.148064)
					(mid 29.674532 -9.125746)
					(end 29.652214 -9.071864)
				)
			)
		)
	)
	(zone
		(layers "In1.Cu" "In2.Cu")
		(hatch none 0.5)
		(connect_pads
			(clearance 0)
		)
		(min_thickness 0.25)
		(keepout
			(tracks not_allowed)
			(vias allowed)
			(pads allowed)
			(copperpour not_allowed)
			(footprints allowed)
		)
		(placement
			(enabled no)
			(sheetname "")
		)
		(fill yes
			(thermal_gap 0.5)
			(thermal_bridge_width 0.5)
			(island_removal_mode 0)
		)
		(polygon
			(pts
				(arc
					(start 194.934332 -318.035432)
					(mid 194.273932 -318.035432)
					(end 194.934332 -318.035432)
				)
			)
		)
	)
	(zone
		(layers "In1.Cu" "In2.Cu")
		(hatch none 0.5)
		(connect_pads
			(clearance 0)
		)
		(min_thickness 0.25)
		(keepout
			(tracks not_allowed)
			(vias allowed)
			(pads allowed)
			(copperpour not_allowed)
			(footprints allowed)
		)
		(placement
			(enabled no)
			(sheetname "")
		)
		(fill yes
			(thermal_gap 0.5)
			(thermal_bridge_width 0.5)
			(island_removal_mode 0)
		)
		(polygon
			(pts
				(arc
					(start 25.482296 -248.335292)
					(mid 24.821896 -248.335292)
					(end 25.482296 -248.335292)
				)
			)
		)
	)
	(zone
		(layers "In1.Cu" "In2.Cu")
		(hatch none 0.5)
		(connect_pads
			(clearance 0)
		)
		(min_thickness 0.25)
		(keepout
			(tracks not_allowed)
			(vias allowed)
			(pads allowed)
			(copperpour not_allowed)
			(footprints allowed)
		)
		(placement
			(enabled no)
			(sheetname "")
		)
		(fill yes
			(thermal_gap 0.5)
			(thermal_bridge_width 0.5)
			(island_removal_mode 0)
		)
		(polygon
			(pts
				(arc
					(start 300.15434 -197.33514)
					(mid 299.49394 -197.33514)
					(end 300.15434 -197.33514)
				)
			)
		)
	)
	(zone
		(layers "In1.Cu" "In2.Cu")
		(hatch none 0.5)
		(connect_pads
			(clearance 0)
		)
		(min_thickness 0.25)
		(keepout
			(tracks not_allowed)
			(vias allowed)
			(pads allowed)
			(copperpour not_allowed)
			(footprints allowed)
		)
		(placement
			(enabled no)
			(sheetname "")
		)
		(fill yes
			(thermal_gap 0.5)
			(thermal_bridge_width 0.5)
			(island_removal_mode 0)
		)
		(polygon
			(pts
				(arc
					(start 33.026096 -312.085228)
					(mid 32.365696 -312.085228)
					(end 33.026096 -312.085228)
				)
			)
		)
	)
	(zone
		(layers "In1.Cu" "In2.Cu")
		(hatch none 0.5)
		(connect_pads
			(clearance 0)
		)
		(min_thickness 0.25)
		(keepout
			(tracks not_allowed)
			(vias allowed)
			(pads allowed)
			(copperpour not_allowed)
			(footprints allowed)
		)
		(placement
			(enabled no)
			(sheetname "")
		)
		(fill yes
			(thermal_gap 0.5)
			(thermal_bridge_width 0.5)
			(island_removal_mode 0)
		)
		(polygon
			(pts
				(arc
					(start 25.482296 -235.585254)
					(mid 24.821896 -235.585254)
					(end 25.482296 -235.585254)
				)
			)
		)
	)
	(zone
		(layers "In1.Cu" "In2.Cu")
		(hatch none 0.5)
		(connect_pads
			(clearance 0)
		)
		(min_thickness 0.25)
		(keepout
			(tracks not_allowed)
			(vias allowed)
			(pads allowed)
			(copperpour not_allowed)
			(footprints allowed)
		)
		(placement
			(enabled no)
			(sheetname "")
		)
		(fill yes
			(thermal_gap 0.5)
			(thermal_bridge_width 0.5)
			(island_removal_mode 0)
		)
		(polygon
			(pts
				(arc
					(start 277.522432 -212.635084)
					(mid 276.862032 -212.635084)
					(end 277.522432 -212.635084)
				)
			)
		)
	)
	(zone
		(layers "In1.Cu" "In2.Cu")
		(hatch none 0.5)
		(connect_pads
			(clearance 0)
		)
		(min_thickness 0.25)
		(keepout
			(tracks not_allowed)
			(vias allowed)
			(pads allowed)
			(copperpour not_allowed)
			(footprints allowed)
		)
		(placement
			(enabled no)
			(sheetname "")
		)
		(fill yes
			(thermal_gap 0.5)
			(thermal_bridge_width 0.5)
			(island_removal_mode 0)
		)
		(polygon
			(pts
				(arc
					(start 44.670218 -228.78542)
					(mid 44.009818 -228.78542)
					(end 44.670218 -228.78542)
				)
			)
		)
	)
	(zone
		(layers "In1.Cu" "In2.Cu")
		(hatch none 0.5)
		(connect_pads
			(clearance 0)
		)
		(min_thickness 0.25)
		(keepout
			(tracks not_allowed)
			(vias allowed)
			(pads allowed)
			(copperpour not_allowed)
			(footprints allowed)
		)
		(placement
			(enabled no)
			(sheetname "")
		)
		(fill yes
			(thermal_gap 0.5)
			(thermal_bridge_width 0.5)
			(island_removal_mode 0)
		)
		(polygon
			(pts
				(arc
					(start 285.066232 -236.435138)
					(mid 284.405832 -236.435138)
					(end 285.066232 -236.435138)
				)
			)
		)
	)
	(zone
		(layers "In1.Cu" "In2.Cu")
		(hatch none 0.5)
		(connect_pads
			(clearance 0)
		)
		(min_thickness 0.25)
		(keepout
			(tracks not_allowed)
			(vias allowed)
			(pads allowed)
			(copperpour not_allowed)
			(footprints allowed)
		)
		(placement
			(enabled no)
			(sheetname "")
		)
		(fill yes
			(thermal_gap 0.5)
			(thermal_bridge_width 0.5)
			(island_removal_mode 0)
		)
		(polygon
			(pts
				(arc
					(start 17.938242 -250.035314)
					(mid 17.277842 -250.035314)
					(end 17.938242 -250.035314)
				)
			)
		)
	)
	(zone
		(layers "In1.Cu" "In2.Cu")
		(hatch none 0.5)
		(connect_pads
			(clearance 0)
		)
		(min_thickness 0.25)
		(keepout
			(tracks not_allowed)
			(vias allowed)
			(pads allowed)
			(copperpour not_allowed)
			(footprints allowed)
		)
		(placement
			(enabled no)
			(sheetname "")
		)
		(fill yes
			(thermal_gap 0.5)
			(thermal_bridge_width 0.5)
			(island_removal_mode 0)
		)
		(polygon
			(pts
				(arc
					(start 194.934332 -229.635304)
					(mid 194.273932 -229.635304)
					(end 194.934332 -229.635304)
				)
			)
		)
	)
	(zone
		(layers "In1.Cu" "In2.Cu")
		(hatch none 0.5)
		(connect_pads
			(clearance 0)
		)
		(min_thickness 0.25)
		(keepout
			(tracks not_allowed)
			(vias allowed)
			(pads allowed)
			(copperpour not_allowed)
			(footprints allowed)
		)
		(placement
			(enabled no)
			(sheetname "")
		)
		(fill yes
			(thermal_gap 0.5)
			(thermal_bridge_width 0.5)
			(island_removal_mode 0)
		)
		(polygon
			(pts
				(arc
					(start 37.126164 -252.58522)
					(mid 36.465764 -252.58522)
					(end 37.126164 -252.58522)
				)
			)
		)
	)
	(zone
		(layers "In1.Cu" "In2.Cu")
		(hatch none 0.5)
		(connect_pads
			(clearance 0)
		)
		(min_thickness 0.25)
		(keepout
			(tracks not_allowed)
			(vias allowed)
			(pads allowed)
			(copperpour not_allowed)
			(footprints allowed)
		)
		(placement
			(enabled no)
			(sheetname "")
		)
		(fill yes
			(thermal_gap 0.5)
			(thermal_bridge_width 0.5)
			(island_removal_mode 0)
		)
		(polygon
			(pts
				(arc
					(start 172.30217 -239.835436)
					(mid 171.64177 -239.835436)
					(end 172.30217 -239.835436)
				)
			)
		)
	)
	(zone
		(layers "In1.Cu" "In2.Cu")
		(hatch none 0.5)
		(connect_pads
			(clearance 0)
		)
		(min_thickness 0.25)
		(keepout
			(tracks not_allowed)
			(vias allowed)
			(pads allowed)
			(copperpour not_allowed)
			(footprints allowed)
		)
		(placement
			(enabled no)
			(sheetname "")
		)
		(fill yes
			(thermal_gap 0.5)
			(thermal_bridge_width 0.5)
			(island_removal_mode 0)
		)
		(polygon
			(pts
				(arc
					(start 17.938242 -222.835216)
					(mid 17.277842 -222.835216)
					(end 17.938242 -222.835216)
				)
			)
		)
	)
	(zone
		(layers "In1.Cu" "In2.Cu")
		(hatch none 0.5)
		(connect_pads
			(clearance 0)
		)
		(min_thickness 0.25)
		(keepout
			(tracks not_allowed)
			(vias allowed)
			(pads allowed)
			(copperpour not_allowed)
			(footprints allowed)
		)
		(placement
			(enabled no)
			(sheetname "")
		)
		(fill yes
			(thermal_gap 0.5)
			(thermal_bridge_width 0.5)
			(island_removal_mode 0)
		)
		(polygon
			(pts
				(arc
					(start 269.978378 -295.085008)
					(mid 269.317978 -295.085008)
					(end 269.978378 -295.085008)
				)
			)
		)
	)
	(zone
		(layers "In1.Cu" "In2.Cu")
		(hatch none 0.5)
		(connect_pads
			(clearance 0)
		)
		(min_thickness 0.25)
		(keepout
			(tracks not_allowed)
			(vias allowed)
			(pads allowed)
			(copperpour not_allowed)
			(footprints allowed)
		)
		(placement
			(enabled no)
			(sheetname "")
		)
		(fill yes
			(thermal_gap 0.5)
			(thermal_bridge_width 0.5)
			(island_removal_mode 0)
		)
		(polygon
			(pts
				(arc
					(start 44.670218 -238.135414)
					(mid 44.009818 -238.135414)
					(end 44.670218 -238.135414)
				)
			)
		)
	)
	(zone
		(layers "In1.Cu" "In2.Cu")
		(hatch none 0.5)
		(connect_pads
			(clearance 0)
		)
		(min_thickness 0.25)
		(keepout
			(tracks not_allowed)
			(vias allowed)
			(pads allowed)
			(copperpour not_allowed)
			(footprints allowed)
		)
		(placement
			(enabled no)
			(sheetname "")
		)
		(fill yes
			(thermal_gap 0.5)
			(thermal_bridge_width 0.5)
			(island_removal_mode 0)
		)
		(polygon
			(pts
				(arc
					(start 59.099704 -370.978684)
					(mid 59.119628 -370.98792)
					(end 59.14136 -370.99113)
				)
				(arc
					(start 59.335924 -370.99113)
					(mid 59.389806 -370.968812)
					(end 59.412124 -370.91493)
				)
				(arc
					(start 59.412124 -370.22913)
					(mid 59.389806 -370.175248)
					(end 59.335924 -370.15293)
				)
				(arc
					(start 59.14136 -370.15293)
					(mid 59.119616 -370.156098)
					(end 59.099704 -370.165376)
				)
				(arc
					(start 58.80354 -370.358162)
					(mid 58.761856 -370.370384)
					(end 58.720228 -370.357908)
				)
				(arc
					(start 58.426604 -370.165376)
					(mid 58.40668 -370.15614)
					(end 58.384948 -370.15293)
				)
				(arc
					(start 58.190384 -370.15293)
					(mid 58.136502 -370.175248)
					(end 58.114184 -370.22913)
				)
				(arc
					(start 58.114184 -370.91493)
					(mid 58.136502 -370.968812)
					(end 58.190384 -370.99113)
				)
				(arc
					(start 58.386218 -370.99113)
					(mid 58.407962 -370.987962)
					(end 58.427874 -370.978684)
				)
				(arc
					(start 58.721498 -370.786152)
					(mid 58.763154 -370.77375)
					(end 58.80481 -370.786152)
				)
			)
		)
	)
	(zone
		(layers "In1.Cu" "In2.Cu")
		(hatch none 0.5)
		(connect_pads
			(clearance 0)
		)
		(min_thickness 0.25)
		(keepout
			(tracks not_allowed)
			(vias allowed)
			(pads allowed)
			(copperpour not_allowed)
			(footprints allowed)
		)
		(placement
			(enabled no)
			(sheetname "")
		)
		(fill yes
			(thermal_gap 0.5)
			(thermal_bridge_width 0.5)
			(island_removal_mode 0)
		)
		(polygon
			(pts
				(arc
					(start 176.402238 -210.085432)
					(mid 175.741838 -210.085432)
					(end 176.402238 -210.085432)
				)
			)
		)
	)
	(zone
		(layers "In1.Cu" "In2.Cu")
		(hatch none 0.5)
		(connect_pads
			(clearance 0)
		)
		(min_thickness 0.25)
		(keepout
			(tracks not_allowed)
			(vias allowed)
			(pads allowed)
			(copperpour not_allowed)
			(footprints allowed)
		)
		(placement
			(enabled no)
			(sheetname "")
		)
		(fill yes
			(thermal_gap 0.5)
			(thermal_bridge_width 0.5)
			(island_removal_mode 0)
		)
		(polygon
			(pts
				(arc
					(start 277.522432 -292.535102)
					(mid 276.862032 -292.535102)
					(end 277.522432 -292.535102)
				)
			)
		)
	)
	(zone
		(layers "In1.Cu" "In2.Cu")
		(hatch none 0.5)
		(connect_pads
			(clearance 0)
		)
		(min_thickness 0.25)
		(keepout
			(tracks not_allowed)
			(vias allowed)
			(pads allowed)
			(copperpour not_allowed)
			(footprints allowed)
		)
		(placement
			(enabled no)
			(sheetname "")
		)
		(fill yes
			(thermal_gap 0.5)
			(thermal_bridge_width 0.5)
			(island_removal_mode 0)
		)
		(polygon
			(pts
				(arc
					(start 439.430414 -242.385088)
					(mid 438.770014 -242.385088)
					(end 439.430414 -242.385088)
				)
			)
		)
	)
	(zone
		(layers "In1.Cu" "In2.Cu")
		(hatch none 0.5)
		(connect_pads
			(clearance 0)
		)
		(min_thickness 0.25)
		(keepout
			(tracks not_allowed)
			(vias allowed)
			(pads allowed)
			(copperpour not_allowed)
			(footprints allowed)
		)
		(placement
			(enabled no)
			(sheetname "")
		)
		(fill yes
			(thermal_gap 0.5)
			(thermal_bridge_width 0.5)
			(island_removal_mode 0)
		)
		(polygon
			(pts
				(arc
					(start 269.978378 -238.985044)
					(mid 269.317978 -238.985044)
					(end 269.978378 -238.985044)
				)
			)
		)
	)
	(zone
		(layers "In1.Cu" "In2.Cu")
		(hatch none 0.5)
		(connect_pads
			(clearance 0)
		)
		(min_thickness 0.25)
		(keepout
			(tracks not_allowed)
			(vias allowed)
			(pads allowed)
			(copperpour not_allowed)
			(footprints allowed)
		)
		(placement
			(enabled no)
			(sheetname "")
		)
		(fill yes
			(thermal_gap 0.5)
			(thermal_bridge_width 0.5)
			(island_removal_mode 0)
		)
		(polygon
			(pts
				(arc
					(start 288.510218 -209.23504)
					(mid 287.849818 -209.23504)
					(end 288.510218 -209.23504)
				)
			)
		)
	)
	(zone
		(layers "In1.Cu" "In2.Cu")
		(hatch none 0.5)
		(connect_pads
			(clearance 0)
		)
		(min_thickness 0.25)
		(keepout
			(tracks not_allowed)
			(vias allowed)
			(pads allowed)
			(copperpour not_allowed)
			(footprints allowed)
		)
		(placement
			(enabled no)
			(sheetname "")
		)
		(fill yes
			(thermal_gap 0.5)
			(thermal_bridge_width 0.5)
			(island_removal_mode 0)
		)
		(polygon
			(pts
				(arc
					(start 285.066232 -298.485052)
					(mid 284.405832 -298.485052)
					(end 285.066232 -298.485052)
				)
			)
		)
	)
	(zone
		(layers "In1.Cu" "In2.Cu")
		(hatch none 0.5)
		(connect_pads
			(clearance 0)
		)
		(min_thickness 0.25)
		(keepout
			(tracks not_allowed)
			(vias allowed)
			(pads allowed)
			(copperpour not_allowed)
			(footprints allowed)
		)
		(placement
			(enabled no)
			(sheetname "")
		)
		(fill yes
			(thermal_gap 0.5)
			(thermal_bridge_width 0.5)
			(island_removal_mode 0)
		)
		(polygon
			(pts
				(arc
					(start 454.518268 -313.784996)
					(mid 453.857868 -313.784996)
					(end 454.518268 -313.784996)
				)
			)
		)
	)
	(zone
		(layers "In1.Cu" "In2.Cu")
		(hatch none 0.5)
		(connect_pads
			(clearance 0)
		)
		(min_thickness 0.25)
		(keepout
			(tracks not_allowed)
			(vias allowed)
			(pads allowed)
			(copperpour not_allowed)
			(footprints allowed)
		)
		(placement
			(enabled no)
			(sheetname "")
		)
		(fill yes
			(thermal_gap 0.5)
			(thermal_bridge_width 0.5)
			(island_removal_mode 0)
		)
		(polygon
			(pts
				(arc
					(start 25.482296 -220.28531)
					(mid 24.821896 -220.28531)
					(end 25.482296 -220.28531)
				)
			)
		)
	)
	(zone
		(layers "In1.Cu" "In2.Cu")
		(hatch none 0.5)
		(connect_pads
			(clearance 0)
		)
		(min_thickness 0.25)
		(keepout
			(tracks not_allowed)
			(vias allowed)
			(pads allowed)
			(copperpour not_allowed)
			(footprints allowed)
		)
		(placement
			(enabled no)
			(sheetname "")
		)
		(fill yes
			(thermal_gap 0.5)
			(thermal_bridge_width 0.5)
			(island_removal_mode 0)
		)
		(polygon
			(pts
				(arc
					(start 420.242238 -210.935062)
					(mid 419.581838 -210.935062)
					(end 420.242238 -210.935062)
				)
			)
		)
	)
	(zone
		(layers "In1.Cu" "In2.Cu")
		(hatch none 0.5)
		(connect_pads
			(clearance 0)
		)
		(min_thickness 0.25)
		(keepout
			(tracks not_allowed)
			(vias allowed)
			(pads allowed)
			(copperpour not_allowed)
			(footprints allowed)
		)
		(placement
			(enabled no)
			(sheetname "")
		)
		(fill yes
			(thermal_gap 0.5)
			(thermal_bridge_width 0.5)
			(island_removal_mode 0)
		)
		(polygon
			(pts
				(arc
					(start 183.946292 -254.285242)
					(mid 183.285892 -254.285242)
					(end 183.946292 -254.285242)
				)
			)
		)
	)
	(zone
		(layers "In1.Cu" "In2.Cu")
		(hatch none 0.5)
		(connect_pads
			(clearance 0)
		)
		(min_thickness 0.25)
		(keepout
			(tracks not_allowed)
			(vias allowed)
			(pads allowed)
			(copperpour not_allowed)
			(footprints allowed)
		)
		(placement
			(enabled no)
			(sheetname "")
		)
		(fill yes
			(thermal_gap 0.5)
			(thermal_bridge_width 0.5)
			(island_removal_mode 0)
		)
		(polygon
			(pts
				(arc
					(start 44.670218 -229.635304)
					(mid 44.009818 -229.635304)
					(end 44.670218 -229.635304)
				)
			)
		)
	)
	(zone
		(layers "In1.Cu" "In2.Cu")
		(hatch none 0.5)
		(connect_pads
			(clearance 0)
		)
		(min_thickness 0.25)
		(keepout
			(tracks not_allowed)
			(vias allowed)
			(pads allowed)
			(copperpour not_allowed)
			(footprints allowed)
		)
		(placement
			(enabled no)
			(sheetname "")
		)
		(fill yes
			(thermal_gap 0.5)
			(thermal_bridge_width 0.5)
			(island_removal_mode 0)
		)
		(polygon
			(pts
				(arc
					(start 424.472354 -7.672324)
					(mid 424.494672 -7.618442)
					(end 424.548554 -7.596124)
				)
				(arc
					(start 425.585128 -7.596124)
					(mid 425.63901 -7.618442)
					(end 425.661328 -7.672324)
				)
				(arc
					(start 425.661328 -9.071864)
					(mid 425.63901 -9.125746)
					(end 425.585128 -9.148064)
				)
				(arc
					(start 424.548554 -9.148064)
					(mid 424.494672 -9.125746)
					(end 424.472354 -9.071864)
				)
			)
		)
	)
	(zone
		(layers "In1.Cu" "In2.Cu")
		(hatch none 0.5)
		(connect_pads
			(clearance 0)
		)
		(min_thickness 0.25)
		(keepout
			(tracks not_allowed)
			(vias allowed)
			(pads allowed)
			(copperpour not_allowed)
			(footprints allowed)
		)
		(placement
			(enabled no)
			(sheetname "")
		)
		(fill yes
			(thermal_gap 0.5)
			(thermal_bridge_width 0.5)
			(island_removal_mode 0)
		)
		(polygon
			(pts
				(arc
					(start 33.026096 -211.7852)
					(mid 32.365696 -211.7852)
					(end 33.026096 -211.7852)
				)
			)
		)
	)
	(zone
		(layers "In1.Cu" "In2.Cu")
		(hatch none 0.5)
		(connect_pads
			(clearance 0)
		)
		(min_thickness 0.25)
		(keepout
			(tracks not_allowed)
			(vias allowed)
			(pads allowed)
			(copperpour not_allowed)
			(footprints allowed)
		)
		(placement
			(enabled no)
			(sheetname "")
		)
		(fill yes
			(thermal_gap 0.5)
			(thermal_bridge_width 0.5)
			(island_removal_mode 0)
		)
		(polygon
			(pts
				(arc
					(start 52.214272 -254.285242)
					(mid 51.553872 -254.285242)
					(end 52.214272 -254.285242)
				)
			)
		)
	)
	(zone
		(layers "In1.Cu" "In2.Cu")
		(hatch none 0.5)
		(connect_pads
			(clearance 0)
		)
		(min_thickness 0.25)
		(keepout
			(tracks not_allowed)
			(vias allowed)
			(pads allowed)
			(copperpour not_allowed)
			(footprints allowed)
		)
		(placement
			(enabled no)
			(sheetname "")
		)
		(fill yes
			(thermal_gap 0.5)
			(thermal_bridge_width 0.5)
			(island_removal_mode 0)
		)
		(polygon
			(pts
				(arc
					(start 191.490346 -294.235378)
					(mid 190.829946 -294.235378)
					(end 191.490346 -294.235378)
				)
			)
		)
	)
	(zone
		(layers "In1.Cu" "In2.Cu")
		(hatch none 0.5)
		(connect_pads
			(clearance 0)
		)
		(min_thickness 0.25)
		(keepout
			(tracks not_allowed)
			(vias allowed)
			(pads allowed)
			(copperpour not_allowed)
			(footprints allowed)
		)
		(placement
			(enabled no)
			(sheetname "")
		)
		(fill yes
			(thermal_gap 0.5)
			(thermal_bridge_width 0.5)
			(island_removal_mode 0)
		)
		(polygon
			(pts
				(arc
					(start 431.88636 -210.085178)
					(mid 431.22596 -210.085178)
					(end 431.88636 -210.085178)
				)
			)
		)
	)
	(zone
		(layers "In1.Cu" "In2.Cu")
		(hatch none 0.5)
		(connect_pads
			(clearance 0)
		)
		(min_thickness 0.25)
		(keepout
			(tracks not_allowed)
			(vias allowed)
			(pads allowed)
			(copperpour not_allowed)
			(footprints allowed)
		)
		(placement
			(enabled no)
			(sheetname "")
		)
		(fill yes
			(thermal_gap 0.5)
			(thermal_bridge_width 0.5)
			(island_removal_mode 0)
		)
		(polygon
			(pts
				(arc
					(start 22.03831 -289.135312)
					(mid 21.37791 -289.135312)
					(end 22.03831 -289.135312)
				)
			)
		)
	)
	(zone
		(layers "In1.Cu" "In2.Cu")
		(hatch none 0.5)
		(connect_pads
			(clearance 0)
		)
		(min_thickness 0.25)
		(keepout
			(tracks not_allowed)
			(vias allowed)
			(pads allowed)
			(copperpour not_allowed)
			(footprints allowed)
		)
		(placement
			(enabled no)
			(sheetname "")
		)
		(fill yes
			(thermal_gap 0.5)
			(thermal_bridge_width 0.5)
			(island_removal_mode 0)
		)
		(polygon
			(pts
				(arc
					(start 22.03831 -216.035382)
					(mid 21.37791 -216.035382)
					(end 22.03831 -216.035382)
				)
			)
		)
	)
	(zone
		(layers "In1.Cu" "In2.Cu")
		(hatch none 0.5)
		(connect_pads
			(clearance 0)
		)
		(min_thickness 0.25)
		(keepout
			(tracks not_allowed)
			(vias allowed)
			(pads allowed)
			(copperpour not_allowed)
			(footprints allowed)
		)
		(placement
			(enabled no)
			(sheetname "")
		)
		(fill yes
			(thermal_gap 0.5)
			(thermal_bridge_width 0.5)
			(island_removal_mode 0)
		)
		(polygon
			(pts
				(arc
					(start 300.15434 -306.135024)
					(mid 299.49394 -306.135024)
					(end 300.15434 -306.135024)
				)
			)
		)
	)
	(zone
		(layers "In1.Cu" "In2.Cu")
		(hatch none 0.5)
		(connect_pads
			(clearance 0)
		)
		(min_thickness 0.25)
		(keepout
			(tracks not_allowed)
			(vias allowed)
			(pads allowed)
			(copperpour not_allowed)
			(footprints allowed)
		)
		(placement
			(enabled no)
			(sheetname "")
		)
		(fill yes
			(thermal_gap 0.5)
			(thermal_bridge_width 0.5)
			(island_removal_mode 0)
		)
		(polygon
			(pts
				(arc
					(start 424.342306 -252.584966)
					(mid 423.681906 -252.584966)
					(end 424.342306 -252.584966)
				)
			)
		)
	)
	(zone
		(layers "In1.Cu" "In2.Cu")
		(hatch none 0.5)
		(connect_pads
			(clearance 0)
		)
		(min_thickness 0.25)
		(keepout
			(tracks not_allowed)
			(vias allowed)
			(pads allowed)
			(copperpour not_allowed)
			(footprints allowed)
		)
		(placement
			(enabled no)
			(sheetname "")
		)
		(fill yes
			(thermal_gap 0.5)
			(thermal_bridge_width 0.5)
			(island_removal_mode 0)
		)
		(polygon
			(pts
				(arc
					(start 177.832258 -50.058828)
					(mid 177.88614 -50.081146)
					(end 177.908458 -50.135028)
				)
				(arc
					(start 177.908458 -50.9651)
					(mid 177.88614 -51.018982)
					(end 177.832258 -51.0413)
				)
				(arc
					(start 176.384458 -51.0413)
					(mid 176.330576 -51.018982)
					(end 176.308258 -50.9651)
				)
				(arc
					(start 176.308258 -50.135028)
					(mid 176.330576 -50.081146)
					(end 176.384458 -50.058828)
				)
			)
		)
	)
	(zone
		(layers "In1.Cu" "In2.Cu")
		(hatch none 0.5)
		(connect_pads
			(clearance 0)
		)
		(min_thickness 0.25)
		(keepout
			(tracks not_allowed)
			(vias allowed)
			(pads allowed)
			(copperpour not_allowed)
			(footprints allowed)
		)
		(placement
			(enabled no)
			(sheetname "")
		)
		(fill yes
			(thermal_gap 0.5)
			(thermal_bridge_width 0.5)
			(island_removal_mode 0)
		)
		(polygon
			(pts
				(arc
					(start 435.330346 -201.585068)
					(mid 434.669946 -201.585068)
					(end 435.330346 -201.585068)
				)
			)
		)
	)
	(zone
		(layers "In1.Cu" "In2.Cu")
		(hatch none 0.5)
		(connect_pads
			(clearance 0)
		)
		(min_thickness 0.25)
		(keepout
			(tracks not_allowed)
			(vias allowed)
			(pads allowed)
			(copperpour not_allowed)
			(footprints allowed)
		)
		(placement
			(enabled no)
			(sheetname "")
		)
		(fill yes
			(thermal_gap 0.5)
			(thermal_bridge_width 0.5)
			(island_removal_mode 0)
		)
		(polygon
			(pts
				(arc
					(start 285.066232 -303.585118)
					(mid 284.405832 -303.585118)
					(end 285.066232 -303.585118)
				)
			)
		)
	)
	(zone
		(layers "In1.Cu" "In2.Cu")
		(hatch none 0.5)
		(connect_pads
			(clearance 0)
		)
		(min_thickness 0.25)
		(keepout
			(tracks not_allowed)
			(vias allowed)
			(pads allowed)
			(copperpour not_allowed)
			(footprints allowed)
		)
		(placement
			(enabled no)
			(sheetname "")
		)
		(fill yes
			(thermal_gap 0.5)
			(thermal_bridge_width 0.5)
			(island_removal_mode 0)
		)
		(polygon
			(pts
				(arc
					(start 187.390278 -304.435256)
					(mid 186.729878 -304.435256)
					(end 187.390278 -304.435256)
				)
			)
		)
	)
	(zone
		(layers "In1.Cu" "In2.Cu")
		(hatch none 0.5)
		(connect_pads
			(clearance 0)
		)
		(min_thickness 0.25)
		(keepout
			(tracks not_allowed)
			(vias allowed)
			(pads allowed)
			(copperpour not_allowed)
			(footprints allowed)
		)
		(placement
			(enabled no)
			(sheetname "")
		)
		(fill yes
			(thermal_gap 0.5)
			(thermal_bridge_width 0.5)
			(island_removal_mode 0)
		)
		(polygon
			(pts
				(arc
					(start 183.946292 -244.08511)
					(mid 183.285892 -244.08511)
					(end 183.946292 -244.08511)
				)
			)
		)
	)
	(zone
		(layers "In1.Cu" "In2.Cu")
		(hatch none 0.5)
		(connect_pads
			(clearance 0)
		)
		(min_thickness 0.25)
		(keepout
			(tracks not_allowed)
			(vias allowed)
			(pads allowed)
			(copperpour not_allowed)
			(footprints allowed)
		)
		(placement
			(enabled no)
			(sheetname "")
		)
		(fill yes
			(thermal_gap 0.5)
			(thermal_bridge_width 0.5)
			(island_removal_mode 0)
		)
		(polygon
			(pts
				(arc
					(start 96.732852 -373.442484)
					(mid 96.752776 -373.45172)
					(end 96.774508 -373.45493)
				)
				(arc
					(start 96.969072 -373.45493)
					(mid 97.022954 -373.432612)
					(end 97.045272 -373.37873)
				)
				(arc
					(start 97.045272 -372.69293)
					(mid 97.022954 -372.639048)
					(end 96.969072 -372.61673)
				)
				(arc
					(start 96.774508 -372.61673)
					(mid 96.752764 -372.619898)
					(end 96.732852 -372.629176)
				)
				(arc
					(start 96.436688 -372.821962)
					(mid 96.395004 -372.834184)
					(end 96.353376 -372.821708)
				)
				(arc
					(start 96.059752 -372.629176)
					(mid 96.039828 -372.61994)
					(end 96.018096 -372.61673)
				)
				(arc
					(start 95.823532 -372.61673)
					(mid 95.76965 -372.639048)
					(end 95.747332 -372.69293)
				)
				(arc
					(start 95.747332 -373.37873)
					(mid 95.76965 -373.432612)
					(end 95.823532 -373.45493)
				)
				(arc
					(start 96.019366 -373.45493)
					(mid 96.04111 -373.451762)
					(end 96.061022 -373.442484)
				)
				(arc
					(start 96.354646 -373.249952)
					(mid 96.396302 -373.23755)
					(end 96.437958 -373.249952)
				)
			)
		)
	)
	(zone
		(layers "In1.Cu" "In2.Cu")
		(hatch none 0.5)
		(connect_pads
			(clearance 0)
		)
		(min_thickness 0.25)
		(keepout
			(tracks not_allowed)
			(vias allowed)
			(pads allowed)
			(copperpour not_allowed)
			(footprints allowed)
		)
		(placement
			(enabled no)
			(sheetname "")
		)
		(fill yes
			(thermal_gap 0.5)
			(thermal_bridge_width 0.5)
			(island_removal_mode 0)
		)
		(polygon
			(pts
				(arc
					(start 300.15434 -201.585068)
					(mid 299.49394 -201.585068)
					(end 300.15434 -201.585068)
				)
			)
		)
	)
	(zone
		(layers "In1.Cu" "In2.Cu")
		(hatch none 0.5)
		(connect_pads
			(clearance 0)
		)
		(min_thickness 0.25)
		(keepout
			(tracks not_allowed)
			(vias allowed)
			(pads allowed)
			(copperpour not_allowed)
			(footprints allowed)
		)
		(placement
			(enabled no)
			(sheetname "")
		)
		(fill yes
			(thermal_gap 0.5)
			(thermal_bridge_width 0.5)
			(island_removal_mode 0)
		)
		(polygon
			(pts
				(arc
					(start 202.478132 -289.98545)
					(mid 201.817732 -289.98545)
					(end 202.478132 -289.98545)
				)
			)
		)
	)
	(zone
		(layers "In1.Cu" "In2.Cu")
		(hatch none 0.5)
		(connect_pads
			(clearance 0)
		)
		(min_thickness 0.25)
		(keepout
			(tracks not_allowed)
			(vias allowed)
			(pads allowed)
			(copperpour not_allowed)
			(footprints allowed)
		)
		(placement
			(enabled no)
			(sheetname "")
		)
		(fill yes
			(thermal_gap 0.5)
			(thermal_bridge_width 0.5)
			(island_removal_mode 0)
		)
		(polygon
			(pts
				(arc
					(start 269.978378 -317.18504)
					(mid 269.317978 -317.18504)
					(end 269.978378 -317.18504)
				)
			)
		)
	)
	(zone
		(layers "In1.Cu" "In2.Cu")
		(hatch none 0.5)
		(connect_pads
			(clearance 0)
		)
		(min_thickness 0.25)
		(keepout
			(tracks not_allowed)
			(vias allowed)
			(pads allowed)
			(copperpour not_allowed)
			(footprints allowed)
		)
		(placement
			(enabled no)
			(sheetname "")
		)
		(fill yes
			(thermal_gap 0.5)
			(thermal_bridge_width 0.5)
			(island_removal_mode 0)
		)
		(polygon
			(pts
				(arc
					(start 285.066232 -216.035128)
					(mid 284.405832 -216.035128)
					(end 285.066232 -216.035128)
				)
			)
		)
	)
	(zone
		(layers "In1.Cu" "In2.Cu")
		(hatch none 0.5)
		(connect_pads
			(clearance 0)
		)
		(min_thickness 0.25)
		(keepout
			(tracks not_allowed)
			(vias allowed)
			(pads allowed)
			(copperpour not_allowed)
			(footprints allowed)
		)
		(placement
			(enabled no)
			(sheetname "")
		)
		(fill yes
			(thermal_gap 0.5)
			(thermal_bridge_width 0.5)
			(island_removal_mode 0)
		)
		(polygon
			(pts
				(arc
					(start 65.956434 -408.860244)
					(mid 65.978752 -408.914126)
					(end 66.032634 -408.936444)
				)
				(arc
					(start 66.228214 -408.936444)
					(mid 66.25009 -408.933312)
					(end 66.270124 -408.923998)
				)
				(arc
					(start 66.563748 -408.731466)
					(mid 66.605404 -408.719064)
					(end 66.64706 -408.731466)
				)
				(arc
					(start 66.941954 -408.923998)
					(mid 66.961878 -408.933234)
					(end 66.98361 -408.936444)
				)
				(arc
					(start 67.178174 -408.936444)
					(mid 67.232056 -408.914126)
					(end 67.254374 -408.860244)
				)
				(arc
					(start 67.254374 -408.174444)
					(mid 67.232056 -408.120562)
					(end 67.178174 -408.098244)
				)
				(arc
					(start 66.98361 -408.098244)
					(mid 66.961866 -408.101412)
					(end 66.941954 -408.11069)
				)
				(arc
					(start 66.64579 -408.303476)
					(mid 66.604106 -408.315698)
					(end 66.562478 -408.303222)
				)
				(arc
					(start 66.268854 -408.11069)
					(mid 66.24893 -408.101454)
					(end 66.227198 -408.098244)
				)
				(arc
					(start 66.032634 -408.098244)
					(mid 65.978752 -408.120562)
					(end 65.956434 -408.174444)
				)
			)
		)
	)
	(zone
		(layers "In1.Cu" "In2.Cu")
		(hatch none 0.5)
		(connect_pads
			(clearance 0)
		)
		(min_thickness 0.25)
		(keepout
			(tracks not_allowed)
			(vias allowed)
			(pads allowed)
			(copperpour not_allowed)
			(footprints allowed)
		)
		(placement
			(enabled no)
			(sheetname "")
		)
		(fill yes
			(thermal_gap 0.5)
			(thermal_bridge_width 0.5)
			(island_removal_mode 0)
		)
		(polygon
			(pts
				(arc
					(start 269.978378 -281.485086)
					(mid 269.317978 -281.485086)
					(end 269.978378 -281.485086)
				)
			)
		)
	)
	(zone
		(layers "In1.Cu" "In2.Cu")
		(hatch none 0.5)
		(connect_pads
			(clearance 0)
		)
		(min_thickness 0.25)
		(keepout
			(tracks not_allowed)
			(vias allowed)
			(pads allowed)
			(copperpour not_allowed)
			(footprints allowed)
		)
		(placement
			(enabled no)
			(sheetname "")
		)
		(fill yes
			(thermal_gap 0.5)
			(thermal_bridge_width 0.5)
			(island_removal_mode 0)
		)
		(polygon
			(pts
				(arc
					(start 269.978378 -220.285056)
					(mid 269.317978 -220.285056)
					(end 269.978378 -220.285056)
				)
			)
		)
	)
	(zone
		(layers "In1.Cu" "In2.Cu")
		(hatch none 0.5)
		(connect_pads
			(clearance 0)
		)
		(min_thickness 0.25)
		(keepout
			(tracks not_allowed)
			(vias allowed)
			(pads allowed)
			(copperpour not_allowed)
			(footprints allowed)
		)
		(placement
			(enabled no)
			(sheetname "")
		)
		(fill yes
			(thermal_gap 0.5)
			(thermal_bridge_width 0.5)
			(island_removal_mode 0)
		)
		(polygon
			(pts
				(arc
					(start 280.966164 -293.384986)
					(mid 280.305764 -293.384986)
					(end 280.966164 -293.384986)
				)
			)
		)
	)
	(zone
		(layers "In1.Cu" "In2.Cu")
		(hatch none 0.5)
		(connect_pads
			(clearance 0)
		)
		(min_thickness 0.25)
		(keepout
			(tracks not_allowed)
			(vias allowed)
			(pads allowed)
			(copperpour not_allowed)
			(footprints allowed)
		)
		(placement
			(enabled no)
			(sheetname "")
		)
		(fill yes
			(thermal_gap 0.5)
			(thermal_bridge_width 0.5)
			(island_removal_mode 0)
		)
		(polygon
			(pts
				(arc
					(start 48.114204 -261.935214)
					(mid 47.453804 -261.935214)
					(end 48.114204 -261.935214)
				)
			)
		)
	)
	(zone
		(layers "In1.Cu" "In2.Cu")
		(hatch none 0.5)
		(connect_pads
			(clearance 0)
		)
		(min_thickness 0.25)
		(keepout
			(tracks not_allowed)
			(vias allowed)
			(pads allowed)
			(copperpour not_allowed)
			(footprints allowed)
		)
		(placement
			(enabled no)
			(sheetname "")
		)
		(fill yes
			(thermal_gap 0.5)
			(thermal_bridge_width 0.5)
			(island_removal_mode 0)
		)
		(polygon
			(pts
				(arc
					(start 187.390278 -308.685438)
					(mid 186.729878 -308.685438)
					(end 187.390278 -308.685438)
				)
			)
		)
	)
	(zone
		(layers "In1.Cu" "In2.Cu")
		(hatch none 0.5)
		(connect_pads
			(clearance 0)
		)
		(min_thickness 0.25)
		(keepout
			(tracks not_allowed)
			(vias allowed)
			(pads allowed)
			(copperpour not_allowed)
			(footprints allowed)
		)
		(placement
			(enabled no)
			(sheetname "")
		)
		(fill yes
			(thermal_gap 0.5)
			(thermal_bridge_width 0.5)
			(island_removal_mode 0)
		)
		(polygon
			(pts
				(arc
					(start 269.978378 -298.485052)
					(mid 269.317978 -298.485052)
					(end 269.978378 -298.485052)
				)
			)
		)
	)
	(zone
		(layers "In1.Cu" "In2.Cu")
		(hatch none 0.5)
		(connect_pads
			(clearance 0)
		)
		(min_thickness 0.25)
		(keepout
			(tracks not_allowed)
			(vias allowed)
			(pads allowed)
			(copperpour not_allowed)
			(footprints allowed)
		)
		(placement
			(enabled no)
			(sheetname "")
		)
		(fill yes
			(thermal_gap 0.5)
			(thermal_bridge_width 0.5)
			(island_removal_mode 0)
		)
		(polygon
			(pts
				(arc
					(start 446.974468 -300.185074)
					(mid 446.314068 -300.185074)
					(end 446.974468 -300.185074)
				)
			)
		)
	)
	(zone
		(layers "In1.Cu" "In2.Cu")
		(hatch none 0.5)
		(connect_pads
			(clearance 0)
		)
		(min_thickness 0.25)
		(keepout
			(tracks not_allowed)
			(vias allowed)
			(pads allowed)
			(copperpour not_allowed)
			(footprints allowed)
		)
		(placement
			(enabled no)
			(sheetname "")
		)
		(fill yes
			(thermal_gap 0.5)
			(thermal_bridge_width 0.5)
			(island_removal_mode 0)
		)
		(polygon
			(pts
				(arc
					(start 431.88636 -272.135092)
					(mid 431.22596 -272.135092)
					(end 431.88636 -272.135092)
				)
			)
		)
	)
	(zone
		(layers "In1.Cu" "In2.Cu")
		(hatch none 0.5)
		(connect_pads
			(clearance 0)
		)
		(min_thickness 0.25)
		(keepout
			(tracks not_allowed)
			(vias allowed)
			(pads allowed)
			(copperpour not_allowed)
			(footprints allowed)
		)
		(placement
			(enabled no)
			(sheetname "")
		)
		(fill yes
			(thermal_gap 0.5)
			(thermal_bridge_width 0.5)
			(island_removal_mode 0)
		)
		(polygon
			(pts
				(arc
					(start 285.066232 -301.885096)
					(mid 284.405832 -301.885096)
					(end 285.066232 -301.885096)
				)
			)
		)
	)
	(zone
		(layers "In1.Cu" "In2.Cu")
		(hatch none 0.5)
		(connect_pads
			(clearance 0)
		)
		(min_thickness 0.25)
		(keepout
			(tracks not_allowed)
			(vias allowed)
			(pads allowed)
			(copperpour not_allowed)
			(footprints allowed)
		)
		(placement
			(enabled no)
			(sheetname "")
		)
		(fill yes
			(thermal_gap 0.5)
			(thermal_bridge_width 0.5)
			(island_removal_mode 0)
		)
		(polygon
			(pts
				(arc
					(start 29.582364 -238.985298)
					(mid 28.921964 -238.985298)
					(end 29.582364 -238.985298)
				)
			)
		)
	)
	(zone
		(layers "In1.Cu" "In2.Cu")
		(hatch none 0.5)
		(connect_pads
			(clearance 0)
		)
		(min_thickness 0.25)
		(keepout
			(tracks not_allowed)
			(vias allowed)
			(pads allowed)
			(copperpour not_allowed)
			(footprints allowed)
		)
		(placement
			(enabled no)
			(sheetname "")
		)
		(fill yes
			(thermal_gap 0.5)
			(thermal_bridge_width 0.5)
			(island_removal_mode 0)
		)
		(polygon
			(pts
				(arc
					(start 25.482296 -286.585406)
					(mid 24.821896 -286.585406)
					(end 25.482296 -286.585406)
				)
			)
		)
	)
	(zone
		(layers "In1.Cu" "In2.Cu")
		(hatch none 0.5)
		(connect_pads
			(clearance 0)
		)
		(min_thickness 0.25)
		(keepout
			(tracks not_allowed)
			(vias allowed)
			(pads allowed)
			(copperpour not_allowed)
			(footprints allowed)
		)
		(placement
			(enabled no)
			(sheetname "")
		)
		(fill yes
			(thermal_gap 0.5)
			(thermal_bridge_width 0.5)
			(island_removal_mode 0)
		)
		(polygon
			(pts
				(arc
					(start 202.478132 -295.9354)
					(mid 201.817732 -295.9354)
					(end 202.478132 -295.9354)
				)
			)
		)
	)
	(zone
		(layers "In1.Cu" "In2.Cu")
		(hatch none 0.5)
		(connect_pads
			(clearance 0)
		)
		(min_thickness 0.25)
		(keepout
			(tracks not_allowed)
			(vias allowed)
			(pads allowed)
			(copperpour not_allowed)
			(footprints allowed)
		)
		(placement
			(enabled no)
			(sheetname "")
		)
		(fill yes
			(thermal_gap 0.5)
			(thermal_bridge_width 0.5)
			(island_removal_mode 0)
		)
		(polygon
			(pts
				(arc
					(start 442.8744 -308.685184)
					(mid 442.214 -308.685184)
					(end 442.8744 -308.685184)
				)
			)
		)
	)
	(zone
		(layers "In1.Cu" "In2.Cu")
		(hatch none 0.5)
		(connect_pads
			(clearance 0)
		)
		(min_thickness 0.25)
		(keepout
			(tracks not_allowed)
			(vias allowed)
			(pads allowed)
			(copperpour not_allowed)
			(footprints allowed)
		)
		(placement
			(enabled no)
			(sheetname "")
		)
		(fill yes
			(thermal_gap 0.5)
			(thermal_bridge_width 0.5)
			(island_removal_mode 0)
		)
		(polygon
			(pts
				(arc
					(start 40.57015 -207.535272)
					(mid 39.90975 -207.535272)
					(end 40.57015 -207.535272)
				)
			)
		)
	)
	(zone
		(layers "In1.Cu" "In2.Cu")
		(hatch none 0.5)
		(connect_pads
			(clearance 0)
		)
		(min_thickness 0.25)
		(keepout
			(tracks not_allowed)
			(vias allowed)
			(pads allowed)
			(copperpour not_allowed)
			(footprints allowed)
		)
		(placement
			(enabled no)
			(sheetname "")
		)
		(fill yes
			(thermal_gap 0.5)
			(thermal_bridge_width 0.5)
			(island_removal_mode 0)
		)
		(polygon
			(pts
				(arc
					(start 48.114204 -246.63527)
					(mid 47.453804 -246.63527)
					(end 48.114204 -246.63527)
				)
			)
		)
	)
	(zone
		(layers "In1.Cu" "In2.Cu")
		(hatch none 0.5)
		(connect_pads
			(clearance 0)
		)
		(min_thickness 0.25)
		(keepout
			(tracks not_allowed)
			(vias allowed)
			(pads allowed)
			(copperpour not_allowed)
			(footprints allowed)
		)
		(placement
			(enabled no)
			(sheetname "")
		)
		(fill yes
			(thermal_gap 0.5)
			(thermal_bridge_width 0.5)
			(island_removal_mode 0)
		)
		(polygon
			(pts
				(arc
					(start 309.703216 -417.242244)
					(mid 309.725534 -417.296126)
					(end 309.779416 -417.318444)
				)
				(arc
					(start 309.974996 -417.318444)
					(mid 309.996872 -417.315312)
					(end 310.016906 -417.305998)
				)
				(arc
					(start 310.31053 -417.113466)
					(mid 310.352186 -417.101064)
					(end 310.393842 -417.113466)
				)
				(arc
					(start 310.688736 -417.305998)
					(mid 310.70866 -417.315234)
					(end 310.730392 -417.318444)
				)
				(arc
					(start 310.924956 -417.318444)
					(mid 310.978838 -417.296126)
					(end 311.001156 -417.242244)
				)
				(arc
					(start 311.001156 -416.556444)
					(mid 310.978838 -416.502562)
					(end 310.924956 -416.480244)
				)
				(arc
					(start 310.730392 -416.480244)
					(mid 310.708648 -416.483412)
					(end 310.688736 -416.49269)
				)
				(arc
					(start 310.392572 -416.685476)
					(mid 310.350888 -416.697698)
					(end 310.30926 -416.685222)
				)
				(arc
					(start 310.015636 -416.49269)
					(mid 309.995712 -416.483454)
					(end 309.97398 -416.480244)
				)
				(arc
					(start 309.779416 -416.480244)
					(mid 309.725534 -416.502562)
					(end 309.703216 -416.556444)
				)
			)
		)
	)
	(zone
		(layers "In1.Cu" "In2.Cu")
		(hatch none 0.5)
		(connect_pads
			(clearance 0)
		)
		(min_thickness 0.25)
		(keepout
			(tracks not_allowed)
			(vias allowed)
			(pads allowed)
			(copperpour not_allowed)
			(footprints allowed)
		)
		(placement
			(enabled no)
			(sheetname "")
		)
		(fill yes
			(thermal_gap 0.5)
			(thermal_bridge_width 0.5)
			(island_removal_mode 0)
		)
		(polygon
			(pts
				(arc
					(start 424.342306 -234.735116)
					(mid 423.681906 -234.735116)
					(end 424.342306 -234.735116)
				)
			)
		)
	)
	(zone
		(layers "In1.Cu" "In2.Cu")
		(hatch none 0.5)
		(connect_pads
			(clearance 0)
		)
		(min_thickness 0.25)
		(keepout
			(tracks not_allowed)
			(vias allowed)
			(pads allowed)
			(copperpour not_allowed)
			(footprints allowed)
		)
		(placement
			(enabled no)
			(sheetname "")
		)
		(fill yes
			(thermal_gap 0.5)
			(thermal_bridge_width 0.5)
			(island_removal_mode 0)
		)
		(polygon
			(pts
				(arc
					(start 172.30217 -235.585254)
					(mid 171.64177 -235.585254)
					(end 172.30217 -235.585254)
				)
			)
		)
	)
	(zone
		(layers "In1.Cu" "In2.Cu")
		(hatch none 0.5)
		(connect_pads
			(clearance 0)
		)
		(min_thickness 0.25)
		(keepout
			(tracks not_allowed)
			(vias allowed)
			(pads allowed)
			(copperpour not_allowed)
			(footprints allowed)
		)
		(placement
			(enabled no)
			(sheetname "")
		)
		(fill yes
			(thermal_gap 0.5)
			(thermal_bridge_width 0.5)
			(island_removal_mode 0)
		)
		(polygon
			(pts
				(arc
					(start 439.430414 -208.385156)
					(mid 438.770014 -208.385156)
					(end 439.430414 -208.385156)
				)
			)
		)
	)
	(zone
		(layers "In1.Cu" "In2.Cu")
		(hatch none 0.5)
		(connect_pads
			(clearance 0)
		)
		(min_thickness 0.25)
		(keepout
			(tracks not_allowed)
			(vias allowed)
			(pads allowed)
			(copperpour not_allowed)
			(footprints allowed)
		)
		(placement
			(enabled no)
			(sheetname "")
		)
		(fill yes
			(thermal_gap 0.5)
			(thermal_bridge_width 0.5)
			(island_removal_mode 0)
		)
		(polygon
			(pts
				(arc
					(start 292.610286 -304.435002)
					(mid 291.949886 -304.435002)
					(end 292.610286 -304.435002)
				)
			)
		)
	)
	(zone
		(layers "In1.Cu" "In2.Cu")
		(hatch none 0.5)
		(connect_pads
			(clearance 0)
		)
		(min_thickness 0.25)
		(keepout
			(tracks not_allowed)
			(vias allowed)
			(pads allowed)
			(copperpour not_allowed)
			(footprints allowed)
		)
		(placement
			(enabled no)
			(sheetname "")
		)
		(fill yes
			(thermal_gap 0.5)
			(thermal_bridge_width 0.5)
			(island_removal_mode 0)
		)
		(polygon
			(pts
				(arc
					(start 176.402238 -247.485408)
					(mid 175.741838 -247.485408)
					(end 176.402238 -247.485408)
				)
			)
		)
	)
	(zone
		(layers "In1.Cu" "In2.Cu")
		(hatch none 0.5)
		(connect_pads
			(clearance 0)
		)
		(min_thickness 0.25)
		(keepout
			(tracks not_allowed)
			(vias allowed)
			(pads allowed)
			(copperpour not_allowed)
			(footprints allowed)
		)
		(placement
			(enabled no)
			(sheetname "")
		)
		(fill yes
			(thermal_gap 0.5)
			(thermal_bridge_width 0.5)
			(island_removal_mode 0)
		)
		(polygon
			(pts
				(arc
					(start 44.670218 -269.58544)
					(mid 44.009818 -269.58544)
					(end 44.670218 -269.58544)
				)
			)
		)
	)
	(zone
		(layers "In1.Cu" "In2.Cu")
		(hatch none 0.5)
		(connect_pads
			(clearance 0)
		)
		(min_thickness 0.25)
		(keepout
			(tracks not_allowed)
			(vias allowed)
			(pads allowed)
			(copperpour not_allowed)
			(footprints allowed)
		)
		(placement
			(enabled no)
			(sheetname "")
		)
		(fill yes
			(thermal_gap 0.5)
			(thermal_bridge_width 0.5)
			(island_removal_mode 0)
		)
		(polygon
			(pts
				(arc
					(start 424.342306 -295.085008)
					(mid 423.681906 -295.085008)
					(end 424.342306 -295.085008)
				)
			)
		)
	)
	(zone
		(layers "In1.Cu" "In2.Cu")
		(hatch none 0.5)
		(connect_pads
			(clearance 0)
		)
		(min_thickness 0.25)
		(keepout
			(tracks not_allowed)
			(vias allowed)
			(pads allowed)
			(copperpour not_allowed)
			(footprints allowed)
		)
		(placement
			(enabled no)
			(sheetname "")
		)
		(fill yes
			(thermal_gap 0.5)
			(thermal_bridge_width 0.5)
			(island_removal_mode 0)
		)
		(polygon
			(pts
				(arc
					(start 191.490346 -307.8353)
					(mid 190.829946 -307.8353)
					(end 191.490346 -307.8353)
				)
			)
		)
	)
	(zone
		(layers "In1.Cu" "In2.Cu")
		(hatch none 0.5)
		(connect_pads
			(clearance 0)
		)
		(min_thickness 0.25)
		(keepout
			(tracks not_allowed)
			(vias allowed)
			(pads allowed)
			(copperpour not_allowed)
			(footprints allowed)
		)
		(placement
			(enabled no)
			(sheetname "")
		)
		(fill yes
			(thermal_gap 0.5)
			(thermal_bridge_width 0.5)
			(island_removal_mode 0)
		)
		(polygon
			(pts
				(arc
					(start 446.974468 -220.285056)
					(mid 446.314068 -220.285056)
					(end 446.974468 -220.285056)
				)
			)
		)
	)
	(zone
		(layers "In1.Cu" "In2.Cu")
		(hatch none 0.5)
		(connect_pads
			(clearance 0)
		)
		(min_thickness 0.25)
		(keepout
			(tracks not_allowed)
			(vias allowed)
			(pads allowed)
			(copperpour not_allowed)
			(footprints allowed)
		)
		(placement
			(enabled no)
			(sheetname "")
		)
		(fill yes
			(thermal_gap 0.5)
			(thermal_bridge_width 0.5)
			(island_removal_mode 0)
		)
		(polygon
			(pts
				(arc
					(start 40.57015 -227.935282)
					(mid 39.90975 -227.935282)
					(end 40.57015 -227.935282)
				)
			)
		)
	)
	(zone
		(layers "In1.Cu" "In2.Cu")
		(hatch none 0.5)
		(connect_pads
			(clearance 0)
		)
		(min_thickness 0.25)
		(keepout
			(tracks not_allowed)
			(vias allowed)
			(pads allowed)
			(copperpour not_allowed)
			(footprints allowed)
		)
		(placement
			(enabled no)
			(sheetname "")
		)
		(fill yes
			(thermal_gap 0.5)
			(thermal_bridge_width 0.5)
			(island_removal_mode 0)
		)
		(polygon
			(pts
				(arc
					(start 37.126164 -290.835334)
					(mid 36.465764 -290.835334)
					(end 37.126164 -290.835334)
				)
			)
		)
	)
	(zone
		(layers "In1.Cu" "In2.Cu")
		(hatch none 0.5)
		(connect_pads
			(clearance 0)
		)
		(min_thickness 0.25)
		(keepout
			(tracks not_allowed)
			(vias allowed)
			(pads allowed)
			(copperpour not_allowed)
			(footprints allowed)
		)
		(placement
			(enabled no)
			(sheetname "")
		)
		(fill yes
			(thermal_gap 0.5)
			(thermal_bridge_width 0.5)
			(island_removal_mode 0)
		)
		(polygon
			(pts
				(arc
					(start 172.30217 -286.585406)
					(mid 171.64177 -286.585406)
					(end 172.30217 -286.585406)
				)
			)
		)
	)
	(zone
		(layers "In1.Cu" "In2.Cu")
		(hatch none 0.5)
		(connect_pads
			(clearance 0)
		)
		(min_thickness 0.25)
		(keepout
			(tracks not_allowed)
			(vias allowed)
			(pads allowed)
			(copperpour not_allowed)
			(footprints allowed)
		)
		(placement
			(enabled no)
			(sheetname "")
		)
		(fill yes
			(thermal_gap 0.5)
			(thermal_bridge_width 0.5)
			(island_removal_mode 0)
		)
		(polygon
			(pts
				(arc
					(start 232.558844 -57.272936)
					(mid 232.612726 -57.295254)
					(end 232.635044 -57.349136)
				)
				(arc
					(start 232.635044 -58.380884)
					(mid 232.612726 -58.434766)
					(end 232.558844 -58.457084)
				)
				(arc
					(start 231.441244 -58.457084)
					(mid 231.387362 -58.434766)
					(end 231.365044 -58.380884)
				)
				(arc
					(start 231.365044 -57.349136)
					(mid 231.387362 -57.295254)
					(end 231.441244 -57.272936)
				)
			)
		)
	)
	(zone
		(layers "In1.Cu" "In2.Cu")
		(hatch none 0.5)
		(connect_pads
			(clearance 0)
		)
		(min_thickness 0.25)
		(keepout
			(tracks not_allowed)
			(vias allowed)
			(pads allowed)
			(copperpour not_allowed)
			(footprints allowed)
		)
		(placement
			(enabled no)
			(sheetname "")
		)
		(fill yes
			(thermal_gap 0.5)
			(thermal_bridge_width 0.5)
			(island_removal_mode 0)
		)
		(polygon
			(pts
				(arc
					(start 439.430414 -284.88513)
					(mid 438.770014 -284.88513)
					(end 439.430414 -284.88513)
				)
			)
		)
	)
	(zone
		(layers "In1.Cu" "In2.Cu")
		(hatch none 0.5)
		(connect_pads
			(clearance 0)
		)
		(min_thickness 0.25)
		(keepout
			(tracks not_allowed)
			(vias allowed)
			(pads allowed)
			(copperpour not_allowed)
			(footprints allowed)
		)
		(placement
			(enabled no)
			(sheetname "")
		)
		(fill yes
			(thermal_gap 0.5)
			(thermal_bridge_width 0.5)
			(island_removal_mode 0)
		)
		(polygon
			(pts
				(arc
					(start 446.974468 -233.035094)
					(mid 446.314068 -233.035094)
					(end 446.974468 -233.035094)
				)
			)
		)
	)
	(zone
		(layers "In1.Cu" "In2.Cu")
		(hatch none 0.5)
		(connect_pads
			(clearance 0)
		)
		(min_thickness 0.25)
		(keepout
			(tracks not_allowed)
			(vias allowed)
			(pads allowed)
			(copperpour not_allowed)
			(footprints allowed)
		)
		(placement
			(enabled no)
			(sheetname "")
		)
		(fill yes
			(thermal_gap 0.5)
			(thermal_bridge_width 0.5)
			(island_removal_mode 0)
		)
		(polygon
			(pts
				(arc
					(start 427.786292 -318.035178)
					(mid 427.125892 -318.035178)
					(end 427.786292 -318.035178)
				)
			)
		)
	)
	(zone
		(layers "In1.Cu" "In2.Cu")
		(hatch none 0.5)
		(connect_pads
			(clearance 0)
		)
		(min_thickness 0.25)
		(keepout
			(tracks not_allowed)
			(vias allowed)
			(pads allowed)
			(copperpour not_allowed)
			(footprints allowed)
		)
		(placement
			(enabled no)
			(sheetname "")
		)
		(fill yes
			(thermal_gap 0.5)
			(thermal_bridge_width 0.5)
			(island_removal_mode 0)
		)
		(polygon
			(pts
				(arc
					(start 442.8744 -253.435104)
					(mid 442.214 -253.435104)
					(end 442.8744 -253.435104)
				)
			)
		)
	)
	(zone
		(layers "In1.Cu" "In2.Cu")
		(hatch none 0.5)
		(connect_pads
			(clearance 0)
		)
		(min_thickness 0.25)
		(keepout
			(tracks not_allowed)
			(vias allowed)
			(pads allowed)
			(copperpour not_allowed)
			(footprints allowed)
		)
		(placement
			(enabled no)
			(sheetname "")
		)
		(fill yes
			(thermal_gap 0.5)
			(thermal_bridge_width 0.5)
			(island_removal_mode 0)
		)
		(polygon
			(pts
				(arc
					(start 431.88636 -292.535102)
					(mid 431.22596 -292.535102)
					(end 431.88636 -292.535102)
				)
			)
		)
	)
	(zone
		(layers "In1.Cu" "In2.Cu")
		(hatch none 0.5)
		(connect_pads
			(clearance 0)
		)
		(min_thickness 0.25)
		(keepout
			(tracks not_allowed)
			(vias allowed)
			(pads allowed)
			(copperpour not_allowed)
			(footprints allowed)
		)
		(placement
			(enabled no)
			(sheetname "")
		)
		(fill yes
			(thermal_gap 0.5)
			(thermal_bridge_width 0.5)
			(island_removal_mode 0)
		)
		(polygon
			(pts
				(arc
					(start 292.610286 -220.285056)
					(mid 291.949886 -220.285056)
					(end 292.610286 -220.285056)
				)
			)
		)
	)
	(zone
		(layers "In1.Cu" "In2.Cu")
		(hatch none 0.5)
		(connect_pads
			(clearance 0)
		)
		(min_thickness 0.25)
		(keepout
			(tracks not_allowed)
			(vias allowed)
			(pads allowed)
			(copperpour not_allowed)
			(footprints allowed)
		)
		(placement
			(enabled no)
			(sheetname "")
		)
		(fill yes
			(thermal_gap 0.5)
			(thermal_bridge_width 0.5)
			(island_removal_mode 0)
		)
		(polygon
			(pts
				(arc
					(start 48.114204 -222.835216)
					(mid 47.453804 -222.835216)
					(end 48.114204 -222.835216)
				)
			)
		)
	)
	(zone
		(layers "In1.Cu" "In2.Cu")
		(hatch none 0.5)
		(connect_pads
			(clearance 0)
		)
		(min_thickness 0.25)
		(keepout
			(tracks not_allowed)
			(vias allowed)
			(pads allowed)
			(copperpour not_allowed)
			(footprints allowed)
		)
		(placement
			(enabled no)
			(sheetname "")
		)
		(fill yes
			(thermal_gap 0.5)
			(thermal_bridge_width 0.5)
			(island_removal_mode 0)
		)
		(polygon
			(pts
				(arc
					(start 29.582364 -231.335326)
					(mid 28.921964 -231.335326)
					(end 29.582364 -231.335326)
				)
			)
		)
	)
	(zone
		(layers "In1.Cu" "In2.Cu")
		(hatch none 0.5)
		(connect_pads
			(clearance 0)
		)
		(min_thickness 0.25)
		(keepout
			(tracks not_allowed)
			(vias allowed)
			(pads allowed)
			(copperpour not_allowed)
			(footprints allowed)
		)
		(placement
			(enabled no)
			(sheetname "")
		)
		(fill yes
			(thermal_gap 0.5)
			(thermal_bridge_width 0.5)
			(island_removal_mode 0)
		)
		(polygon
			(pts
				(arc
					(start 33.026096 -204.135228)
					(mid 32.365696 -204.135228)
					(end 33.026096 -204.135228)
				)
			)
		)
	)
	(zone
		(layers "In1.Cu" "In2.Cu")
		(hatch none 0.5)
		(connect_pads
			(clearance 0)
		)
		(min_thickness 0.25)
		(keepout
			(tracks not_allowed)
			(vias allowed)
			(pads allowed)
			(copperpour not_allowed)
			(footprints allowed)
		)
		(placement
			(enabled no)
			(sheetname "")
		)
		(fill yes
			(thermal_gap 0.5)
			(thermal_bridge_width 0.5)
			(island_removal_mode 0)
		)
		(polygon
			(pts
				(arc
					(start 17.938242 -286.585406)
					(mid 17.277842 -286.585406)
					(end 17.938242 -286.585406)
				)
			)
		)
	)
	(zone
		(layers "In1.Cu" "In2.Cu")
		(hatch none 0.5)
		(connect_pads
			(clearance 0)
		)
		(min_thickness 0.25)
		(keepout
			(tracks not_allowed)
			(vias allowed)
			(pads allowed)
			(copperpour not_allowed)
			(footprints allowed)
		)
		(placement
			(enabled no)
			(sheetname "")
		)
		(fill yes
			(thermal_gap 0.5)
			(thermal_bridge_width 0.5)
			(island_removal_mode 0)
		)
		(polygon
			(pts
				(arc
					(start 202.478132 -198.185278)
					(mid 201.817732 -198.185278)
					(end 202.478132 -198.185278)
				)
			)
		)
	)
	(zone
		(layers "In1.Cu" "In2.Cu")
		(hatch none 0.5)
		(connect_pads
			(clearance 0)
		)
		(min_thickness 0.25)
		(keepout
			(tracks not_allowed)
			(vias allowed)
			(pads allowed)
			(copperpour not_allowed)
			(footprints allowed)
		)
		(placement
			(enabled no)
			(sheetname "")
		)
		(fill yes
			(thermal_gap 0.5)
			(thermal_bridge_width 0.5)
			(island_removal_mode 0)
		)
		(polygon
			(pts
				(arc
					(start 273.422364 -229.63505)
					(mid 272.761964 -229.63505)
					(end 273.422364 -229.63505)
				)
			)
		)
	)
	(zone
		(layers "In1.Cu" "In2.Cu")
		(hatch none 0.5)
		(connect_pads
			(clearance 0)
		)
		(min_thickness 0.25)
		(keepout
			(tracks not_allowed)
			(vias allowed)
			(pads allowed)
			(copperpour not_allowed)
			(footprints allowed)
		)
		(placement
			(enabled no)
			(sheetname "")
		)
		(fill yes
			(thermal_gap 0.5)
			(thermal_bridge_width 0.5)
			(island_removal_mode 0)
		)
		(polygon
			(pts
				(arc
					(start 285.066232 -304.435002)
					(mid 284.405832 -304.435002)
					(end 285.066232 -304.435002)
				)
			)
		)
	)
	(zone
		(layers "In1.Cu" "In2.Cu")
		(hatch none 0.5)
		(connect_pads
			(clearance 0)
		)
		(min_thickness 0.25)
		(keepout
			(tracks not_allowed)
			(vias allowed)
			(pads allowed)
			(copperpour not_allowed)
			(footprints allowed)
		)
		(placement
			(enabled no)
			(sheetname "")
		)
		(fill yes
			(thermal_gap 0.5)
			(thermal_bridge_width 0.5)
			(island_removal_mode 0)
		)
		(polygon
			(pts
				(arc
					(start 450.4182 -310.384952)
					(mid 449.7578 -310.384952)
					(end 450.4182 -310.384952)
				)
			)
		)
	)
	(zone
		(layers "In1.Cu" "In2.Cu")
		(hatch none 0.5)
		(connect_pads
			(clearance 0)
		)
		(min_thickness 0.25)
		(keepout
			(tracks not_allowed)
			(vias allowed)
			(pads allowed)
			(copperpour not_allowed)
			(footprints allowed)
		)
		(placement
			(enabled no)
			(sheetname "")
		)
		(fill yes
			(thermal_gap 0.5)
			(thermal_bridge_width 0.5)
			(island_removal_mode 0)
		)
		(polygon
			(pts
				(arc
					(start 37.126164 -223.685354)
					(mid 36.465764 -223.685354)
					(end 37.126164 -223.685354)
				)
			)
		)
	)
	(zone
		(layers "In1.Cu" "In2.Cu")
		(hatch none 0.5)
		(connect_pads
			(clearance 0)
		)
		(min_thickness 0.25)
		(keepout
			(tracks not_allowed)
			(vias allowed)
			(pads allowed)
			(copperpour not_allowed)
			(footprints allowed)
		)
		(placement
			(enabled no)
			(sheetname "")
		)
		(fill yes
			(thermal_gap 0.5)
			(thermal_bridge_width 0.5)
			(island_removal_mode 0)
		)
		(polygon
			(pts
				(arc
					(start 29.582364 -307.8353)
					(mid 28.921964 -307.8353)
					(end 29.582364 -307.8353)
				)
			)
		)
	)
	(zone
		(layers "In1.Cu" "In2.Cu")
		(hatch none 0.5)
		(connect_pads
			(clearance 0)
		)
		(min_thickness 0.25)
		(keepout
			(tracks not_allowed)
			(vias allowed)
			(pads allowed)
			(copperpour not_allowed)
			(footprints allowed)
		)
		(placement
			(enabled no)
			(sheetname "")
		)
		(fill yes
			(thermal_gap 0.5)
			(thermal_bridge_width 0.5)
			(island_removal_mode 0)
		)
		(polygon
			(pts
				(arc
					(start 183.946292 -245.785386)
					(mid 183.285892 -245.785386)
					(end 183.946292 -245.785386)
				)
			)
		)
	)
	(zone
		(layers "In1.Cu" "In2.Cu")
		(hatch none 0.5)
		(connect_pads
			(clearance 0)
		)
		(min_thickness 0.25)
		(keepout
			(tracks not_allowed)
			(vias allowed)
			(pads allowed)
			(copperpour not_allowed)
			(footprints allowed)
		)
		(placement
			(enabled no)
			(sheetname "")
		)
		(fill yes
			(thermal_gap 0.5)
			(thermal_bridge_width 0.5)
			(island_removal_mode 0)
		)
		(polygon
			(pts
				(arc
					(start 42.560748 -382.27381)
					(mid 42.551512 -382.293734)
					(end 42.548302 -382.315466)
				)
				(arc
					(start 42.548302 -382.51003)
					(mid 42.57062 -382.563912)
					(end 42.624502 -382.58623)
				)
				(arc
					(start 43.310302 -382.58623)
					(mid 43.364184 -382.563912)
					(end 43.386502 -382.51003)
				)
				(arc
					(start 43.386502 -382.315466)
					(mid 43.383334 -382.293722)
					(end 43.374056 -382.27381)
				)
				(arc
					(start 43.18127 -381.977646)
					(mid 43.169048 -381.935962)
					(end 43.181524 -381.894334)
				)
				(arc
					(start 43.374056 -381.60071)
					(mid 43.383292 -381.580786)
					(end 43.386502 -381.559054)
				)
				(arc
					(start 43.386502 -381.36449)
					(mid 43.364184 -381.310608)
					(end 43.310302 -381.28829)
				)
				(arc
					(start 42.624502 -381.28829)
					(mid 42.57062 -381.310608)
					(end 42.548302 -381.36449)
				)
				(arc
					(start 42.548302 -381.560324)
					(mid 42.55147 -381.582068)
					(end 42.560748 -381.60198)
				)
				(arc
					(start 42.75328 -381.895604)
					(mid 42.765682 -381.93726)
					(end 42.75328 -381.978916)
				)
			)
		)
	)
	(zone
		(layers "In1.Cu" "In2.Cu")
		(hatch none 0.5)
		(connect_pads
			(clearance 0)
		)
		(min_thickness 0.25)
		(keepout
			(tracks not_allowed)
			(vias allowed)
			(pads allowed)
			(copperpour not_allowed)
			(footprints allowed)
		)
		(placement
			(enabled no)
			(sheetname "")
		)
		(fill yes
			(thermal_gap 0.5)
			(thermal_bridge_width 0.5)
			(island_removal_mode 0)
		)
		(polygon
			(pts
				(arc
					(start 280.966164 -229.63505)
					(mid 280.305764 -229.63505)
					(end 280.966164 -229.63505)
				)
			)
		)
	)
	(zone
		(layers "In1.Cu" "In2.Cu")
		(hatch none 0.5)
		(connect_pads
			(clearance 0)
		)
		(min_thickness 0.25)
		(keepout
			(tracks not_allowed)
			(vias allowed)
			(pads allowed)
			(copperpour not_allowed)
			(footprints allowed)
		)
		(placement
			(enabled no)
			(sheetname "")
		)
		(fill yes
			(thermal_gap 0.5)
			(thermal_bridge_width 0.5)
			(island_removal_mode 0)
		)
		(polygon
			(pts
				(arc
					(start 435.330346 -237.285022)
					(mid 434.669946 -237.285022)
					(end 435.330346 -237.285022)
				)
			)
		)
	)
	(zone
		(layers "In1.Cu" "In2.Cu")
		(hatch none 0.5)
		(connect_pads
			(clearance 0)
		)
		(min_thickness 0.25)
		(keepout
			(tracks not_allowed)
			(vias allowed)
			(pads allowed)
			(copperpour not_allowed)
			(footprints allowed)
		)
		(placement
			(enabled no)
			(sheetname "")
		)
		(fill yes
			(thermal_gap 0.5)
			(thermal_bridge_width 0.5)
			(island_removal_mode 0)
		)
		(polygon
			(pts
				(arc
					(start 202.478132 -263.635236)
					(mid 201.817732 -263.635236)
					(end 202.478132 -263.635236)
				)
			)
		)
	)
	(zone
		(layers "In1.Cu" "In2.Cu")
		(hatch none 0.5)
		(connect_pads
			(clearance 0)
		)
		(min_thickness 0.25)
		(keepout
			(tracks not_allowed)
			(vias allowed)
			(pads allowed)
			(copperpour not_allowed)
			(footprints allowed)
		)
		(placement
			(enabled no)
			(sheetname "")
		)
		(fill yes
			(thermal_gap 0.5)
			(thermal_bridge_width 0.5)
			(island_removal_mode 0)
		)
		(polygon
			(pts
				(arc
					(start 446.974468 -214.335106)
					(mid 446.314068 -214.335106)
					(end 446.974468 -214.335106)
				)
			)
		)
	)
	(zone
		(layers "In1.Cu" "In2.Cu")
		(hatch none 0.5)
		(connect_pads
			(clearance 0)
		)
		(min_thickness 0.25)
		(keepout
			(tracks not_allowed)
			(vias allowed)
			(pads allowed)
			(copperpour not_allowed)
			(footprints allowed)
		)
		(placement
			(enabled no)
			(sheetname "")
		)
		(fill yes
			(thermal_gap 0.5)
			(thermal_bridge_width 0.5)
			(island_removal_mode 0)
		)
		(polygon
			(pts
				(arc
					(start 136.119616 -408.860244)
					(mid 136.141934 -408.914126)
					(end 136.195816 -408.936444)
				)
				(arc
					(start 136.391396 -408.936444)
					(mid 136.413272 -408.933312)
					(end 136.433306 -408.923998)
				)
				(arc
					(start 136.72693 -408.731466)
					(mid 136.768586 -408.719064)
					(end 136.810242 -408.731466)
				)
				(arc
					(start 137.105136 -408.923998)
					(mid 137.12506 -408.933234)
					(end 137.146792 -408.936444)
				)
				(arc
					(start 137.341356 -408.936444)
					(mid 137.395238 -408.914126)
					(end 137.417556 -408.860244)
				)
				(arc
					(start 137.417556 -408.174444)
					(mid 137.395238 -408.120562)
					(end 137.341356 -408.098244)
				)
				(arc
					(start 137.146792 -408.098244)
					(mid 137.125048 -408.101412)
					(end 137.105136 -408.11069)
				)
				(arc
					(start 136.808972 -408.303476)
					(mid 136.767288 -408.315698)
					(end 136.72566 -408.303222)
				)
				(arc
					(start 136.432036 -408.11069)
					(mid 136.412112 -408.101454)
					(end 136.39038 -408.098244)
				)
				(arc
					(start 136.195816 -408.098244)
					(mid 136.141934 -408.120562)
					(end 136.119616 -408.174444)
				)
			)
		)
	)
	(zone
		(layers "In1.Cu" "In2.Cu")
		(hatch none 0.5)
		(connect_pads
			(clearance 0)
		)
		(min_thickness 0.25)
		(keepout
			(tracks not_allowed)
			(vias allowed)
			(pads allowed)
			(copperpour not_allowed)
			(footprints allowed)
		)
		(placement
			(enabled no)
			(sheetname "")
		)
		(fill yes
			(thermal_gap 0.5)
			(thermal_bridge_width 0.5)
			(island_removal_mode 0)
		)
		(polygon
			(pts
				(arc
					(start 33.026096 -289.98545)
					(mid 32.365696 -289.98545)
					(end 33.026096 -289.98545)
				)
			)
		)
	)
	(zone
		(layers "In1.Cu" "In2.Cu")
		(hatch none 0.5)
		(connect_pads
			(clearance 0)
		)
		(min_thickness 0.25)
		(keepout
			(tracks not_allowed)
			(vias allowed)
			(pads allowed)
			(copperpour not_allowed)
			(footprints allowed)
		)
		(placement
			(enabled no)
			(sheetname "")
		)
		(fill yes
			(thermal_gap 0.5)
			(thermal_bridge_width 0.5)
			(island_removal_mode 0)
		)
		(polygon
			(pts
				(arc
					(start 52.214272 -317.185294)
					(mid 51.553872 -317.185294)
					(end 52.214272 -317.185294)
				)
			)
		)
	)
	(zone
		(layers "In1.Cu" "In2.Cu")
		(hatch none 0.5)
		(connect_pads
			(clearance 0)
		)
		(min_thickness 0.25)
		(keepout
			(tracks not_allowed)
			(vias allowed)
			(pads allowed)
			(copperpour not_allowed)
			(footprints allowed)
		)
		(placement
			(enabled no)
			(sheetname "")
		)
		(fill yes
			(thermal_gap 0.5)
			(thermal_bridge_width 0.5)
			(island_removal_mode 0)
		)
		(polygon
			(pts
				(arc
					(start 435.330346 -224.534984)
					(mid 434.669946 -224.534984)
					(end 435.330346 -224.534984)
				)
			)
		)
	)
	(zone
		(layers "In1.Cu" "In2.Cu")
		(hatch none 0.5)
		(connect_pads
			(clearance 0)
		)
		(min_thickness 0.25)
		(keepout
			(tracks not_allowed)
			(vias allowed)
			(pads allowed)
			(copperpour not_allowed)
			(footprints allowed)
		)
		(placement
			(enabled no)
			(sheetname "")
		)
		(fill yes
			(thermal_gap 0.5)
			(thermal_bridge_width 0.5)
			(island_removal_mode 0)
		)
		(polygon
			(pts
				(arc
					(start 17.938242 -241.535204)
					(mid 17.277842 -241.535204)
					(end 17.938242 -241.535204)
				)
			)
		)
	)
	(zone
		(layers "In1.Cu" "In2.Cu")
		(hatch none 0.5)
		(connect_pads
			(clearance 0)
		)
		(min_thickness 0.25)
		(keepout
			(tracks not_allowed)
			(vias allowed)
			(pads allowed)
			(copperpour not_allowed)
			(footprints allowed)
		)
		(placement
			(enabled no)
			(sheetname "")
		)
		(fill yes
			(thermal_gap 0.5)
			(thermal_bridge_width 0.5)
			(island_removal_mode 0)
		)
		(polygon
			(pts
				(arc
					(start 280.966164 -263.634982)
					(mid 280.305764 -263.634982)
					(end 280.966164 -263.634982)
				)
			)
		)
	)
	(zone
		(layers "In1.Cu" "In2.Cu")
		(hatch none 0.5)
		(connect_pads
			(clearance 0)
		)
		(min_thickness 0.25)
		(keepout
			(tracks not_allowed)
			(vias allowed)
			(pads allowed)
			(copperpour not_allowed)
			(footprints allowed)
		)
		(placement
			(enabled no)
			(sheetname "")
		)
		(fill yes
			(thermal_gap 0.5)
			(thermal_bridge_width 0.5)
			(island_removal_mode 0)
		)
		(polygon
			(pts
				(arc
					(start 424.342306 -231.335072)
					(mid 423.681906 -231.335072)
					(end 424.342306 -231.335072)
				)
			)
		)
	)
	(zone
		(layers "In1.Cu" "In2.Cu")
		(hatch none 0.5)
		(connect_pads
			(clearance 0)
		)
		(min_thickness 0.25)
		(keepout
			(tracks not_allowed)
			(vias allowed)
			(pads allowed)
			(copperpour not_allowed)
			(footprints allowed)
		)
		(placement
			(enabled no)
			(sheetname "")
		)
		(fill yes
			(thermal_gap 0.5)
			(thermal_bridge_width 0.5)
			(island_removal_mode 0)
		)
		(polygon
			(pts
				(arc
					(start 194.934332 -204.135228)
					(mid 194.273932 -204.135228)
					(end 194.934332 -204.135228)
				)
			)
		)
	)
	(zone
		(layers "In1.Cu" "In2.Cu")
		(hatch none 0.5)
		(connect_pads
			(clearance 0)
		)
		(min_thickness 0.25)
		(keepout
			(tracks not_allowed)
			(vias allowed)
			(pads allowed)
			(copperpour not_allowed)
			(footprints allowed)
		)
		(placement
			(enabled no)
			(sheetname "")
		)
		(fill yes
			(thermal_gap 0.5)
			(thermal_bridge_width 0.5)
			(island_removal_mode 0)
		)
		(polygon
			(pts
				(arc
					(start 446.974468 -249.185176)
					(mid 446.314068 -249.185176)
					(end 446.974468 -249.185176)
				)
			)
		)
	)
	(zone
		(layers "In1.Cu" "In2.Cu")
		(hatch none 0.5)
		(connect_pads
			(clearance 0)
		)
		(min_thickness 0.25)
		(keepout
			(tracks not_allowed)
			(vias allowed)
			(pads allowed)
			(copperpour not_allowed)
			(footprints allowed)
		)
		(placement
			(enabled no)
			(sheetname "")
		)
		(fill yes
			(thermal_gap 0.5)
			(thermal_bridge_width 0.5)
			(island_removal_mode 0)
		)
		(polygon
			(pts
				(arc
					(start 277.522432 -262.785098)
					(mid 276.862032 -262.785098)
					(end 277.522432 -262.785098)
				)
			)
		)
	)
	(zone
		(layers "In1.Cu" "In2.Cu")
		(hatch none 0.5)
		(connect_pads
			(clearance 0)
		)
		(min_thickness 0.25)
		(keepout
			(tracks not_allowed)
			(vias allowed)
			(pads allowed)
			(copperpour not_allowed)
			(footprints allowed)
		)
		(placement
			(enabled no)
			(sheetname "")
		)
		(fill yes
			(thermal_gap 0.5)
			(thermal_bridge_width 0.5)
			(island_removal_mode 0)
		)
		(polygon
			(pts
				(arc
					(start 288.510218 -254.284988)
					(mid 287.849818 -254.284988)
					(end 288.510218 -254.284988)
				)
			)
		)
	)
	(zone
		(layers "In1.Cu" "In2.Cu")
		(hatch none 0.5)
		(connect_pads
			(clearance 0)
		)
		(min_thickness 0.25)
		(keepout
			(tracks not_allowed)
			(vias allowed)
			(pads allowed)
			(copperpour not_allowed)
			(footprints allowed)
		)
		(placement
			(enabled no)
			(sheetname "")
		)
		(fill yes
			(thermal_gap 0.5)
			(thermal_bridge_width 0.5)
			(island_removal_mode 0)
		)
		(polygon
			(pts
				(arc
					(start 439.430414 -312.935112)
					(mid 438.770014 -312.935112)
					(end 439.430414 -312.935112)
				)
			)
		)
	)
	(zone
		(layers "In1.Cu" "In2.Cu")
		(hatch none 0.5)
		(connect_pads
			(clearance 0)
		)
		(min_thickness 0.25)
		(keepout
			(tracks not_allowed)
			(vias allowed)
			(pads allowed)
			(copperpour not_allowed)
			(footprints allowed)
		)
		(placement
			(enabled no)
			(sheetname "")
		)
		(fill yes
			(thermal_gap 0.5)
			(thermal_bridge_width 0.5)
			(island_removal_mode 0)
		)
		(polygon
			(pts
				(arc
					(start 172.30217 -265.335258)
					(mid 171.64177 -265.335258)
					(end 172.30217 -265.335258)
				)
			)
		)
	)
	(zone
		(layers "In1.Cu" "In2.Cu")
		(hatch none 0.5)
		(connect_pads
			(clearance 0)
		)
		(min_thickness 0.25)
		(keepout
			(tracks not_allowed)
			(vias allowed)
			(pads allowed)
			(copperpour not_allowed)
			(footprints allowed)
		)
		(placement
			(enabled no)
			(sheetname "")
		)
		(fill yes
			(thermal_gap 0.5)
			(thermal_bridge_width 0.5)
			(island_removal_mode 0)
		)
		(polygon
			(pts
				(arc
					(start 25.482296 -278.935434)
					(mid 24.821896 -278.935434)
					(end 25.482296 -278.935434)
				)
			)
		)
	)
	(zone
		(layers "In1.Cu" "In2.Cu")
		(hatch none 0.5)
		(connect_pads
			(clearance 0)
		)
		(min_thickness 0.25)
		(keepout
			(tracks not_allowed)
			(vias allowed)
			(pads allowed)
			(copperpour not_allowed)
			(footprints allowed)
		)
		(placement
			(enabled no)
			(sheetname "")
		)
		(fill yes
			(thermal_gap 0.5)
			(thermal_bridge_width 0.5)
			(island_removal_mode 0)
		)
		(polygon
			(pts
				(arc
					(start 117.690646 -373.442484)
					(mid 117.71057 -373.45172)
					(end 117.732302 -373.45493)
				)
				(arc
					(start 117.926866 -373.45493)
					(mid 117.980748 -373.432612)
					(end 118.003066 -373.37873)
				)
				(arc
					(start 118.003066 -372.69293)
					(mid 117.980748 -372.639048)
					(end 117.926866 -372.61673)
				)
				(arc
					(start 117.732302 -372.61673)
					(mid 117.710558 -372.619898)
					(end 117.690646 -372.629176)
				)
				(arc
					(start 117.394482 -372.821962)
					(mid 117.352798 -372.834184)
					(end 117.31117 -372.821708)
				)
				(arc
					(start 117.017546 -372.629176)
					(mid 116.997622 -372.61994)
					(end 116.97589 -372.61673)
				)
				(arc
					(start 116.781326 -372.61673)
					(mid 116.727444 -372.639048)
					(end 116.705126 -372.69293)
				)
				(arc
					(start 116.705126 -373.37873)
					(mid 116.727444 -373.432612)
					(end 116.781326 -373.45493)
				)
				(arc
					(start 116.97716 -373.45493)
					(mid 116.998904 -373.451762)
					(end 117.018816 -373.442484)
				)
				(arc
					(start 117.31244 -373.249952)
					(mid 117.354096 -373.23755)
					(end 117.395752 -373.249952)
				)
			)
		)
	)
	(zone
		(layers "In1.Cu" "In2.Cu")
		(hatch none 0.5)
		(connect_pads
			(clearance 0)
		)
		(min_thickness 0.25)
		(keepout
			(tracks not_allowed)
			(vias allowed)
			(pads allowed)
			(copperpour not_allowed)
			(footprints allowed)
		)
		(placement
			(enabled no)
			(sheetname "")
		)
		(fill yes
			(thermal_gap 0.5)
			(thermal_bridge_width 0.5)
			(island_removal_mode 0)
		)
		(polygon
			(pts
				(arc
					(start 435.330346 -211.784946)
					(mid 434.669946 -211.784946)
					(end 435.330346 -211.784946)
				)
			)
		)
	)
	(zone
		(layers "In1.Cu" "In2.Cu")
		(hatch none 0.5)
		(connect_pads
			(clearance 0)
		)
		(min_thickness 0.25)
		(keepout
			(tracks not_allowed)
			(vias allowed)
			(pads allowed)
			(copperpour not_allowed)
			(footprints allowed)
		)
		(placement
			(enabled no)
			(sheetname "")
		)
		(fill yes
			(thermal_gap 0.5)
			(thermal_bridge_width 0.5)
			(island_removal_mode 0)
		)
		(polygon
			(pts
				(arc
					(start 238.74603 -52.8066)
					(mid 238.736794 -52.826524)
					(end 238.733584 -52.848256)
				)
				(arc
					(start 238.733584 -53.04282)
					(mid 238.755902 -53.096702)
					(end 238.809784 -53.11902)
				)
				(arc
					(start 239.495584 -53.11902)
					(mid 239.549466 -53.096702)
					(end 239.571784 -53.04282)
				)
				(arc
					(start 239.571784 -52.848256)
					(mid 239.568616 -52.826512)
					(end 239.559338 -52.8066)
				)
				(arc
					(start 239.366552 -52.510436)
					(mid 239.35433 -52.468752)
					(end 239.366806 -52.427124)
				)
				(arc
					(start 239.559338 -52.1335)
					(mid 239.568574 -52.113576)
					(end 239.571784 -52.091844)
				)
				(arc
					(start 239.571784 -51.89728)
					(mid 239.549466 -51.843398)
					(end 239.495584 -51.82108)
				)
				(arc
					(start 238.809784 -51.82108)
					(mid 238.755902 -51.843398)
					(end 238.733584 -51.89728)
				)
				(arc
					(start 238.733584 -52.093114)
					(mid 238.736752 -52.114858)
					(end 238.74603 -52.13477)
				)
				(arc
					(start 238.938562 -52.428394)
					(mid 238.950964 -52.47005)
					(end 238.938562 -52.511706)
				)
			)
		)
	)
	(zone
		(layers "In1.Cu" "In2.Cu")
		(hatch none 0.5)
		(connect_pads
			(clearance 0)
		)
		(min_thickness 0.25)
		(keepout
			(tracks not_allowed)
			(vias allowed)
			(pads allowed)
			(copperpour not_allowed)
			(footprints allowed)
		)
		(placement
			(enabled no)
			(sheetname "")
		)
		(fill yes
			(thermal_gap 0.5)
			(thermal_bridge_width 0.5)
			(island_removal_mode 0)
		)
		(polygon
			(pts
				(arc
					(start 130.35788 -26.57348)
					(mid 130.321959 -26.588359)
					(end 130.30708 -26.62428)
				)
				(arc
					(start 130.30708 -27.89428)
					(mid 130.321959 -27.930201)
					(end 130.35788 -27.94508)
				)
				(arc
					(start 130.63728 -27.94508)
					(mid 130.673201 -27.930201)
					(end 130.68808 -27.89428)
				)
				(arc
					(start 130.68808 -26.62428)
					(mid 130.673201 -26.588359)
					(end 130.63728 -26.57348)
				)
			)
		)
	)
	(zone
		(layers "In1.Cu" "In2.Cu")
		(hatch none 0.5)
		(connect_pads
			(clearance 0)
		)
		(min_thickness 0.25)
		(keepout
			(tracks not_allowed)
			(vias allowed)
			(pads allowed)
			(copperpour not_allowed)
			(footprints allowed)
		)
		(placement
			(enabled no)
			(sheetname "")
		)
		(fill yes
			(thermal_gap 0.5)
			(thermal_bridge_width 0.5)
			(island_removal_mode 0)
		)
		(polygon
			(pts
				(arc
					(start 179.846224 -284.035246)
					(mid 179.185824 -284.035246)
					(end 179.846224 -284.035246)
				)
			)
		)
	)
	(zone
		(layers "In1.Cu" "In2.Cu")
		(hatch none 0.5)
		(connect_pads
			(clearance 0)
		)
		(min_thickness 0.25)
		(keepout
			(tracks not_allowed)
			(vias allowed)
			(pads allowed)
			(copperpour not_allowed)
			(footprints allowed)
		)
		(placement
			(enabled no)
			(sheetname "")
		)
		(fill yes
			(thermal_gap 0.5)
			(thermal_bridge_width 0.5)
			(island_removal_mode 0)
		)
		(polygon
			(pts
				(arc
					(start 285.066232 -203.28509)
					(mid 284.405832 -203.28509)
					(end 285.066232 -203.28509)
				)
			)
		)
	)
	(zone
		(layers "In1.Cu" "In2.Cu")
		(hatch none 0.5)
		(connect_pads
			(clearance 0)
		)
		(min_thickness 0.25)
		(keepout
			(tracks not_allowed)
			(vias allowed)
			(pads allowed)
			(copperpour not_allowed)
			(footprints allowed)
		)
		(placement
			(enabled no)
			(sheetname "")
		)
		(fill yes
			(thermal_gap 0.5)
			(thermal_bridge_width 0.5)
			(island_removal_mode 0)
		)
		(polygon
			(pts
				(arc
					(start 33.026096 -263.635236)
					(mid 32.365696 -263.635236)
					(end 33.026096 -263.635236)
				)
			)
		)
	)
	(zone
		(layers "In1.Cu" "In2.Cu")
		(hatch none 0.5)
		(connect_pads
			(clearance 0)
		)
		(min_thickness 0.25)
		(keepout
			(tracks not_allowed)
			(vias allowed)
			(pads allowed)
			(copperpour not_allowed)
			(footprints allowed)
		)
		(placement
			(enabled no)
			(sheetname "")
		)
		(fill yes
			(thermal_gap 0.5)
			(thermal_bridge_width 0.5)
			(island_removal_mode 0)
		)
		(polygon
			(pts
				(arc
					(start 435.330346 -209.23504)
					(mid 434.669946 -209.23504)
					(end 435.330346 -209.23504)
				)
			)
		)
	)
	(zone
		(layers "In1.Cu" "In2.Cu")
		(hatch none 0.5)
		(connect_pads
			(clearance 0)
		)
		(min_thickness 0.25)
		(keepout
			(tracks not_allowed)
			(vias allowed)
			(pads allowed)
			(copperpour not_allowed)
			(footprints allowed)
		)
		(placement
			(enabled no)
			(sheetname "")
		)
		(fill yes
			(thermal_gap 0.5)
			(thermal_bridge_width 0.5)
			(island_removal_mode 0)
		)
		(polygon
			(pts
				(arc
					(start 292.610286 -210.085178)
					(mid 291.949886 -210.085178)
					(end 292.610286 -210.085178)
				)
			)
		)
	)
	(zone
		(layers "In1.Cu" "In2.Cu")
		(hatch none 0.5)
		(connect_pads
			(clearance 0)
		)
		(min_thickness 0.25)
		(keepout
			(tracks not_allowed)
			(vias allowed)
			(pads allowed)
			(copperpour not_allowed)
			(footprints allowed)
		)
		(placement
			(enabled no)
			(sheetname "")
		)
		(fill yes
			(thermal_gap 0.5)
			(thermal_bridge_width 0.5)
			(island_removal_mode 0)
		)
		(polygon
			(pts
				(arc
					(start 300.15434 -234.735116)
					(mid 299.49394 -234.735116)
					(end 300.15434 -234.735116)
				)
			)
		)
	)
	(zone
		(layers "In1.Cu" "In2.Cu")
		(hatch none 0.5)
		(connect_pads
			(clearance 0)
		)
		(min_thickness 0.25)
		(keepout
			(tracks not_allowed)
			(vias allowed)
			(pads allowed)
			(copperpour not_allowed)
			(footprints allowed)
		)
		(placement
			(enabled no)
			(sheetname "")
		)
		(fill yes
			(thermal_gap 0.5)
			(thermal_bridge_width 0.5)
			(island_removal_mode 0)
		)
		(polygon
			(pts
				(arc
					(start 48.114204 -199.8853)
					(mid 47.453804 -199.8853)
					(end 48.114204 -199.8853)
				)
			)
		)
	)
	(zone
		(layers "In1.Cu" "In2.Cu")
		(hatch none 0.5)
		(connect_pads
			(clearance 0)
		)
		(min_thickness 0.25)
		(keepout
			(tracks not_allowed)
			(vias allowed)
			(pads allowed)
			(copperpour not_allowed)
			(footprints allowed)
		)
		(placement
			(enabled no)
			(sheetname "")
		)
		(fill yes
			(thermal_gap 0.5)
			(thermal_bridge_width 0.5)
			(island_removal_mode 0)
		)
		(polygon
			(pts
				(arc
					(start 194.934332 -288.285428)
					(mid 194.273932 -288.285428)
					(end 194.934332 -288.285428)
				)
			)
		)
	)
	(zone
		(layers "In1.Cu" "In2.Cu")
		(hatch none 0.5)
		(connect_pads
			(clearance 0)
		)
		(min_thickness 0.25)
		(keepout
			(tracks not_allowed)
			(vias allowed)
			(pads allowed)
			(copperpour not_allowed)
			(footprints allowed)
		)
		(placement
			(enabled no)
			(sheetname "")
		)
		(fill yes
			(thermal_gap 0.5)
			(thermal_bridge_width 0.5)
			(island_removal_mode 0)
		)
		(polygon
			(pts
				(arc
					(start 22.03831 -269.58544)
					(mid 21.37791 -269.58544)
					(end 22.03831 -269.58544)
				)
			)
		)
	)
	(zone
		(layers "In1.Cu" "In2.Cu")
		(hatch none 0.5)
		(connect_pads
			(clearance 0)
		)
		(min_thickness 0.25)
		(keepout
			(tracks not_allowed)
			(vias allowed)
			(pads allowed)
			(copperpour not_allowed)
			(footprints allowed)
		)
		(placement
			(enabled no)
			(sheetname "")
		)
		(fill yes
			(thermal_gap 0.5)
			(thermal_bridge_width 0.5)
			(island_removal_mode 0)
		)
		(polygon
			(pts
				(arc
					(start 439.430414 -219.435172)
					(mid 438.770014 -219.435172)
					(end 439.430414 -219.435172)
				)
			)
		)
	)
	(zone
		(layers "In1.Cu" "In2.Cu")
		(hatch none 0.5)
		(connect_pads
			(clearance 0)
		)
		(min_thickness 0.25)
		(keepout
			(tracks not_allowed)
			(vias allowed)
			(pads allowed)
			(copperpour not_allowed)
			(footprints allowed)
		)
		(placement
			(enabled no)
			(sheetname "")
		)
		(fill yes
			(thermal_gap 0.5)
			(thermal_bridge_width 0.5)
			(island_removal_mode 0)
		)
		(polygon
			(pts
				(arc
					(start 450.4182 -226.235006)
					(mid 449.7578 -226.235006)
					(end 450.4182 -226.235006)
				)
			)
		)
	)
	(zone
		(layers "In1.Cu" "In2.Cu")
		(hatch none 0.5)
		(connect_pads
			(clearance 0)
		)
		(min_thickness 0.25)
		(keepout
			(tracks not_allowed)
			(vias allowed)
			(pads allowed)
			(copperpour not_allowed)
			(footprints allowed)
		)
		(placement
			(enabled no)
			(sheetname "")
		)
		(fill yes
			(thermal_gap 0.5)
			(thermal_bridge_width 0.5)
			(island_removal_mode 0)
		)
		(polygon
			(pts
				(arc
					(start 439.430414 -212.635084)
					(mid 438.770014 -212.635084)
					(end 439.430414 -212.635084)
				)
			)
		)
	)
	(zone
		(layers "In1.Cu" "In2.Cu")
		(hatch none 0.5)
		(connect_pads
			(clearance 0)
		)
		(min_thickness 0.25)
		(keepout
			(tracks not_allowed)
			(vias allowed)
			(pads allowed)
			(copperpour not_allowed)
			(footprints allowed)
		)
		(placement
			(enabled no)
			(sheetname "")
		)
		(fill yes
			(thermal_gap 0.5)
			(thermal_bridge_width 0.5)
			(island_removal_mode 0)
		)
		(polygon
			(pts
				(arc
					(start 179.846224 -314.635388)
					(mid 179.185824 -314.635388)
					(end 179.846224 -314.635388)
				)
			)
		)
	)
	(zone
		(layers "In1.Cu" "In2.Cu")
		(hatch none 0.5)
		(connect_pads
			(clearance 0)
		)
		(min_thickness 0.25)
		(keepout
			(tracks not_allowed)
			(vias allowed)
			(pads allowed)
			(copperpour not_allowed)
			(footprints allowed)
		)
		(placement
			(enabled no)
			(sheetname "")
		)
		(fill yes
			(thermal_gap 0.5)
			(thermal_bridge_width 0.5)
			(island_removal_mode 0)
		)
		(polygon
			(pts
				(arc
					(start 37.126164 -261.08533)
					(mid 36.465764 -261.08533)
					(end 37.126164 -261.08533)
				)
			)
		)
	)
	(zone
		(layers "In1.Cu" "In2.Cu")
		(hatch none 0.5)
		(connect_pads
			(clearance 0)
		)
		(min_thickness 0.25)
		(keepout
			(tracks not_allowed)
			(vias allowed)
			(pads allowed)
			(copperpour not_allowed)
			(footprints allowed)
		)
		(placement
			(enabled no)
			(sheetname "")
		)
		(fill yes
			(thermal_gap 0.5)
			(thermal_bridge_width 0.5)
			(island_removal_mode 0)
		)
		(polygon
			(pts
				(arc
					(start 454.518268 -223.6851)
					(mid 453.857868 -223.6851)
					(end 454.518268 -223.6851)
				)
			)
		)
	)
	(zone
		(layers "In1.Cu" "In2.Cu")
		(hatch none 0.5)
		(connect_pads
			(clearance 0)
		)
		(min_thickness 0.25)
		(keepout
			(tracks not_allowed)
			(vias allowed)
			(pads allowed)
			(copperpour not_allowed)
			(footprints allowed)
		)
		(placement
			(enabled no)
			(sheetname "")
		)
		(fill yes
			(thermal_gap 0.5)
			(thermal_bridge_width 0.5)
			(island_removal_mode 0)
		)
		(polygon
			(pts
				(arc
					(start 194.934332 -244.935248)
					(mid 194.273932 -244.935248)
					(end 194.934332 -244.935248)
				)
			)
		)
	)
	(zone
		(layers "In1.Cu" "In2.Cu")
		(hatch none 0.5)
		(connect_pads
			(clearance 0)
		)
		(min_thickness 0.25)
		(keepout
			(tracks not_allowed)
			(vias allowed)
			(pads allowed)
			(copperpour not_allowed)
			(footprints allowed)
		)
		(placement
			(enabled no)
			(sheetname "")
		)
		(fill yes
			(thermal_gap 0.5)
			(thermal_bridge_width 0.5)
			(island_removal_mode 0)
		)
		(polygon
			(pts
				(arc
					(start 179.846224 -237.285276)
					(mid 179.185824 -237.285276)
					(end 179.846224 -237.285276)
				)
			)
		)
	)
	(zone
		(layers "In1.Cu" "In2.Cu")
		(hatch none 0.5)
		(connect_pads
			(clearance 0)
		)
		(min_thickness 0.25)
		(keepout
			(tracks not_allowed)
			(vias allowed)
			(pads allowed)
			(copperpour not_allowed)
			(footprints allowed)
		)
		(placement
			(enabled no)
			(sheetname "")
		)
		(fill yes
			(thermal_gap 0.5)
			(thermal_bridge_width 0.5)
			(island_removal_mode 0)
		)
		(polygon
			(pts
				(arc
					(start 29.582364 -245.785386)
					(mid 28.921964 -245.785386)
					(end 29.582364 -245.785386)
				)
			)
		)
	)
	(zone
		(layers "In1.Cu" "In2.Cu")
		(hatch none 0.5)
		(connect_pads
			(clearance 0)
		)
		(min_thickness 0.25)
		(keepout
			(tracks not_allowed)
			(vias allowed)
			(pads allowed)
			(copperpour not_allowed)
			(footprints allowed)
		)
		(placement
			(enabled no)
			(sheetname "")
		)
		(fill yes
			(thermal_gap 0.5)
			(thermal_bridge_width 0.5)
			(island_removal_mode 0)
		)
		(polygon
			(pts
				(arc
					(start 277.522432 -272.135092)
					(mid 276.862032 -272.135092)
					(end 277.522432 -272.135092)
				)
			)
		)
	)
	(zone
		(layers "In1.Cu" "In2.Cu")
		(hatch none 0.5)
		(connect_pads
			(clearance 0)
		)
		(min_thickness 0.25)
		(keepout
			(tracks not_allowed)
			(vias allowed)
			(pads allowed)
			(copperpour not_allowed)
			(footprints allowed)
		)
		(placement
			(enabled no)
			(sheetname "")
		)
		(fill yes
			(thermal_gap 0.5)
			(thermal_bridge_width 0.5)
			(island_removal_mode 0)
		)
		(polygon
			(pts
				(arc
					(start 52.214272 -228.78542)
					(mid 51.553872 -228.78542)
					(end 52.214272 -228.78542)
				)
			)
		)
	)
	(zone
		(layers "In1.Cu" "In2.Cu")
		(hatch none 0.5)
		(connect_pads
			(clearance 0)
		)
		(min_thickness 0.25)
		(keepout
			(tracks not_allowed)
			(vias allowed)
			(pads allowed)
			(copperpour not_allowed)
			(footprints allowed)
		)
		(placement
			(enabled no)
			(sheetname "")
		)
		(fill yes
			(thermal_gap 0.5)
			(thermal_bridge_width 0.5)
			(island_removal_mode 0)
		)
		(polygon
			(pts
				(arc
					(start 424.342306 -272.135092)
					(mid 423.681906 -272.135092)
					(end 424.342306 -272.135092)
				)
			)
		)
	)
	(zone
		(layers "In1.Cu" "In2.Cu")
		(hatch none 0.5)
		(connect_pads
			(clearance 0)
		)
		(min_thickness 0.25)
		(keepout
			(tracks not_allowed)
			(vias allowed)
			(pads allowed)
			(copperpour not_allowed)
			(footprints allowed)
		)
		(placement
			(enabled no)
			(sheetname "")
		)
		(fill yes
			(thermal_gap 0.5)
			(thermal_bridge_width 0.5)
			(island_removal_mode 0)
		)
		(polygon
			(pts
				(arc
					(start 277.522432 -303.585118)
					(mid 276.862032 -303.585118)
					(end 277.522432 -303.585118)
				)
			)
		)
	)
	(zone
		(layers "In1.Cu" "In2.Cu")
		(hatch none 0.5)
		(connect_pads
			(clearance 0)
		)
		(min_thickness 0.25)
		(keepout
			(tracks not_allowed)
			(vias allowed)
			(pads allowed)
			(copperpour not_allowed)
			(footprints allowed)
		)
		(placement
			(enabled no)
			(sheetname "")
		)
		(fill yes
			(thermal_gap 0.5)
			(thermal_bridge_width 0.5)
			(island_removal_mode 0)
		)
		(polygon
			(pts
				(arc
					(start 403.541484 -11.91768)
					(mid 403.519166 -11.971562)
					(end 403.465284 -11.99388)
				)
				(arc
					(start 402.42871 -11.99388)
					(mid 402.374828 -11.971562)
					(end 402.35251 -11.91768)
				)
				(arc
					(start 402.35251 -10.51814)
					(mid 402.374828 -10.464258)
					(end 402.42871 -10.44194)
				)
				(arc
					(start 403.465284 -10.44194)
					(mid 403.519166 -10.464258)
					(end 403.541484 -10.51814)
				)
			)
		)
	)
	(zone
		(layers "In1.Cu" "In2.Cu")
		(hatch none 0.5)
		(connect_pads
			(clearance 0)
		)
		(min_thickness 0.25)
		(keepout
			(tracks not_allowed)
			(vias allowed)
			(pads allowed)
			(copperpour not_allowed)
			(footprints allowed)
		)
		(placement
			(enabled no)
			(sheetname "")
		)
		(fill yes
			(thermal_gap 0.5)
			(thermal_bridge_width 0.5)
			(island_removal_mode 0)
		)
		(polygon
			(pts
				(arc
					(start 194.934332 -304.435256)
					(mid 194.273932 -304.435256)
					(end 194.934332 -304.435256)
				)
			)
		)
	)
	(zone
		(layers "In1.Cu" "In2.Cu")
		(hatch none 0.5)
		(connect_pads
			(clearance 0)
		)
		(min_thickness 0.25)
		(keepout
			(tracks not_allowed)
			(vias allowed)
			(pads allowed)
			(copperpour not_allowed)
			(footprints allowed)
		)
		(placement
			(enabled no)
			(sheetname "")
		)
		(fill yes
			(thermal_gap 0.5)
			(thermal_bridge_width 0.5)
			(island_removal_mode 0)
		)
		(polygon
			(pts
				(arc
					(start 29.582364 -298.485306)
					(mid 28.921964 -298.485306)
					(end 29.582364 -298.485306)
				)
			)
		)
	)
	(zone
		(layers "In1.Cu" "In2.Cu")
		(hatch none 0.5)
		(connect_pads
			(clearance 0)
		)
		(min_thickness 0.25)
		(keepout
			(tracks not_allowed)
			(vias allowed)
			(pads allowed)
			(copperpour not_allowed)
			(footprints allowed)
		)
		(placement
			(enabled no)
			(sheetname "")
		)
		(fill yes
			(thermal_gap 0.5)
			(thermal_bridge_width 0.5)
			(island_removal_mode 0)
		)
		(polygon
			(pts
				(arc
					(start 435.330346 -305.28514)
					(mid 434.669946 -305.28514)
					(end 435.330346 -305.28514)
				)
			)
		)
	)
	(zone
		(layers "In1.Cu" "In2.Cu")
		(hatch none 0.5)
		(connect_pads
			(clearance 0)
		)
		(min_thickness 0.25)
		(keepout
			(tracks not_allowed)
			(vias allowed)
			(pads allowed)
			(copperpour not_allowed)
			(footprints allowed)
		)
		(placement
			(enabled no)
			(sheetname "")
		)
		(fill yes
			(thermal_gap 0.5)
			(thermal_bridge_width 0.5)
			(island_removal_mode 0)
		)
		(polygon
			(pts
				(arc
					(start 52.214272 -294.235378)
					(mid 51.553872 -294.235378)
					(end 52.214272 -294.235378)
				)
			)
		)
	)
	(zone
		(layers "In1.Cu" "In2.Cu")
		(hatch none 0.5)
		(connect_pads
			(clearance 0)
		)
		(min_thickness 0.25)
		(keepout
			(tracks not_allowed)
			(vias allowed)
			(pads allowed)
			(copperpour not_allowed)
			(footprints allowed)
		)
		(placement
			(enabled no)
			(sheetname "")
		)
		(fill yes
			(thermal_gap 0.5)
			(thermal_bridge_width 0.5)
			(island_removal_mode 0)
		)
		(polygon
			(pts
				(arc
					(start 435.330346 -284.034992)
					(mid 434.669946 -284.034992)
					(end 435.330346 -284.034992)
				)
			)
		)
	)
	(zone
		(layers "In1.Cu" "In2.Cu")
		(hatch none 0.5)
		(connect_pads
			(clearance 0)
		)
		(min_thickness 0.25)
		(keepout
			(tracks not_allowed)
			(vias allowed)
			(pads allowed)
			(copperpour not_allowed)
			(footprints allowed)
		)
		(placement
			(enabled no)
			(sheetname "")
		)
		(fill yes
			(thermal_gap 0.5)
			(thermal_bridge_width 0.5)
			(island_removal_mode 0)
		)
		(polygon
			(pts
				(arc
					(start 37.126164 -214.33536)
					(mid 36.465764 -214.33536)
					(end 37.126164 -214.33536)
				)
			)
		)
	)
	(zone
		(layers "In1.Cu" "In2.Cu")
		(hatch none 0.5)
		(connect_pads
			(clearance 0)
		)
		(min_thickness 0.25)
		(keepout
			(tracks not_allowed)
			(vias allowed)
			(pads allowed)
			(copperpour not_allowed)
			(footprints allowed)
		)
		(placement
			(enabled no)
			(sheetname "")
		)
		(fill yes
			(thermal_gap 0.5)
			(thermal_bridge_width 0.5)
			(island_removal_mode 0)
		)
		(polygon
			(pts
				(arc
					(start 17.938242 -238.985298)
					(mid 17.277842 -238.985298)
					(end 17.938242 -238.985298)
				)
			)
		)
	)
	(zone
		(layers "In1.Cu" "In2.Cu")
		(hatch none 0.5)
		(connect_pads
			(clearance 0)
		)
		(min_thickness 0.25)
		(keepout
			(tracks not_allowed)
			(vias allowed)
			(pads allowed)
			(copperpour not_allowed)
			(footprints allowed)
		)
		(placement
			(enabled no)
			(sheetname "")
		)
		(fill yes
			(thermal_gap 0.5)
			(thermal_bridge_width 0.5)
			(island_removal_mode 0)
		)
		(polygon
			(pts
				(arc
					(start 199.0344 -199.035416)
					(mid 198.374 -199.035416)
					(end 199.0344 -199.035416)
				)
			)
		)
	)
	(zone
		(layers "In1.Cu" "In2.Cu")
		(hatch none 0.5)
		(connect_pads
			(clearance 0)
		)
		(min_thickness 0.25)
		(keepout
			(tracks not_allowed)
			(vias allowed)
			(pads allowed)
			(copperpour not_allowed)
			(footprints allowed)
		)
		(placement
			(enabled no)
			(sheetname "")
		)
		(fill yes
			(thermal_gap 0.5)
			(thermal_bridge_width 0.5)
			(island_removal_mode 0)
		)
		(polygon
			(pts
				(arc
					(start 273.422364 -295.935146)
					(mid 272.761964 -295.935146)
					(end 273.422364 -295.935146)
				)
			)
		)
	)
	(zone
		(layers "In1.Cu" "In2.Cu")
		(hatch none 0.5)
		(connect_pads
			(clearance 0)
		)
		(min_thickness 0.25)
		(keepout
			(tracks not_allowed)
			(vias allowed)
			(pads allowed)
			(copperpour not_allowed)
			(footprints allowed)
		)
		(placement
			(enabled no)
			(sheetname "")
		)
		(fill yes
			(thermal_gap 0.5)
			(thermal_bridge_width 0.5)
			(island_removal_mode 0)
		)
		(polygon
			(pts
				(arc
					(start 22.03831 -200.735438)
					(mid 21.37791 -200.735438)
					(end 22.03831 -200.735438)
				)
			)
		)
	)
	(zone
		(layers "In1.Cu" "In2.Cu")
		(hatch none 0.5)
		(connect_pads
			(clearance 0)
		)
		(min_thickness 0.25)
		(keepout
			(tracks not_allowed)
			(vias allowed)
			(pads allowed)
			(copperpour not_allowed)
			(footprints allowed)
		)
		(placement
			(enabled no)
			(sheetname "")
		)
		(fill yes
			(thermal_gap 0.5)
			(thermal_bridge_width 0.5)
			(island_removal_mode 0)
		)
		(polygon
			(pts
				(arc
					(start 176.402238 -313.78525)
					(mid 175.741838 -313.78525)
					(end 176.402238 -313.78525)
				)
			)
		)
	)
	(zone
		(layers "In1.Cu" "In2.Cu")
		(hatch none 0.5)
		(connect_pads
			(clearance 0)
		)
		(min_thickness 0.25)
		(keepout
			(tracks not_allowed)
			(vias allowed)
			(pads allowed)
			(copperpour not_allowed)
			(footprints allowed)
		)
		(placement
			(enabled no)
			(sheetname "")
		)
		(fill yes
			(thermal_gap 0.5)
			(thermal_bridge_width 0.5)
			(island_removal_mode 0)
		)
		(polygon
			(pts
				(arc
					(start 273.422364 -289.985196)
					(mid 272.761964 -289.985196)
					(end 273.422364 -289.985196)
				)
			)
		)
	)
	(zone
		(layers "In1.Cu" "In2.Cu")
		(hatch none 0.5)
		(connect_pads
			(clearance 0)
		)
		(min_thickness 0.25)
		(keepout
			(tracks not_allowed)
			(vias allowed)
			(pads allowed)
			(copperpour not_allowed)
			(footprints allowed)
		)
		(placement
			(enabled no)
			(sheetname "")
		)
		(fill yes
			(thermal_gap 0.5)
			(thermal_bridge_width 0.5)
			(island_removal_mode 0)
		)
		(polygon
			(pts
				(arc
					(start 273.422364 -222.834962)
					(mid 272.761964 -222.834962)
					(end 273.422364 -222.834962)
				)
			)
		)
	)
	(zone
		(layers "In1.Cu" "In2.Cu")
		(hatch none 0.5)
		(connect_pads
			(clearance 0)
		)
		(min_thickness 0.25)
		(keepout
			(tracks not_allowed)
			(vias allowed)
			(pads allowed)
			(copperpour not_allowed)
			(footprints allowed)
		)
		(placement
			(enabled no)
			(sheetname "")
		)
		(fill yes
			(thermal_gap 0.5)
			(thermal_bridge_width 0.5)
			(island_removal_mode 0)
		)
		(polygon
			(pts
				(arc
					(start 292.610286 -217.73515)
					(mid 291.949886 -217.73515)
					(end 292.610286 -217.73515)
				)
			)
		)
	)
	(zone
		(layers "In1.Cu" "In2.Cu")
		(hatch none 0.5)
		(connect_pads
			(clearance 0)
		)
		(min_thickness 0.25)
		(keepout
			(tracks not_allowed)
			(vias allowed)
			(pads allowed)
			(copperpour not_allowed)
			(footprints allowed)
		)
		(placement
			(enabled no)
			(sheetname "")
		)
		(fill yes
			(thermal_gap 0.5)
			(thermal_bridge_width 0.5)
			(island_removal_mode 0)
		)
		(polygon
			(pts
				(arc
					(start 420.242238 -250.03506)
					(mid 419.581838 -250.03506)
					(end 420.242238 -250.03506)
				)
			)
		)
	)
	(zone
		(layers "In1.Cu" "In2.Cu")
		(hatch none 0.5)
		(connect_pads
			(clearance 0)
		)
		(min_thickness 0.25)
		(keepout
			(tracks not_allowed)
			(vias allowed)
			(pads allowed)
			(copperpour not_allowed)
			(footprints allowed)
		)
		(placement
			(enabled no)
			(sheetname "")
		)
		(fill yes
			(thermal_gap 0.5)
			(thermal_bridge_width 0.5)
			(island_removal_mode 0)
		)
		(polygon
			(pts
				(arc
					(start 22.03831 -262.785352)
					(mid 21.37791 -262.785352)
					(end 22.03831 -262.785352)
				)
			)
		)
	)
	(zone
		(layers "In1.Cu" "In2.Cu")
		(hatch none 0.5)
		(connect_pads
			(clearance 0)
		)
		(min_thickness 0.25)
		(keepout
			(tracks not_allowed)
			(vias allowed)
			(pads allowed)
			(copperpour not_allowed)
			(footprints allowed)
		)
		(placement
			(enabled no)
			(sheetname "")
		)
		(fill yes
			(thermal_gap 0.5)
			(thermal_bridge_width 0.5)
			(island_removal_mode 0)
		)
		(polygon
			(pts
				(arc
					(start 17.938242 -253.435358)
					(mid 17.277842 -253.435358)
					(end 17.938242 -253.435358)
				)
			)
		)
	)
	(zone
		(layers "In1.Cu" "In2.Cu")
		(hatch none 0.5)
		(connect_pads
			(clearance 0)
		)
		(min_thickness 0.25)
		(keepout
			(tracks not_allowed)
			(vias allowed)
			(pads allowed)
			(copperpour not_allowed)
			(footprints allowed)
		)
		(placement
			(enabled no)
			(sheetname "")
		)
		(fill yes
			(thermal_gap 0.5)
			(thermal_bridge_width 0.5)
			(island_removal_mode 0)
		)
		(polygon
			(pts
				(arc
					(start 439.430414 -197.33514)
					(mid 438.770014 -197.33514)
					(end 439.430414 -197.33514)
				)
			)
		)
	)
	(zone
		(layers "In1.Cu" "In2.Cu")
		(hatch none 0.5)
		(connect_pads
			(clearance 0)
		)
		(min_thickness 0.25)
		(keepout
			(tracks not_allowed)
			(vias allowed)
			(pads allowed)
			(copperpour not_allowed)
			(footprints allowed)
		)
		(placement
			(enabled no)
			(sheetname "")
		)
		(fill yes
			(thermal_gap 0.5)
			(thermal_bridge_width 0.5)
			(island_removal_mode 0)
		)
		(polygon
			(pts
				(arc
					(start 176.402238 -249.18543)
					(mid 175.741838 -249.18543)
					(end 176.402238 -249.18543)
				)
			)
		)
	)
	(zone
		(layers "In1.Cu" "In2.Cu")
		(hatch none 0.5)
		(connect_pads
			(clearance 0)
		)
		(min_thickness 0.25)
		(keepout
			(tracks not_allowed)
			(vias allowed)
			(pads allowed)
			(copperpour not_allowed)
			(footprints allowed)
		)
		(placement
			(enabled no)
			(sheetname "")
		)
		(fill yes
			(thermal_gap 0.5)
			(thermal_bridge_width 0.5)
			(island_removal_mode 0)
		)
		(polygon
			(pts
				(arc
					(start 84.335874 -408.860244)
					(mid 84.358192 -408.914126)
					(end 84.412074 -408.936444)
				)
				(arc
					(start 84.607654 -408.936444)
					(mid 84.62953 -408.933312)
					(end 84.649564 -408.923998)
				)
				(arc
					(start 84.943188 -408.731466)
					(mid 84.984844 -408.719064)
					(end 85.0265 -408.731466)
				)
				(arc
					(start 85.321394 -408.923998)
					(mid 85.341318 -408.933234)
					(end 85.36305 -408.936444)
				)
				(arc
					(start 85.557614 -408.936444)
					(mid 85.611496 -408.914126)
					(end 85.633814 -408.860244)
				)
				(arc
					(start 85.633814 -408.174444)
					(mid 85.611496 -408.120562)
					(end 85.557614 -408.098244)
				)
				(arc
					(start 85.36305 -408.098244)
					(mid 85.341306 -408.101412)
					(end 85.321394 -408.11069)
				)
				(arc
					(start 85.02523 -408.303476)
					(mid 84.983546 -408.315698)
					(end 84.941918 -408.303222)
				)
				(arc
					(start 84.648294 -408.11069)
					(mid 84.62837 -408.101454)
					(end 84.606638 -408.098244)
				)
				(arc
					(start 84.412074 -408.098244)
					(mid 84.358192 -408.120562)
					(end 84.335874 -408.174444)
				)
			)
		)
	)
	(zone
		(layers "In1.Cu" "In2.Cu")
		(hatch none 0.5)
		(connect_pads
			(clearance 0)
		)
		(min_thickness 0.25)
		(keepout
			(tracks not_allowed)
			(vias allowed)
			(pads allowed)
			(copperpour not_allowed)
			(footprints allowed)
		)
		(placement
			(enabled no)
			(sheetname "")
		)
		(fill yes
			(thermal_gap 0.5)
			(thermal_bridge_width 0.5)
			(island_removal_mode 0)
		)
		(polygon
			(pts
				(arc
					(start 33.026096 -280.635202)
					(mid 32.365696 -280.635202)
					(end 33.026096 -280.635202)
				)
			)
		)
	)
	(zone
		(layers "In1.Cu" "In2.Cu")
		(hatch none 0.5)
		(connect_pads
			(clearance 0)
		)
		(min_thickness 0.25)
		(keepout
			(tracks not_allowed)
			(vias allowed)
			(pads allowed)
			(copperpour not_allowed)
			(footprints allowed)
		)
		(placement
			(enabled no)
			(sheetname "")
		)
		(fill yes
			(thermal_gap 0.5)
			(thermal_bridge_width 0.5)
			(island_removal_mode 0)
		)
		(polygon
			(pts
				(arc
					(start 187.390278 -272.98523)
					(mid 186.729878 -272.98523)
					(end 187.390278 -272.98523)
				)
			)
		)
	)
	(zone
		(layers "In1.Cu" "In2.Cu")
		(hatch none 0.5)
		(connect_pads
			(clearance 0)
		)
		(min_thickness 0.25)
		(keepout
			(tracks not_allowed)
			(vias allowed)
			(pads allowed)
			(copperpour not_allowed)
			(footprints allowed)
		)
		(placement
			(enabled no)
			(sheetname "")
		)
		(fill yes
			(thermal_gap 0.5)
			(thermal_bridge_width 0.5)
			(island_removal_mode 0)
		)
		(polygon
			(pts
				(arc
					(start 435.330346 -243.234972)
					(mid 434.669946 -243.234972)
					(end 435.330346 -243.234972)
				)
			)
		)
	)
	(zone
		(layers "In1.Cu" "In2.Cu")
		(hatch none 0.5)
		(connect_pads
			(clearance 0)
		)
		(min_thickness 0.25)
		(keepout
			(tracks not_allowed)
			(vias allowed)
			(pads allowed)
			(copperpour not_allowed)
			(footprints allowed)
		)
		(placement
			(enabled no)
			(sheetname "")
		)
		(fill yes
			(thermal_gap 0.5)
			(thermal_bridge_width 0.5)
			(island_removal_mode 0)
		)
		(polygon
			(pts
				(arc
					(start 273.422364 -276.38502)
					(mid 272.761964 -276.38502)
					(end 273.422364 -276.38502)
				)
			)
		)
	)
	(zone
		(layers "In1.Cu" "In2.Cu")
		(hatch none 0.5)
		(connect_pads
			(clearance 0)
		)
		(min_thickness 0.25)
		(keepout
			(tracks not_allowed)
			(vias allowed)
			(pads allowed)
			(copperpour not_allowed)
			(footprints allowed)
		)
		(placement
			(enabled no)
			(sheetname "")
		)
		(fill yes
			(thermal_gap 0.5)
			(thermal_bridge_width 0.5)
			(island_removal_mode 0)
		)
		(polygon
			(pts
				(arc
					(start 296.054272 -221.13494)
					(mid 295.393872 -221.13494)
					(end 296.054272 -221.13494)
				)
			)
		)
	)
	(zone
		(layers "In1.Cu" "In2.Cu")
		(hatch none 0.5)
		(connect_pads
			(clearance 0)
		)
		(min_thickness 0.25)
		(keepout
			(tracks not_allowed)
			(vias allowed)
			(pads allowed)
			(copperpour not_allowed)
			(footprints allowed)
		)
		(placement
			(enabled no)
			(sheetname "")
		)
		(fill yes
			(thermal_gap 0.5)
			(thermal_bridge_width 0.5)
			(island_removal_mode 0)
		)
		(polygon
			(pts
				(arc
					(start 435.330346 -312.084974)
					(mid 434.669946 -312.084974)
					(end 435.330346 -312.084974)
				)
			)
		)
	)
	(zone
		(layers "In1.Cu" "In2.Cu")
		(hatch none 0.5)
		(connect_pads
			(clearance 0)
		)
		(min_thickness 0.25)
		(keepout
			(tracks not_allowed)
			(vias allowed)
			(pads allowed)
			(copperpour not_allowed)
			(footprints allowed)
		)
		(placement
			(enabled no)
			(sheetname "")
		)
		(fill yes
			(thermal_gap 0.5)
			(thermal_bridge_width 0.5)
			(island_removal_mode 0)
		)
		(polygon
			(pts
				(arc
					(start 17.938242 -227.935282)
					(mid 17.277842 -227.935282)
					(end 17.938242 -227.935282)
				)
			)
		)
	)
	(zone
		(layers "In1.Cu" "In2.Cu")
		(hatch none 0.5)
		(connect_pads
			(clearance 0)
		)
		(min_thickness 0.25)
		(keepout
			(tracks not_allowed)
			(vias allowed)
			(pads allowed)
			(copperpour not_allowed)
			(footprints allowed)
		)
		(placement
			(enabled no)
			(sheetname "")
		)
		(fill yes
			(thermal_gap 0.5)
			(thermal_bridge_width 0.5)
			(island_removal_mode 0)
		)
		(polygon
			(pts
				(arc
					(start 439.430414 -227.085144)
					(mid 438.770014 -227.085144)
					(end 439.430414 -227.085144)
				)
			)
		)
	)
	(zone
		(layers "In1.Cu" "In2.Cu")
		(hatch none 0.5)
		(connect_pads
			(clearance 0)
		)
		(min_thickness 0.25)
		(keepout
			(tracks not_allowed)
			(vias allowed)
			(pads allowed)
			(copperpour not_allowed)
			(footprints allowed)
		)
		(placement
			(enabled no)
			(sheetname "")
		)
		(fill yes
			(thermal_gap 0.5)
			(thermal_bridge_width 0.5)
			(island_removal_mode 0)
		)
		(polygon
			(pts
				(arc
					(start 269.978378 -233.035094)
					(mid 269.317978 -233.035094)
					(end 269.978378 -233.035094)
				)
			)
		)
	)
	(zone
		(layers "In1.Cu" "In2.Cu")
		(hatch none 0.5)
		(connect_pads
			(clearance 0)
		)
		(min_thickness 0.25)
		(keepout
			(tracks not_allowed)
			(vias allowed)
			(pads allowed)
			(copperpour not_allowed)
			(footprints allowed)
		)
		(placement
			(enabled no)
			(sheetname "")
		)
		(fill yes
			(thermal_gap 0.5)
			(thermal_bridge_width 0.5)
			(island_removal_mode 0)
		)
		(polygon
			(pts
				(arc
					(start 187.390278 -277.235412)
					(mid 186.729878 -277.235412)
					(end 187.390278 -277.235412)
				)
			)
		)
	)
	(zone
		(layers "In1.Cu" "In2.Cu")
		(hatch none 0.5)
		(connect_pads
			(clearance 0)
		)
		(min_thickness 0.25)
		(keepout
			(tracks not_allowed)
			(vias allowed)
			(pads allowed)
			(copperpour not_allowed)
			(footprints allowed)
		)
		(placement
			(enabled no)
			(sheetname "")
		)
		(fill yes
			(thermal_gap 0.5)
			(thermal_bridge_width 0.5)
			(island_removal_mode 0)
		)
		(polygon
			(pts
				(arc
					(start 129.993136 -408.860244)
					(mid 130.015454 -408.914126)
					(end 130.069336 -408.936444)
				)
				(arc
					(start 130.264916 -408.936444)
					(mid 130.286792 -408.933312)
					(end 130.306826 -408.923998)
				)
				(arc
					(start 130.60045 -408.731466)
					(mid 130.642106 -408.719064)
					(end 130.683762 -408.731466)
				)
				(arc
					(start 130.978656 -408.923998)
					(mid 130.99858 -408.933234)
					(end 131.020312 -408.936444)
				)
				(arc
					(start 131.214876 -408.936444)
					(mid 131.268758 -408.914126)
					(end 131.291076 -408.860244)
				)
				(arc
					(start 131.291076 -408.174444)
					(mid 131.268758 -408.120562)
					(end 131.214876 -408.098244)
				)
				(arc
					(start 131.020312 -408.098244)
					(mid 130.998568 -408.101412)
					(end 130.978656 -408.11069)
				)
				(arc
					(start 130.682492 -408.303476)
					(mid 130.640808 -408.315698)
					(end 130.59918 -408.303222)
				)
				(arc
					(start 130.305556 -408.11069)
					(mid 130.285632 -408.101454)
					(end 130.2639 -408.098244)
				)
				(arc
					(start 130.069336 -408.098244)
					(mid 130.015454 -408.120562)
					(end 129.993136 -408.174444)
				)
			)
		)
	)
	(zone
		(layers "In1.Cu" "In2.Cu")
		(hatch none 0.5)
		(connect_pads
			(clearance 0)
		)
		(min_thickness 0.25)
		(keepout
			(tracks not_allowed)
			(vias allowed)
			(pads allowed)
			(copperpour not_allowed)
			(footprints allowed)
		)
		(placement
			(enabled no)
			(sheetname "")
		)
		(fill yes
			(thermal_gap 0.5)
			(thermal_bridge_width 0.5)
			(island_removal_mode 0)
		)
		(polygon
			(pts
				(arc
					(start 424.342306 -267.885164)
					(mid 423.681906 -267.885164)
					(end 424.342306 -267.885164)
				)
			)
		)
	)
	(zone
		(layers "In1.Cu" "In2.Cu")
		(hatch none 0.5)
		(connect_pads
			(clearance 0)
		)
		(min_thickness 0.25)
		(keepout
			(tracks not_allowed)
			(vias allowed)
			(pads allowed)
			(copperpour not_allowed)
			(footprints allowed)
		)
		(placement
			(enabled no)
			(sheetname "")
		)
		(fill yes
			(thermal_gap 0.5)
			(thermal_bridge_width 0.5)
			(island_removal_mode 0)
		)
		(polygon
			(pts
				(arc
					(start 269.978378 -245.785132)
					(mid 269.317978 -245.785132)
					(end 269.978378 -245.785132)
				)
			)
		)
	)
	(zone
		(layers "In1.Cu" "In2.Cu")
		(hatch none 0.5)
		(connect_pads
			(clearance 0)
		)
		(min_thickness 0.25)
		(keepout
			(tracks not_allowed)
			(vias allowed)
			(pads allowed)
			(copperpour not_allowed)
			(footprints allowed)
		)
		(placement
			(enabled no)
			(sheetname "")
		)
		(fill yes
			(thermal_gap 0.5)
			(thermal_bridge_width 0.5)
			(island_removal_mode 0)
		)
		(polygon
			(pts
				(arc
					(start 187.390278 -205.83525)
					(mid 186.729878 -205.83525)
					(end 187.390278 -205.83525)
				)
			)
		)
	)
	(zone
		(layers "In1.Cu" "In2.Cu")
		(hatch none 0.5)
		(connect_pads
			(clearance 0)
		)
		(min_thickness 0.25)
		(keepout
			(tracks not_allowed)
			(vias allowed)
			(pads allowed)
			(copperpour not_allowed)
			(footprints allowed)
		)
		(placement
			(enabled no)
			(sheetname "")
		)
		(fill yes
			(thermal_gap 0.5)
			(thermal_bridge_width 0.5)
			(island_removal_mode 0)
		)
		(polygon
			(pts
				(arc
					(start 112.585246 -370.978684)
					(mid 112.60517 -370.98792)
					(end 112.626902 -370.99113)
				)
				(arc
					(start 112.821466 -370.99113)
					(mid 112.875348 -370.968812)
					(end 112.897666 -370.91493)
				)
				(arc
					(start 112.897666 -370.22913)
					(mid 112.875348 -370.175248)
					(end 112.821466 -370.15293)
				)
				(arc
					(start 112.626902 -370.15293)
					(mid 112.605158 -370.156098)
					(end 112.585246 -370.165376)
				)
				(arc
					(start 112.289082 -370.358162)
					(mid 112.247398 -370.370384)
					(end 112.20577 -370.357908)
				)
				(arc
					(start 111.912146 -370.165376)
					(mid 111.892222 -370.15614)
					(end 111.87049 -370.15293)
				)
				(arc
					(start 111.675926 -370.15293)
					(mid 111.622044 -370.175248)
					(end 111.599726 -370.22913)
				)
				(arc
					(start 111.599726 -370.91493)
					(mid 111.622044 -370.968812)
					(end 111.675926 -370.99113)
				)
				(arc
					(start 111.87176 -370.99113)
					(mid 111.893504 -370.987962)
					(end 111.913416 -370.978684)
				)
				(arc
					(start 112.20704 -370.786152)
					(mid 112.248696 -370.77375)
					(end 112.290352 -370.786152)
				)
			)
		)
	)
	(zone
		(layers "In1.Cu" "In2.Cu")
		(hatch none 0.5)
		(connect_pads
			(clearance 0)
		)
		(min_thickness 0.25)
		(keepout
			(tracks not_allowed)
			(vias allowed)
			(pads allowed)
			(copperpour not_allowed)
			(footprints allowed)
		)
		(placement
			(enabled no)
			(sheetname "")
		)
		(fill yes
			(thermal_gap 0.5)
			(thermal_bridge_width 0.5)
			(island_removal_mode 0)
		)
		(polygon
			(pts
				(arc
					(start 431.88636 -234.735116)
					(mid 431.22596 -234.735116)
					(end 431.88636 -234.735116)
				)
			)
		)
	)
	(zone
		(layers "In1.Cu" "In2.Cu")
		(hatch none 0.5)
		(connect_pads
			(clearance 0)
		)
		(min_thickness 0.25)
		(keepout
			(tracks not_allowed)
			(vias allowed)
			(pads allowed)
			(copperpour not_allowed)
			(footprints allowed)
		)
		(placement
			(enabled no)
			(sheetname "")
		)
		(fill yes
			(thermal_gap 0.5)
			(thermal_bridge_width 0.5)
			(island_removal_mode 0)
		)
		(polygon
			(pts
				(arc
					(start 17.938242 -312.085228)
					(mid 17.277842 -312.085228)
					(end 17.938242 -312.085228)
				)
			)
		)
	)
	(zone
		(layers "In1.Cu" "In2.Cu")
		(hatch none 0.5)
		(connect_pads
			(clearance 0)
		)
		(min_thickness 0.25)
		(keepout
			(tracks not_allowed)
			(vias allowed)
			(pads allowed)
			(copperpour not_allowed)
			(footprints allowed)
		)
		(placement
			(enabled no)
			(sheetname "")
		)
		(fill yes
			(thermal_gap 0.5)
			(thermal_bridge_width 0.5)
			(island_removal_mode 0)
		)
		(polygon
			(pts
				(arc
					(start 91.627452 -370.978684)
					(mid 91.647376 -370.98792)
					(end 91.669108 -370.99113)
				)
				(arc
					(start 91.863672 -370.99113)
					(mid 91.917554 -370.968812)
					(end 91.939872 -370.91493)
				)
				(arc
					(start 91.939872 -370.22913)
					(mid 91.917554 -370.175248)
					(end 91.863672 -370.15293)
				)
				(arc
					(start 91.669108 -370.15293)
					(mid 91.647364 -370.156098)
					(end 91.627452 -370.165376)
				)
				(arc
					(start 91.331288 -370.358162)
					(mid 91.289604 -370.370384)
					(end 91.247976 -370.357908)
				)
				(arc
					(start 90.954352 -370.165376)
					(mid 90.934428 -370.15614)
					(end 90.912696 -370.15293)
				)
				(arc
					(start 90.718132 -370.15293)
					(mid 90.66425 -370.175248)
					(end 90.641932 -370.22913)
				)
				(arc
					(start 90.641932 -370.91493)
					(mid 90.66425 -370.968812)
					(end 90.718132 -370.99113)
				)
				(arc
					(start 90.913966 -370.99113)
					(mid 90.93571 -370.987962)
					(end 90.955622 -370.978684)
				)
				(arc
					(start 91.249246 -370.786152)
					(mid 91.290902 -370.77375)
					(end 91.332558 -370.786152)
				)
			)
		)
	)
	(zone
		(layers "In1.Cu" "In2.Cu")
		(hatch none 0.5)
		(connect_pads
			(clearance 0)
		)
		(min_thickness 0.25)
		(keepout
			(tracks not_allowed)
			(vias allowed)
			(pads allowed)
			(copperpour not_allowed)
			(footprints allowed)
		)
		(placement
			(enabled no)
			(sheetname "")
		)
		(fill yes
			(thermal_gap 0.5)
			(thermal_bridge_width 0.5)
			(island_removal_mode 0)
		)
		(polygon
			(pts
				(arc
					(start 106.440986 -292.411404)
					(mid 106.136186 -292.716204)
					(end 106.440986 -293.021004)
				)
				(arc
					(start 107.38104 -293.021004)
					(mid 107.68584 -292.716204)
					(end 107.38104 -292.411404)
				)
			)
		)
	)
	(zone
		(layers "In1.Cu" "In2.Cu")
		(hatch none 0.5)
		(connect_pads
			(clearance 0)
		)
		(min_thickness 0.25)
		(keepout
			(tracks not_allowed)
			(vias allowed)
			(pads allowed)
			(copperpour not_allowed)
			(footprints allowed)
		)
		(placement
			(enabled no)
			(sheetname "")
		)
		(fill yes
			(thermal_gap 0.5)
			(thermal_bridge_width 0.5)
			(island_removal_mode 0)
		)
		(polygon
			(pts
				(arc
					(start 157.025594 -373.442484)
					(mid 157.045518 -373.45172)
					(end 157.06725 -373.45493)
				)
				(arc
					(start 157.261814 -373.45493)
					(mid 157.315696 -373.432612)
					(end 157.338014 -373.37873)
				)
				(arc
					(start 157.338014 -372.69293)
					(mid 157.315696 -372.639048)
					(end 157.261814 -372.61673)
				)
				(arc
					(start 157.06725 -372.61673)
					(mid 157.045506 -372.619898)
					(end 157.025594 -372.629176)
				)
				(arc
					(start 156.72943 -372.821962)
					(mid 156.687746 -372.834184)
					(end 156.646118 -372.821708)
				)
				(arc
					(start 156.352494 -372.629176)
					(mid 156.33257 -372.61994)
					(end 156.310838 -372.61673)
				)
				(arc
					(start 156.116274 -372.61673)
					(mid 156.062392 -372.639048)
					(end 156.040074 -372.69293)
				)
				(arc
					(start 156.040074 -373.37873)
					(mid 156.062392 -373.432612)
					(end 156.116274 -373.45493)
				)
				(arc
					(start 156.312108 -373.45493)
					(mid 156.333852 -373.451762)
					(end 156.353764 -373.442484)
				)
				(arc
					(start 156.647388 -373.249952)
					(mid 156.689044 -373.23755)
					(end 156.7307 -373.249952)
				)
			)
		)
	)
	(zone
		(layers "In1.Cu" "In2.Cu")
		(hatch none 0.5)
		(connect_pads
			(clearance 0)
		)
		(min_thickness 0.25)
		(keepout
			(tracks not_allowed)
			(vias allowed)
			(pads allowed)
			(copperpour not_allowed)
			(footprints allowed)
		)
		(placement
			(enabled no)
			(sheetname "")
		)
		(fill yes
			(thermal_gap 0.5)
			(thermal_bridge_width 0.5)
			(island_removal_mode 0)
		)
		(polygon
			(pts
				(arc
					(start 194.934332 -248.335292)
					(mid 194.273932 -248.335292)
					(end 194.934332 -248.335292)
				)
			)
		)
	)
	(zone
		(layers "In1.Cu" "In2.Cu")
		(hatch none 0.5)
		(connect_pads
			(clearance 0)
		)
		(min_thickness 0.25)
		(keepout
			(tracks not_allowed)
			(vias allowed)
			(pads allowed)
			(copperpour not_allowed)
			(footprints allowed)
		)
		(placement
			(enabled no)
			(sheetname "")
		)
		(fill yes
			(thermal_gap 0.5)
			(thermal_bridge_width 0.5)
			(island_removal_mode 0)
		)
		(polygon
			(pts
				(arc
					(start 199.0344 -217.735404)
					(mid 198.374 -217.735404)
					(end 199.0344 -217.735404)
				)
			)
		)
	)
	(zone
		(layers "In1.Cu" "In2.Cu")
		(hatch none 0.5)
		(connect_pads
			(clearance 0)
		)
		(min_thickness 0.25)
		(keepout
			(tracks not_allowed)
			(vias allowed)
			(pads allowed)
			(copperpour not_allowed)
			(footprints allowed)
		)
		(placement
			(enabled no)
			(sheetname "")
		)
		(fill yes
			(thermal_gap 0.5)
			(thermal_bridge_width 0.5)
			(island_removal_mode 0)
		)
		(polygon
			(pts
				(arc
					(start 435.330346 -238.985044)
					(mid 434.669946 -238.985044)
					(end 435.330346 -238.985044)
				)
			)
		)
	)
	(zone
		(layers "In1.Cu" "In2.Cu")
		(hatch none 0.5)
		(connect_pads
			(clearance 0)
		)
		(min_thickness 0.25)
		(keepout
			(tracks not_allowed)
			(vias allowed)
			(pads allowed)
			(copperpour not_allowed)
			(footprints allowed)
		)
		(placement
			(enabled no)
			(sheetname "")
		)
		(fill yes
			(thermal_gap 0.5)
			(thermal_bridge_width 0.5)
			(island_removal_mode 0)
		)
		(polygon
			(pts
				(arc
					(start 44.670218 -272.135346)
					(mid 44.009818 -272.135346)
					(end 44.670218 -272.135346)
				)
			)
		)
	)
	(zone
		(layers "In1.Cu" "In2.Cu")
		(hatch none 0.5)
		(connect_pads
			(clearance 0)
		)
		(min_thickness 0.25)
		(keepout
			(tracks not_allowed)
			(vias allowed)
			(pads allowed)
			(copperpour not_allowed)
			(footprints allowed)
		)
		(placement
			(enabled no)
			(sheetname "")
		)
		(fill yes
			(thermal_gap 0.5)
			(thermal_bridge_width 0.5)
			(island_removal_mode 0)
		)
		(polygon
			(pts
				(arc
					(start 269.978378 -201.585068)
					(mid 269.317978 -201.585068)
					(end 269.978378 -201.585068)
				)
			)
		)
	)
	(zone
		(layers "In1.Cu" "In2.Cu")
		(hatch none 0.5)
		(connect_pads
			(clearance 0)
		)
		(min_thickness 0.25)
		(keepout
			(tracks not_allowed)
			(vias allowed)
			(pads allowed)
			(copperpour not_allowed)
			(footprints allowed)
		)
		(placement
			(enabled no)
			(sheetname "")
		)
		(fill yes
			(thermal_gap 0.5)
			(thermal_bridge_width 0.5)
			(island_removal_mode 0)
		)
		(polygon
			(pts
				(arc
					(start 40.57015 -297.635422)
					(mid 39.90975 -297.635422)
					(end 40.57015 -297.635422)
				)
			)
		)
	)
	(zone
		(layers "In1.Cu" "In2.Cu")
		(hatch none 0.5)
		(connect_pads
			(clearance 0)
		)
		(min_thickness 0.25)
		(keepout
			(tracks not_allowed)
			(vias allowed)
			(pads allowed)
			(copperpour not_allowed)
			(footprints allowed)
		)
		(placement
			(enabled no)
			(sheetname "")
		)
		(fill yes
			(thermal_gap 0.5)
			(thermal_bridge_width 0.5)
			(island_removal_mode 0)
		)
		(polygon
			(pts
				(arc
					(start 273.422364 -241.53495)
					(mid 272.761964 -241.53495)
					(end 273.422364 -241.53495)
				)
			)
		)
	)
	(zone
		(layers "In1.Cu" "In2.Cu")
		(hatch none 0.5)
		(connect_pads
			(clearance 0)
		)
		(min_thickness 0.25)
		(keepout
			(tracks not_allowed)
			(vias allowed)
			(pads allowed)
			(copperpour not_allowed)
			(footprints allowed)
		)
		(placement
			(enabled no)
			(sheetname "")
		)
		(fill yes
			(thermal_gap 0.5)
			(thermal_bridge_width 0.5)
			(island_removal_mode 0)
		)
		(polygon
			(pts
				(arc
					(start 420.242238 -215.18499)
					(mid 419.581838 -215.18499)
					(end 420.242238 -215.18499)
				)
			)
		)
	)
	(zone
		(layers "In1.Cu" "In2.Cu")
		(hatch none 0.5)
		(connect_pads
			(clearance 0)
		)
		(min_thickness 0.25)
		(keepout
			(tracks not_allowed)
			(vias allowed)
			(pads allowed)
			(copperpour not_allowed)
			(footprints allowed)
		)
		(placement
			(enabled no)
			(sheetname "")
		)
		(fill yes
			(thermal_gap 0.5)
			(thermal_bridge_width 0.5)
			(island_removal_mode 0)
		)
		(polygon
			(pts
				(arc
					(start 57.172352 -7.672324)
					(mid 57.19467 -7.618442)
					(end 57.248552 -7.596124)
				)
				(arc
					(start 58.285126 -7.596124)
					(mid 58.339008 -7.618442)
					(end 58.361326 -7.672324)
				)
				(arc
					(start 58.361326 -9.071864)
					(mid 58.339008 -9.125746)
					(end 58.285126 -9.148064)
				)
				(arc
					(start 57.248552 -9.148064)
					(mid 57.19467 -9.125746)
					(end 57.172352 -9.071864)
				)
			)
		)
	)
	(zone
		(layers "In1.Cu" "In2.Cu")
		(hatch none 0.5)
		(connect_pads
			(clearance 0)
		)
		(min_thickness 0.25)
		(keepout
			(tracks not_allowed)
			(vias allowed)
			(pads allowed)
			(copperpour not_allowed)
			(footprints allowed)
		)
		(placement
			(enabled no)
			(sheetname "")
		)
		(fill yes
			(thermal_gap 0.5)
			(thermal_bridge_width 0.5)
			(island_removal_mode 0)
		)
		(polygon
			(pts
				(arc
					(start 29.582364 -301.88535)
					(mid 28.921964 -301.88535)
					(end 29.582364 -301.88535)
				)
			)
		)
	)
	(zone
		(layers "In1.Cu" "In2.Cu")
		(hatch none 0.5)
		(connect_pads
			(clearance 0)
		)
		(min_thickness 0.25)
		(keepout
			(tracks not_allowed)
			(vias allowed)
			(pads allowed)
			(copperpour not_allowed)
			(footprints allowed)
		)
		(placement
			(enabled no)
			(sheetname "")
		)
		(fill yes
			(thermal_gap 0.5)
			(thermal_bridge_width 0.5)
			(island_removal_mode 0)
		)
		(polygon
			(pts
				(arc
					(start 442.8744 -198.185024)
					(mid 442.214 -198.185024)
					(end 442.8744 -198.185024)
				)
			)
		)
	)
	(zone
		(layers "In1.Cu" "In2.Cu")
		(hatch none 0.5)
		(connect_pads
			(clearance 0)
		)
		(min_thickness 0.25)
		(keepout
			(tracks not_allowed)
			(vias allowed)
			(pads allowed)
			(copperpour not_allowed)
			(footprints allowed)
		)
		(placement
			(enabled no)
			(sheetname "")
		)
		(fill yes
			(thermal_gap 0.5)
			(thermal_bridge_width 0.5)
			(island_removal_mode 0)
		)
		(polygon
			(pts
				(arc
					(start 191.490346 -283.185362)
					(mid 190.829946 -283.185362)
					(end 191.490346 -283.185362)
				)
			)
		)
	)
	(zone
		(layers "In1.Cu" "In2.Cu")
		(hatch none 0.5)
		(connect_pads
			(clearance 0)
		)
		(min_thickness 0.25)
		(keepout
			(tracks not_allowed)
			(vias allowed)
			(pads allowed)
			(copperpour not_allowed)
			(footprints allowed)
		)
		(placement
			(enabled no)
			(sheetname "")
		)
		(fill yes
			(thermal_gap 0.5)
			(thermal_bridge_width 0.5)
			(island_removal_mode 0)
		)
		(polygon
			(pts
				(arc
					(start 33.026096 -235.585254)
					(mid 32.365696 -235.585254)
					(end 33.026096 -235.585254)
				)
			)
		)
	)
	(zone
		(layers "In1.Cu" "In2.Cu")
		(hatch none 0.5)
		(connect_pads
			(clearance 0)
		)
		(min_thickness 0.25)
		(keepout
			(tracks not_allowed)
			(vias allowed)
			(pads allowed)
			(copperpour not_allowed)
			(footprints allowed)
		)
		(placement
			(enabled no)
			(sheetname "")
		)
		(fill yes
			(thermal_gap 0.5)
			(thermal_bridge_width 0.5)
			(island_removal_mode 0)
		)
		(polygon
			(pts
				(arc
					(start 33.026096 -272.98523)
					(mid 32.365696 -272.98523)
					(end 33.026096 -272.98523)
				)
			)
		)
	)
	(zone
		(layers "In1.Cu" "In2.Cu")
		(hatch none 0.5)
		(connect_pads
			(clearance 0)
		)
		(min_thickness 0.25)
		(keepout
			(tracks not_allowed)
			(vias allowed)
			(pads allowed)
			(copperpour not_allowed)
			(footprints allowed)
		)
		(placement
			(enabled no)
			(sheetname "")
		)
		(fill yes
			(thermal_gap 0.5)
			(thermal_bridge_width 0.5)
			(island_removal_mode 0)
		)
		(polygon
			(pts
				(arc
					(start 454.518268 -301.885096)
					(mid 453.857868 -301.885096)
					(end 454.518268 -301.885096)
				)
			)
		)
	)
	(zone
		(layers "In1.Cu" "In2.Cu")
		(hatch none 0.5)
		(connect_pads
			(clearance 0)
		)
		(min_thickness 0.25)
		(keepout
			(tracks not_allowed)
			(vias allowed)
			(pads allowed)
			(copperpour not_allowed)
			(footprints allowed)
		)
		(placement
			(enabled no)
			(sheetname "")
		)
		(fill yes
			(thermal_gap 0.5)
			(thermal_bridge_width 0.5)
			(island_removal_mode 0)
		)
		(polygon
			(pts
				(arc
					(start 424.342306 -200.735184)
					(mid 423.681906 -200.735184)
					(end 424.342306 -200.735184)
				)
			)
		)
	)
	(zone
		(layers "In1.Cu" "In2.Cu")
		(hatch none 0.5)
		(connect_pads
			(clearance 0)
		)
		(min_thickness 0.25)
		(keepout
			(tracks not_allowed)
			(vias allowed)
			(pads allowed)
			(copperpour not_allowed)
			(footprints allowed)
		)
		(placement
			(enabled no)
			(sheetname "")
		)
		(fill yes
			(thermal_gap 0.5)
			(thermal_bridge_width 0.5)
			(island_removal_mode 0)
		)
		(polygon
			(pts
				(arc
					(start 29.582364 -284.885384)
					(mid 28.921964 -284.885384)
					(end 29.582364 -284.885384)
				)
			)
		)
	)
	(zone
		(layers "In1.Cu" "In2.Cu")
		(hatch none 0.5)
		(connect_pads
			(clearance 0)
		)
		(min_thickness 0.25)
		(keepout
			(tracks not_allowed)
			(vias allowed)
			(pads allowed)
			(copperpour not_allowed)
			(footprints allowed)
		)
		(placement
			(enabled no)
			(sheetname "")
		)
		(fill yes
			(thermal_gap 0.5)
			(thermal_bridge_width 0.5)
			(island_removal_mode 0)
		)
		(polygon
			(pts
				(arc
					(start 454.518268 -262.785098)
					(mid 453.857868 -262.785098)
					(end 454.518268 -262.785098)
				)
			)
		)
	)
	(zone
		(layers "In1.Cu" "In2.Cu")
		(hatch none 0.5)
		(connect_pads
			(clearance 0)
		)
		(min_thickness 0.25)
		(keepout
			(tracks not_allowed)
			(vias allowed)
			(pads allowed)
			(copperpour not_allowed)
			(footprints allowed)
		)
		(placement
			(enabled no)
			(sheetname "")
		)
		(fill yes
			(thermal_gap 0.5)
			(thermal_bridge_width 0.5)
			(island_removal_mode 0)
		)
		(polygon
			(pts
				(arc
					(start 194.934332 -268.735302)
					(mid 194.273932 -268.735302)
					(end 194.934332 -268.735302)
				)
			)
		)
	)
	(zone
		(layers "In1.Cu" "In2.Cu")
		(hatch none 0.5)
		(connect_pads
			(clearance 0)
		)
		(min_thickness 0.25)
		(keepout
			(tracks not_allowed)
			(vias allowed)
			(pads allowed)
			(copperpour not_allowed)
			(footprints allowed)
		)
		(placement
			(enabled no)
			(sheetname "")
		)
		(fill yes
			(thermal_gap 0.5)
			(thermal_bridge_width 0.5)
			(island_removal_mode 0)
		)
		(polygon
			(pts
				(arc
					(start 269.978378 -272.135092)
					(mid 269.317978 -272.135092)
					(end 269.978378 -272.135092)
				)
			)
		)
	)
	(zone
		(layers "In1.Cu" "In2.Cu")
		(hatch none 0.5)
		(connect_pads
			(clearance 0)
		)
		(min_thickness 0.25)
		(keepout
			(tracks not_allowed)
			(vias allowed)
			(pads allowed)
			(copperpour not_allowed)
			(footprints allowed)
		)
		(placement
			(enabled no)
			(sheetname "")
		)
		(fill yes
			(thermal_gap 0.5)
			(thermal_bridge_width 0.5)
			(island_removal_mode 0)
		)
		(polygon
			(pts
				(arc
					(start 33.026096 -230.485442)
					(mid 32.365696 -230.485442)
					(end 33.026096 -230.485442)
				)
			)
		)
	)
	(zone
		(layers "In1.Cu" "In2.Cu")
		(hatch none 0.5)
		(connect_pads
			(clearance 0)
		)
		(min_thickness 0.25)
		(keepout
			(tracks not_allowed)
			(vias allowed)
			(pads allowed)
			(copperpour not_allowed)
			(footprints allowed)
		)
		(placement
			(enabled no)
			(sheetname "")
		)
		(fill yes
			(thermal_gap 0.5)
			(thermal_bridge_width 0.5)
			(island_removal_mode 0)
		)
		(polygon
			(pts
				(arc
					(start 202.478132 -241.535204)
					(mid 201.817732 -241.535204)
					(end 202.478132 -241.535204)
				)
			)
		)
	)
	(zone
		(layers "In1.Cu" "In2.Cu")
		(hatch none 0.5)
		(connect_pads
			(clearance 0)
		)
		(min_thickness 0.25)
		(keepout
			(tracks not_allowed)
			(vias allowed)
			(pads allowed)
			(copperpour not_allowed)
			(footprints allowed)
		)
		(placement
			(enabled no)
			(sheetname "")
		)
		(fill yes
			(thermal_gap 0.5)
			(thermal_bridge_width 0.5)
			(island_removal_mode 0)
		)
		(polygon
			(pts
				(arc
					(start 176.402238 -244.08511)
					(mid 175.741838 -244.08511)
					(end 176.402238 -244.08511)
				)
			)
		)
	)
	(zone
		(layers "In1.Cu" "In2.Cu")
		(hatch none 0.5)
		(connect_pads
			(clearance 0)
		)
		(min_thickness 0.25)
		(keepout
			(tracks not_allowed)
			(vias allowed)
			(pads allowed)
			(copperpour not_allowed)
			(footprints allowed)
		)
		(placement
			(enabled no)
			(sheetname "")
		)
		(fill yes
			(thermal_gap 0.5)
			(thermal_bridge_width 0.5)
			(island_removal_mode 0)
		)
		(polygon
			(pts
				(arc
					(start 379.866652 -417.242244)
					(mid 379.88897 -417.296126)
					(end 379.942852 -417.318444)
				)
				(arc
					(start 380.138432 -417.318444)
					(mid 380.160308 -417.315312)
					(end 380.180342 -417.305998)
				)
				(arc
					(start 380.473966 -417.113466)
					(mid 380.515622 -417.101064)
					(end 380.557278 -417.113466)
				)
				(arc
					(start 380.852172 -417.305998)
					(mid 380.872096 -417.315234)
					(end 380.893828 -417.318444)
				)
				(arc
					(start 381.088392 -417.318444)
					(mid 381.142274 -417.296126)
					(end 381.164592 -417.242244)
				)
				(arc
					(start 381.164592 -416.556444)
					(mid 381.142274 -416.502562)
					(end 381.088392 -416.480244)
				)
				(arc
					(start 380.893828 -416.480244)
					(mid 380.872084 -416.483412)
					(end 380.852172 -416.49269)
				)
				(arc
					(start 380.556008 -416.685476)
					(mid 380.514324 -416.697698)
					(end 380.472696 -416.685222)
				)
				(arc
					(start 380.179072 -416.49269)
					(mid 380.159148 -416.483454)
					(end 380.137416 -416.480244)
				)
				(arc
					(start 379.942852 -416.480244)
					(mid 379.88897 -416.502562)
					(end 379.866652 -416.556444)
				)
			)
		)
	)
	(zone
		(layers "In1.Cu" "In2.Cu")
		(hatch none 0.5)
		(connect_pads
			(clearance 0)
		)
		(min_thickness 0.25)
		(keepout
			(tracks not_allowed)
			(vias allowed)
			(pads allowed)
			(copperpour not_allowed)
			(footprints allowed)
		)
		(placement
			(enabled no)
			(sheetname "")
		)
		(fill yes
			(thermal_gap 0.5)
			(thermal_bridge_width 0.5)
			(island_removal_mode 0)
		)
		(polygon
			(pts
				(arc
					(start 277.522432 -199.035162)
					(mid 276.862032 -199.035162)
					(end 277.522432 -199.035162)
				)
			)
		)
	)
	(zone
		(layers "In1.Cu" "In2.Cu")
		(hatch none 0.5)
		(connect_pads
			(clearance 0)
		)
		(min_thickness 0.25)
		(keepout
			(tracks not_allowed)
			(vias allowed)
			(pads allowed)
			(copperpour not_allowed)
			(footprints allowed)
		)
		(placement
			(enabled no)
			(sheetname "")
		)
		(fill yes
			(thermal_gap 0.5)
			(thermal_bridge_width 0.5)
			(island_removal_mode 0)
		)
		(polygon
			(pts
				(arc
					(start 25.482296 -251.735336)
					(mid 24.821896 -251.735336)
					(end 25.482296 -251.735336)
				)
			)
		)
	)
	(zone
		(layers "In1.Cu" "In2.Cu")
		(hatch none 0.5)
		(connect_pads
			(clearance 0)
		)
		(min_thickness 0.25)
		(keepout
			(tracks not_allowed)
			(vias allowed)
			(pads allowed)
			(copperpour not_allowed)
			(footprints allowed)
		)
		(placement
			(enabled no)
			(sheetname "")
		)
		(fill yes
			(thermal_gap 0.5)
			(thermal_bridge_width 0.5)
			(island_removal_mode 0)
		)
		(polygon
			(pts
				(arc
					(start 27.85237 -7.672324)
					(mid 27.874688 -7.618442)
					(end 27.92857 -7.596124)
				)
				(arc
					(start 28.965144 -7.596124)
					(mid 29.019026 -7.618442)
					(end 29.041344 -7.672324)
				)
				(arc
					(start 29.041344 -9.071864)
					(mid 29.019026 -9.125746)
					(end 28.965144 -9.148064)
				)
				(arc
					(start 27.92857 -9.148064)
					(mid 27.874688 -9.125746)
					(end 27.85237 -9.071864)
				)
			)
		)
	)
	(zone
		(layers "In1.Cu" "In2.Cu")
		(hatch none 0.5)
		(connect_pads
			(clearance 0)
		)
		(min_thickness 0.25)
		(keepout
			(tracks not_allowed)
			(vias allowed)
			(pads allowed)
			(copperpour not_allowed)
			(footprints allowed)
		)
		(placement
			(enabled no)
			(sheetname "")
		)
		(fill yes
			(thermal_gap 0.5)
			(thermal_bridge_width 0.5)
			(island_removal_mode 0)
		)
		(polygon
			(pts
				(arc
					(start 442.8744 -227.935028)
					(mid 442.214 -227.935028)
					(end 442.8744 -227.935028)
				)
			)
		)
	)
	(zone
		(layers "In1.Cu" "In2.Cu")
		(hatch none 0.5)
		(connect_pads
			(clearance 0)
		)
		(min_thickness 0.25)
		(keepout
			(tracks not_allowed)
			(vias allowed)
			(pads allowed)
			(copperpour not_allowed)
			(footprints allowed)
		)
		(placement
			(enabled no)
			(sheetname "")
		)
		(fill yes
			(thermal_gap 0.5)
			(thermal_bridge_width 0.5)
			(island_removal_mode 0)
		)
		(polygon
			(pts
				(arc
					(start 52.214272 -296.785284)
					(mid 51.553872 -296.785284)
					(end 52.214272 -296.785284)
				)
			)
		)
	)
	(zone
		(layers "In1.Cu" "In2.Cu")
		(hatch none 0.5)
		(connect_pads
			(clearance 0)
		)
		(min_thickness 0.25)
		(keepout
			(tracks not_allowed)
			(vias allowed)
			(pads allowed)
			(copperpour not_allowed)
			(footprints allowed)
		)
		(placement
			(enabled no)
			(sheetname "")
		)
		(fill yes
			(thermal_gap 0.5)
			(thermal_bridge_width 0.5)
			(island_removal_mode 0)
		)
		(polygon
			(pts
				(arc
					(start 25.482296 -314.635388)
					(mid 24.821896 -314.635388)
					(end 25.482296 -314.635388)
				)
			)
		)
	)
	(zone
		(layers "In1.Cu" "In2.Cu")
		(hatch none 0.5)
		(connect_pads
			(clearance 0)
		)
		(min_thickness 0.25)
		(keepout
			(tracks not_allowed)
			(vias allowed)
			(pads allowed)
			(copperpour not_allowed)
			(footprints allowed)
		)
		(placement
			(enabled no)
			(sheetname "")
		)
		(fill yes
			(thermal_gap 0.5)
			(thermal_bridge_width 0.5)
			(island_removal_mode 0)
		)
		(polygon
			(pts
				(arc
					(start 442.8744 -276.38502)
					(mid 442.214 -276.38502)
					(end 442.8744 -276.38502)
				)
			)
		)
	)
	(zone
		(layers "In1.Cu" "In2.Cu")
		(hatch none 0.5)
		(connect_pads
			(clearance 0)
		)
		(min_thickness 0.25)
		(keepout
			(tracks not_allowed)
			(vias allowed)
			(pads allowed)
			(copperpour not_allowed)
			(footprints allowed)
		)
		(placement
			(enabled no)
			(sheetname "")
		)
		(fill yes
			(thermal_gap 0.5)
			(thermal_bridge_width 0.5)
			(island_removal_mode 0)
		)
		(polygon
			(pts
				(arc
					(start 269.978378 -307.835046)
					(mid 269.317978 -307.835046)
					(end 269.978378 -307.835046)
				)
			)
		)
	)
	(zone
		(layers "In1.Cu" "In2.Cu")
		(hatch none 0.5)
		(connect_pads
			(clearance 0)
		)
		(min_thickness 0.25)
		(keepout
			(tracks not_allowed)
			(vias allowed)
			(pads allowed)
			(copperpour not_allowed)
			(footprints allowed)
		)
		(placement
			(enabled no)
			(sheetname "")
		)
		(fill yes
			(thermal_gap 0.5)
			(thermal_bridge_width 0.5)
			(island_removal_mode 0)
		)
		(polygon
			(pts
				(arc
					(start 439.430414 -203.28509)
					(mid 438.770014 -203.28509)
					(end 439.430414 -203.28509)
				)
			)
		)
	)
	(zone
		(layers "In1.Cu" "In2.Cu")
		(hatch none 0.5)
		(connect_pads
			(clearance 0)
		)
		(min_thickness 0.25)
		(keepout
			(tracks not_allowed)
			(vias allowed)
			(pads allowed)
			(copperpour not_allowed)
			(footprints allowed)
		)
		(placement
			(enabled no)
			(sheetname "")
		)
		(fill yes
			(thermal_gap 0.5)
			(thermal_bridge_width 0.5)
			(island_removal_mode 0)
		)
		(polygon
			(pts
				(arc
					(start 194.934332 -282.335224)
					(mid 194.273932 -282.335224)
					(end 194.934332 -282.335224)
				)
			)
		)
	)
	(zone
		(layers "In1.Cu" "In2.Cu")
		(hatch none 0.5)
		(connect_pads
			(clearance 0)
		)
		(min_thickness 0.25)
		(keepout
			(tracks not_allowed)
			(vias allowed)
			(pads allowed)
			(copperpour not_allowed)
			(footprints allowed)
		)
		(placement
			(enabled no)
			(sheetname "")
		)
		(fill yes
			(thermal_gap 0.5)
			(thermal_bridge_width 0.5)
			(island_removal_mode 0)
		)
		(polygon
			(pts
				(arc
					(start 439.430414 -266.185142)
					(mid 438.770014 -266.185142)
					(end 439.430414 -266.185142)
				)
			)
		)
	)
	(zone
		(layers "In1.Cu" "In2.Cu")
		(hatch none 0.5)
		(connect_pads
			(clearance 0)
		)
		(min_thickness 0.25)
		(keepout
			(tracks not_allowed)
			(vias allowed)
			(pads allowed)
			(copperpour not_allowed)
			(footprints allowed)
		)
		(placement
			(enabled no)
			(sheetname "")
		)
		(fill yes
			(thermal_gap 0.5)
			(thermal_bridge_width 0.5)
			(island_removal_mode 0)
		)
		(polygon
			(pts
				(arc
					(start 187.390278 -224.535238)
					(mid 186.729878 -224.535238)
					(end 187.390278 -224.535238)
				)
			)
		)
	)
	(zone
		(layers "In1.Cu" "In2.Cu")
		(hatch none 0.5)
		(connect_pads
			(clearance 0)
		)
		(min_thickness 0.25)
		(keepout
			(tracks not_allowed)
			(vias allowed)
			(pads allowed)
			(copperpour not_allowed)
			(footprints allowed)
		)
		(placement
			(enabled no)
			(sheetname "")
		)
		(fill yes
			(thermal_gap 0.5)
			(thermal_bridge_width 0.5)
			(island_removal_mode 0)
		)
		(polygon
			(pts
				(arc
					(start 450.4182 -227.935028)
					(mid 449.7578 -227.935028)
					(end 450.4182 -227.935028)
				)
			)
		)
	)
	(zone
		(layers "In1.Cu" "In2.Cu")
		(hatch none 0.5)
		(connect_pads
			(clearance 0)
		)
		(min_thickness 0.25)
		(keepout
			(tracks not_allowed)
			(vias allowed)
			(pads allowed)
			(copperpour not_allowed)
			(footprints allowed)
		)
		(placement
			(enabled no)
			(sheetname "")
		)
		(fill yes
			(thermal_gap 0.5)
			(thermal_bridge_width 0.5)
			(island_removal_mode 0)
		)
		(polygon
			(pts
				(arc
					(start 442.8744 -199.885046)
					(mid 442.214 -199.885046)
					(end 442.8744 -199.885046)
				)
			)
		)
	)
	(zone
		(layers "In1.Cu" "In2.Cu")
		(hatch none 0.5)
		(connect_pads
			(clearance 0)
		)
		(min_thickness 0.25)
		(keepout
			(tracks not_allowed)
			(vias allowed)
			(pads allowed)
			(copperpour not_allowed)
			(footprints allowed)
		)
		(placement
			(enabled no)
			(sheetname "")
		)
		(fill yes
			(thermal_gap 0.5)
			(thermal_bridge_width 0.5)
			(island_removal_mode 0)
		)
		(polygon
			(pts
				(arc
					(start 277.522432 -266.185142)
					(mid 276.862032 -266.185142)
					(end 277.522432 -266.185142)
				)
			)
		)
	)
	(zone
		(layers "In1.Cu" "In2.Cu")
		(hatch none 0.5)
		(connect_pads
			(clearance 0)
		)
		(min_thickness 0.25)
		(keepout
			(tracks not_allowed)
			(vias allowed)
			(pads allowed)
			(copperpour not_allowed)
			(footprints allowed)
		)
		(placement
			(enabled no)
			(sheetname "")
		)
		(fill yes
			(thermal_gap 0.5)
			(thermal_bridge_width 0.5)
			(island_removal_mode 0)
		)
		(polygon
			(pts
				(arc
					(start 191.490346 -244.085364)
					(mid 190.829946 -244.085364)
					(end 191.490346 -244.085364)
				)
			)
		)
	)
	(zone
		(layers "In1.Cu" "In2.Cu")
		(hatch none 0.5)
		(connect_pads
			(clearance 0)
		)
		(min_thickness 0.25)
		(keepout
			(tracks not_allowed)
			(vias allowed)
			(pads allowed)
			(copperpour not_allowed)
			(footprints allowed)
		)
		(placement
			(enabled no)
			(sheetname "")
		)
		(fill yes
			(thermal_gap 0.5)
			(thermal_bridge_width 0.5)
			(island_removal_mode 0)
		)
		(polygon
			(pts
				(arc
					(start 183.946292 -227.085398)
					(mid 183.285892 -227.085398)
					(end 183.946292 -227.085398)
				)
			)
		)
	)
	(zone
		(layers "In1.Cu" "In2.Cu")
		(hatch none 0.5)
		(connect_pads
			(clearance 0)
		)
		(min_thickness 0.25)
		(keepout
			(tracks not_allowed)
			(vias allowed)
			(pads allowed)
			(copperpour not_allowed)
			(footprints allowed)
		)
		(placement
			(enabled no)
			(sheetname "")
		)
		(fill yes
			(thermal_gap 0.5)
			(thermal_bridge_width 0.5)
			(island_removal_mode 0)
		)
		(polygon
			(pts
				(arc
					(start 273.422364 -209.23504)
					(mid 272.761964 -209.23504)
					(end 273.422364 -209.23504)
				)
			)
		)
	)
	(zone
		(layers "In1.Cu" "In2.Cu")
		(hatch none 0.5)
		(connect_pads
			(clearance 0)
		)
		(min_thickness 0.25)
		(keepout
			(tracks not_allowed)
			(vias allowed)
			(pads allowed)
			(copperpour not_allowed)
			(footprints allowed)
		)
		(placement
			(enabled no)
			(sheetname "")
		)
		(fill yes
			(thermal_gap 0.5)
			(thermal_bridge_width 0.5)
			(island_removal_mode 0)
		)
		(polygon
			(pts
				(arc
					(start 202.478132 -265.335258)
					(mid 201.817732 -265.335258)
					(end 202.478132 -265.335258)
				)
			)
		)
	)
	(zone
		(layers "In1.Cu" "In2.Cu")
		(hatch none 0.5)
		(connect_pads
			(clearance 0)
		)
		(min_thickness 0.25)
		(keepout
			(tracks not_allowed)
			(vias allowed)
			(pads allowed)
			(copperpour not_allowed)
			(footprints allowed)
		)
		(placement
			(enabled no)
			(sheetname "")
		)
		(fill yes
			(thermal_gap 0.5)
			(thermal_bridge_width 0.5)
			(island_removal_mode 0)
		)
		(polygon
			(pts
				(arc
					(start 172.30217 -210.935316)
					(mid 171.64177 -210.935316)
					(end 172.30217 -210.935316)
				)
			)
		)
	)
	(zone
		(layers "In1.Cu" "In2.Cu")
		(hatch none 0.5)
		(connect_pads
			(clearance 0)
		)
		(min_thickness 0.25)
		(keepout
			(tracks not_allowed)
			(vias allowed)
			(pads allowed)
			(copperpour not_allowed)
			(footprints allowed)
		)
		(placement
			(enabled no)
			(sheetname "")
		)
		(fill yes
			(thermal_gap 0.5)
			(thermal_bridge_width 0.5)
			(island_removal_mode 0)
		)
		(polygon
			(pts
				(arc
					(start 199.0344 -275.53539)
					(mid 198.374 -275.53539)
					(end 199.0344 -275.53539)
				)
			)
		)
	)
	(zone
		(layers "In1.Cu" "In2.Cu")
		(hatch none 0.5)
		(connect_pads
			(clearance 0)
		)
		(min_thickness 0.25)
		(keepout
			(tracks not_allowed)
			(vias allowed)
			(pads allowed)
			(copperpour not_allowed)
			(footprints allowed)
		)
		(placement
			(enabled no)
			(sheetname "")
		)
		(fill yes
			(thermal_gap 0.5)
			(thermal_bridge_width 0.5)
			(island_removal_mode 0)
		)
		(polygon
			(pts
				(arc
					(start 269.978378 -203.28509)
					(mid 269.317978 -203.28509)
					(end 269.978378 -203.28509)
				)
			)
		)
	)
	(zone
		(layers "In1.Cu" "In2.Cu")
		(hatch none 0.5)
		(connect_pads
			(clearance 0)
		)
		(min_thickness 0.25)
		(keepout
			(tracks not_allowed)
			(vias allowed)
			(pads allowed)
			(copperpour not_allowed)
			(footprints allowed)
		)
		(placement
			(enabled no)
			(sheetname "")
		)
		(fill yes
			(thermal_gap 0.5)
			(thermal_bridge_width 0.5)
			(island_removal_mode 0)
		)
		(polygon
			(pts
				(arc
					(start 29.582364 -267.885418)
					(mid 28.921964 -267.885418)
					(end 29.582364 -267.885418)
				)
			)
		)
	)
	(zone
		(layers "In1.Cu" "In2.Cu")
		(hatch none 0.5)
		(connect_pads
			(clearance 0)
		)
		(min_thickness 0.25)
		(keepout
			(tracks not_allowed)
			(vias allowed)
			(pads allowed)
			(copperpour not_allowed)
			(footprints allowed)
		)
		(placement
			(enabled no)
			(sheetname "")
		)
		(fill yes
			(thermal_gap 0.5)
			(thermal_bridge_width 0.5)
			(island_removal_mode 0)
		)
		(polygon
			(pts
				(arc
					(start 277.522432 -298.485052)
					(mid 276.862032 -298.485052)
					(end 277.522432 -298.485052)
				)
			)
		)
	)
	(zone
		(layers "In1.Cu" "In2.Cu")
		(hatch none 0.5)
		(connect_pads
			(clearance 0)
		)
		(min_thickness 0.25)
		(keepout
			(tracks not_allowed)
			(vias allowed)
			(pads allowed)
			(copperpour not_allowed)
			(footprints allowed)
		)
		(placement
			(enabled no)
			(sheetname "")
		)
		(fill yes
			(thermal_gap 0.5)
			(thermal_bridge_width 0.5)
			(island_removal_mode 0)
		)
		(polygon
			(pts
				(arc
					(start 296.054272 -312.084974)
					(mid 295.393872 -312.084974)
					(end 296.054272 -312.084974)
				)
			)
		)
	)
	(zone
		(layers "In1.Cu" "In2.Cu")
		(hatch none 0.5)
		(connect_pads
			(clearance 0)
		)
		(min_thickness 0.25)
		(keepout
			(tracks not_allowed)
			(vias allowed)
			(pads allowed)
			(copperpour not_allowed)
			(footprints allowed)
		)
		(placement
			(enabled no)
			(sheetname "")
		)
		(fill yes
			(thermal_gap 0.5)
			(thermal_bridge_width 0.5)
			(island_removal_mode 0)
		)
		(polygon
			(pts
				(arc
					(start 269.978378 -306.135024)
					(mid 269.317978 -306.135024)
					(end 269.978378 -306.135024)
				)
			)
		)
	)
	(zone
		(layers "In1.Cu" "In2.Cu")
		(hatch none 0.5)
		(connect_pads
			(clearance 0)
		)
		(min_thickness 0.25)
		(keepout
			(tracks not_allowed)
			(vias allowed)
			(pads allowed)
			(copperpour not_allowed)
			(footprints allowed)
		)
		(placement
			(enabled no)
			(sheetname "")
		)
		(fill yes
			(thermal_gap 0.5)
			(thermal_bridge_width 0.5)
			(island_removal_mode 0)
		)
		(polygon
			(pts
				(arc
					(start 292.610286 -247.485154)
					(mid 291.949886 -247.485154)
					(end 292.610286 -247.485154)
				)
			)
		)
	)
	(zone
		(layers "In1.Cu" "In2.Cu")
		(hatch none 0.5)
		(connect_pads
			(clearance 0)
		)
		(min_thickness 0.25)
		(keepout
			(tracks not_allowed)
			(vias allowed)
			(pads allowed)
			(copperpour not_allowed)
			(footprints allowed)
		)
		(placement
			(enabled no)
			(sheetname "")
		)
		(fill yes
			(thermal_gap 0.5)
			(thermal_bridge_width 0.5)
			(island_removal_mode 0)
		)
		(polygon
			(pts
				(arc
					(start 269.978378 -236.435138)
					(mid 269.317978 -236.435138)
					(end 269.978378 -236.435138)
				)
			)
		)
	)
	(zone
		(layers "In1.Cu" "In2.Cu")
		(hatch none 0.5)
		(connect_pads
			(clearance 0)
		)
		(min_thickness 0.25)
		(keepout
			(tracks not_allowed)
			(vias allowed)
			(pads allowed)
			(copperpour not_allowed)
			(footprints allowed)
		)
		(placement
			(enabled no)
			(sheetname "")
		)
		(fill yes
			(thermal_gap 0.5)
			(thermal_bridge_width 0.5)
			(island_removal_mode 0)
		)
		(polygon
			(pts
				(arc
					(start 191.490346 -301.88535)
					(mid 190.829946 -301.88535)
					(end 191.490346 -301.88535)
				)
			)
		)
	)
	(zone
		(layers "In1.Cu" "In2.Cu")
		(hatch none 0.5)
		(connect_pads
			(clearance 0)
		)
		(min_thickness 0.25)
		(keepout
			(tracks not_allowed)
			(vias allowed)
			(pads allowed)
			(copperpour not_allowed)
			(footprints allowed)
		)
		(placement
			(enabled no)
			(sheetname "")
		)
		(fill yes
			(thermal_gap 0.5)
			(thermal_bridge_width 0.5)
			(island_removal_mode 0)
		)
		(polygon
			(pts
				(arc
					(start 420.242238 -213.484968)
					(mid 419.581838 -213.484968)
					(end 420.242238 -213.484968)
				)
			)
		)
	)
	(zone
		(layers "In1.Cu" "In2.Cu")
		(hatch none 0.5)
		(connect_pads
			(clearance 0)
		)
		(min_thickness 0.25)
		(keepout
			(tracks not_allowed)
			(vias allowed)
			(pads allowed)
			(copperpour not_allowed)
			(footprints allowed)
		)
		(placement
			(enabled no)
			(sheetname "")
		)
		(fill yes
			(thermal_gap 0.5)
			(thermal_bridge_width 0.5)
			(island_removal_mode 0)
		)
		(polygon
			(pts
				(arc
					(start 269.978378 -285.735014)
					(mid 269.317978 -285.735014)
					(end 269.978378 -285.735014)
				)
			)
		)
	)
	(zone
		(layers "In1.Cu" "In2.Cu")
		(hatch none 0.5)
		(connect_pads
			(clearance 0)
		)
		(min_thickness 0.25)
		(keepout
			(tracks not_allowed)
			(vias allowed)
			(pads allowed)
			(copperpour not_allowed)
			(footprints allowed)
		)
		(placement
			(enabled no)
			(sheetname "")
		)
		(fill yes
			(thermal_gap 0.5)
			(thermal_bridge_width 0.5)
			(island_removal_mode 0)
		)
		(polygon
			(pts
				(arc
					(start 17.938242 -314.635388)
					(mid 17.277842 -314.635388)
					(end 17.938242 -314.635388)
				)
			)
		)
	)
	(zone
		(layers "In1.Cu" "In2.Cu")
		(hatch none 0.5)
		(connect_pads
			(clearance 0)
		)
		(min_thickness 0.25)
		(keepout
			(tracks not_allowed)
			(vias allowed)
			(pads allowed)
			(copperpour not_allowed)
			(footprints allowed)
		)
		(placement
			(enabled no)
			(sheetname "")
		)
		(fill yes
			(thermal_gap 0.5)
			(thermal_bridge_width 0.5)
			(island_removal_mode 0)
		)
		(polygon
			(pts
				(arc
					(start 29.582364 -279.785318)
					(mid 28.921964 -279.785318)
					(end 29.582364 -279.785318)
				)
			)
		)
	)
	(zone
		(layers "In1.Cu" "In2.Cu")
		(hatch none 0.5)
		(connect_pads
			(clearance 0)
		)
		(min_thickness 0.25)
		(keepout
			(tracks not_allowed)
			(vias allowed)
			(pads allowed)
			(copperpour not_allowed)
			(footprints allowed)
		)
		(placement
			(enabled no)
			(sheetname "")
		)
		(fill yes
			(thermal_gap 0.5)
			(thermal_bridge_width 0.5)
			(island_removal_mode 0)
		)
		(polygon
			(pts
				(arc
					(start 435.330346 -198.185024)
					(mid 434.669946 -198.185024)
					(end 435.330346 -198.185024)
				)
			)
		)
	)
	(zone
		(layers "In1.Cu" "In2.Cu")
		(hatch none 0.5)
		(connect_pads
			(clearance 0)
		)
		(min_thickness 0.25)
		(keepout
			(tracks not_allowed)
			(vias allowed)
			(pads allowed)
			(copperpour not_allowed)
			(footprints allowed)
		)
		(placement
			(enabled no)
			(sheetname "")
		)
		(fill yes
			(thermal_gap 0.5)
			(thermal_bridge_width 0.5)
			(island_removal_mode 0)
		)
		(polygon
			(pts
				(arc
					(start 269.978378 -313.784996)
					(mid 269.317978 -313.784996)
					(end 269.978378 -313.784996)
				)
			)
		)
	)
	(zone
		(layers "In1.Cu" "In2.Cu")
		(hatch none 0.5)
		(connect_pads
			(clearance 0)
		)
		(min_thickness 0.25)
		(keepout
			(tracks not_allowed)
			(vias allowed)
			(pads allowed)
			(copperpour not_allowed)
			(footprints allowed)
		)
		(placement
			(enabled no)
			(sheetname "")
		)
		(fill yes
			(thermal_gap 0.5)
			(thermal_bridge_width 0.5)
			(island_removal_mode 0)
		)
		(polygon
			(pts
				(arc
					(start 296.054272 -280.634948)
					(mid 295.393872 -280.634948)
					(end 296.054272 -280.634948)
				)
			)
		)
	)
	(zone
		(layers "In1.Cu" "In2.Cu")
		(hatch none 0.5)
		(connect_pads
			(clearance 0)
		)
		(min_thickness 0.25)
		(keepout
			(tracks not_allowed)
			(vias allowed)
			(pads allowed)
			(copperpour not_allowed)
			(footprints allowed)
		)
		(placement
			(enabled no)
			(sheetname "")
		)
		(fill yes
			(thermal_gap 0.5)
			(thermal_bridge_width 0.5)
			(island_removal_mode 0)
		)
		(polygon
			(pts
				(arc
					(start 44.670218 -204.985366)
					(mid 44.009818 -204.985366)
					(end 44.670218 -204.985366)
				)
			)
		)
	)
	(zone
		(layers "In1.Cu" "In2.Cu")
		(hatch none 0.5)
		(connect_pads
			(clearance 0)
		)
		(min_thickness 0.25)
		(keepout
			(tracks not_allowed)
			(vias allowed)
			(pads allowed)
			(copperpour not_allowed)
			(footprints allowed)
		)
		(placement
			(enabled no)
			(sheetname "")
		)
		(fill yes
			(thermal_gap 0.5)
			(thermal_bridge_width 0.5)
			(island_removal_mode 0)
		)
		(polygon
			(pts
				(arc
					(start 183.946292 -233.035348)
					(mid 183.285892 -233.035348)
					(end 183.946292 -233.035348)
				)
			)
		)
	)
	(zone
		(layers "In1.Cu" "In2.Cu")
		(hatch none 0.5)
		(connect_pads
			(clearance 0)
		)
		(min_thickness 0.25)
		(keepout
			(tracks not_allowed)
			(vias allowed)
			(pads allowed)
			(copperpour not_allowed)
			(footprints allowed)
		)
		(placement
			(enabled no)
			(sheetname "")
		)
		(fill yes
			(thermal_gap 0.5)
			(thermal_bridge_width 0.5)
			(island_removal_mode 0)
		)
		(polygon
			(pts
				(arc
					(start 172.30217 -316.33541)
					(mid 171.64177 -316.33541)
					(end 172.30217 -316.33541)
				)
			)
		)
	)
	(zone
		(layers "In1.Cu" "In2.Cu")
		(hatch none 0.5)
		(connect_pads
			(clearance 0)
		)
		(min_thickness 0.25)
		(keepout
			(tracks not_allowed)
			(vias allowed)
			(pads allowed)
			(copperpour not_allowed)
			(footprints allowed)
		)
		(placement
			(enabled no)
			(sheetname "")
		)
		(fill yes
			(thermal_gap 0.5)
			(thermal_bridge_width 0.5)
			(island_removal_mode 0)
		)
		(polygon
			(pts
				(arc
					(start 280.966164 -224.534984)
					(mid 280.305764 -224.534984)
					(end 280.966164 -224.534984)
				)
			)
		)
	)
	(zone
		(layers "In1.Cu" "In2.Cu")
		(hatch none 0.5)
		(connect_pads
			(clearance 0)
		)
		(min_thickness 0.25)
		(keepout
			(tracks not_allowed)
			(vias allowed)
			(pads allowed)
			(copperpour not_allowed)
			(footprints allowed)
		)
		(placement
			(enabled no)
			(sheetname "")
		)
		(fill yes
			(thermal_gap 0.5)
			(thermal_bridge_width 0.5)
			(island_removal_mode 0)
		)
		(polygon
			(pts
				(arc
					(start 450.4182 -198.185024)
					(mid 449.7578 -198.185024)
					(end 450.4182 -198.185024)
				)
			)
		)
	)
	(zone
		(layers "In1.Cu" "In2.Cu")
		(hatch none 0.5)
		(connect_pads
			(clearance 0)
		)
		(min_thickness 0.25)
		(keepout
			(tracks not_allowed)
			(vias allowed)
			(pads allowed)
			(copperpour not_allowed)
			(footprints allowed)
		)
		(placement
			(enabled no)
			(sheetname "")
		)
		(fill yes
			(thermal_gap 0.5)
			(thermal_bridge_width 0.5)
			(island_removal_mode 0)
		)
		(polygon
			(pts
				(arc
					(start 424.342306 -254.284988)
					(mid 423.681906 -254.284988)
					(end 424.342306 -254.284988)
				)
			)
		)
	)
	(zone
		(layers "In1.Cu" "In2.Cu")
		(hatch none 0.5)
		(connect_pads
			(clearance 0)
		)
		(min_thickness 0.25)
		(keepout
			(tracks not_allowed)
			(vias allowed)
			(pads allowed)
			(copperpour not_allowed)
			(footprints allowed)
		)
		(placement
			(enabled no)
			(sheetname "")
		)
		(fill yes
			(thermal_gap 0.5)
			(thermal_bridge_width 0.5)
			(island_removal_mode 0)
		)
		(polygon
			(pts
				(arc
					(start 300.15434 -208.385156)
					(mid 299.49394 -208.385156)
					(end 300.15434 -208.385156)
				)
			)
		)
	)
	(zone
		(layers "In1.Cu" "In2.Cu")
		(hatch none 0.5)
		(connect_pads
			(clearance 0)
		)
		(min_thickness 0.25)
		(keepout
			(tracks not_allowed)
			(vias allowed)
			(pads allowed)
			(copperpour not_allowed)
			(footprints allowed)
		)
		(placement
			(enabled no)
			(sheetname "")
		)
		(fill yes
			(thermal_gap 0.5)
			(thermal_bridge_width 0.5)
			(island_removal_mode 0)
		)
		(polygon
			(pts
				(arc
					(start 439.430414 -200.735184)
					(mid 438.770014 -200.735184)
					(end 439.430414 -200.735184)
				)
			)
		)
	)
	(zone
		(layers "In1.Cu" "In2.Cu")
		(hatch none 0.5)
		(connect_pads
			(clearance 0)
		)
		(min_thickness 0.25)
		(keepout
			(tracks not_allowed)
			(vias allowed)
			(pads allowed)
			(copperpour not_allowed)
			(footprints allowed)
		)
		(placement
			(enabled no)
			(sheetname "")
		)
		(fill yes
			(thermal_gap 0.5)
			(thermal_bridge_width 0.5)
			(island_removal_mode 0)
		)
		(polygon
			(pts
				(arc
					(start 280.966164 -261.93496)
					(mid 280.305764 -261.93496)
					(end 280.966164 -261.93496)
				)
			)
		)
	)
	(zone
		(layers "In1.Cu" "In2.Cu")
		(hatch none 0.5)
		(connect_pads
			(clearance 0)
		)
		(min_thickness 0.25)
		(keepout
			(tracks not_allowed)
			(vias allowed)
			(pads allowed)
			(copperpour not_allowed)
			(footprints allowed)
		)
		(placement
			(enabled no)
			(sheetname "")
		)
		(fill yes
			(thermal_gap 0.5)
			(thermal_bridge_width 0.5)
			(island_removal_mode 0)
		)
		(polygon
			(pts
				(arc
					(start 300.15434 -204.985112)
					(mid 299.49394 -204.985112)
					(end 300.15434 -204.985112)
				)
			)
		)
	)
	(zone
		(layers "In1.Cu" "In2.Cu")
		(hatch none 0.5)
		(connect_pads
			(clearance 0)
		)
		(min_thickness 0.25)
		(keepout
			(tracks not_allowed)
			(vias allowed)
			(pads allowed)
			(copperpour not_allowed)
			(footprints allowed)
		)
		(placement
			(enabled no)
			(sheetname "")
		)
		(fill yes
			(thermal_gap 0.5)
			(thermal_bridge_width 0.5)
			(island_removal_mode 0)
		)
		(polygon
			(pts
				(arc
					(start 199.0344 -317.185294)
					(mid 198.374 -317.185294)
					(end 199.0344 -317.185294)
				)
			)
		)
	)
	(zone
		(layers "In1.Cu" "In2.Cu")
		(hatch none 0.5)
		(connect_pads
			(clearance 0)
		)
		(min_thickness 0.25)
		(keepout
			(tracks not_allowed)
			(vias allowed)
			(pads allowed)
			(copperpour not_allowed)
			(footprints allowed)
		)
		(placement
			(enabled no)
			(sheetname "")
		)
		(fill yes
			(thermal_gap 0.5)
			(thermal_bridge_width 0.5)
			(island_removal_mode 0)
		)
		(polygon
			(pts
				(arc
					(start 52.214272 -281.48534)
					(mid 51.553872 -281.48534)
					(end 52.214272 -281.48534)
				)
			)
		)
	)
	(zone
		(layers "In1.Cu" "In2.Cu")
		(hatch none 0.5)
		(connect_pads
			(clearance 0)
		)
		(min_thickness 0.25)
		(keepout
			(tracks not_allowed)
			(vias allowed)
			(pads allowed)
			(copperpour not_allowed)
			(footprints allowed)
		)
		(placement
			(enabled no)
			(sheetname "")
		)
		(fill yes
			(thermal_gap 0.5)
			(thermal_bridge_width 0.5)
			(island_removal_mode 0)
		)
		(polygon
			(pts
				(arc
					(start 48.114204 -238.985298)
					(mid 47.453804 -238.985298)
					(end 48.114204 -238.985298)
				)
			)
		)
	)
	(zone
		(layers "In1.Cu" "In2.Cu")
		(hatch none 0.5)
		(connect_pads
			(clearance 0)
		)
		(min_thickness 0.25)
		(keepout
			(tracks not_allowed)
			(vias allowed)
			(pads allowed)
			(copperpour not_allowed)
			(footprints allowed)
		)
		(placement
			(enabled no)
			(sheetname "")
		)
		(fill yes
			(thermal_gap 0.5)
			(thermal_bridge_width 0.5)
			(island_removal_mode 0)
		)
		(polygon
			(pts
				(arc
					(start 296.054272 -310.384952)
					(mid 295.393872 -310.384952)
					(end 296.054272 -310.384952)
				)
			)
		)
	)
	(zone
		(layers "In1.Cu" "In2.Cu")
		(hatch none 0.5)
		(connect_pads
			(clearance 0)
		)
		(min_thickness 0.25)
		(keepout
			(tracks not_allowed)
			(vias allowed)
			(pads allowed)
			(copperpour not_allowed)
			(footprints allowed)
		)
		(placement
			(enabled no)
			(sheetname "")
		)
		(fill yes
			(thermal_gap 0.5)
			(thermal_bridge_width 0.5)
			(island_removal_mode 0)
		)
		(polygon
			(pts
				(arc
					(start 52.214272 -290.835334)
					(mid 51.553872 -290.835334)
					(end 52.214272 -290.835334)
				)
			)
		)
	)
	(zone
		(layers "In1.Cu" "In2.Cu")
		(hatch none 0.5)
		(connect_pads
			(clearance 0)
		)
		(min_thickness 0.25)
		(keepout
			(tracks not_allowed)
			(vias allowed)
			(pads allowed)
			(copperpour not_allowed)
			(footprints allowed)
		)
		(placement
			(enabled no)
			(sheetname "")
		)
		(fill yes
			(thermal_gap 0.5)
			(thermal_bridge_width 0.5)
			(island_removal_mode 0)
		)
		(polygon
			(pts
				(arc
					(start 450.4182 -246.635016)
					(mid 449.7578 -246.635016)
					(end 450.4182 -246.635016)
				)
			)
		)
	)
	(zone
		(layers "In1.Cu" "In2.Cu")
		(hatch none 0.5)
		(connect_pads
			(clearance 0)
		)
		(min_thickness 0.25)
		(keepout
			(tracks not_allowed)
			(vias allowed)
			(pads allowed)
			(copperpour not_allowed)
			(footprints allowed)
		)
		(placement
			(enabled no)
			(sheetname "")
		)
		(fill yes
			(thermal_gap 0.5)
			(thermal_bridge_width 0.5)
			(island_removal_mode 0)
		)
		(polygon
			(pts
				(arc
					(start 183.946292 -219.435426)
					(mid 183.285892 -219.435426)
					(end 183.946292 -219.435426)
				)
			)
		)
	)
	(zone
		(layers "In1.Cu" "In2.Cu")
		(hatch none 0.5)
		(connect_pads
			(clearance 0)
		)
		(min_thickness 0.25)
		(keepout
			(tracks not_allowed)
			(vias allowed)
			(pads allowed)
			(copperpour not_allowed)
			(footprints allowed)
		)
		(placement
			(enabled no)
			(sheetname "")
		)
		(fill yes
			(thermal_gap 0.5)
			(thermal_bridge_width 0.5)
			(island_removal_mode 0)
		)
		(polygon
			(pts
				(arc
					(start 389.815578 -16.443198)
					(mid 389.837896 -16.49708)
					(end 389.891778 -16.519398)
				)
				(arc
					(start 390.087358 -16.519398)
					(mid 390.109234 -16.516266)
					(end 390.129268 -16.506952)
				)
				(arc
					(start 390.422892 -16.31442)
					(mid 390.464548 -16.302018)
					(end 390.506204 -16.31442)
				)
				(arc
					(start 390.801098 -16.506952)
					(mid 390.821022 -16.516188)
					(end 390.842754 -16.519398)
				)
				(arc
					(start 391.037318 -16.519398)
					(mid 391.0912 -16.49708)
					(end 391.113518 -16.443198)
				)
				(arc
					(start 391.113518 -15.757398)
					(mid 391.0912 -15.703516)
					(end 391.037318 -15.681198)
				)
				(arc
					(start 390.842754 -15.681198)
					(mid 390.82101 -15.684366)
					(end 390.801098 -15.693644)
				)
				(arc
					(start 390.504934 -15.88643)
					(mid 390.46325 -15.898652)
					(end 390.421622 -15.886176)
				)
				(arc
					(start 390.127998 -15.693644)
					(mid 390.108074 -15.684408)
					(end 390.086342 -15.681198)
				)
				(arc
					(start 389.891778 -15.681198)
					(mid 389.837896 -15.703516)
					(end 389.815578 -15.757398)
				)
			)
		)
	)
	(zone
		(layers "In1.Cu" "In2.Cu")
		(hatch none 0.5)
		(connect_pads
			(clearance 0)
		)
		(min_thickness 0.25)
		(keepout
			(tracks not_allowed)
			(vias allowed)
			(pads allowed)
			(copperpour not_allowed)
			(footprints allowed)
		)
		(placement
			(enabled no)
			(sheetname "")
		)
		(fill yes
			(thermal_gap 0.5)
			(thermal_bridge_width 0.5)
			(island_removal_mode 0)
		)
		(polygon
			(pts
				(arc
					(start 292.610286 -315.485018)
					(mid 291.949886 -315.485018)
					(end 292.610286 -315.485018)
				)
			)
		)
	)
	(zone
		(layers "In1.Cu" "In2.Cu")
		(hatch none 0.5)
		(connect_pads
			(clearance 0)
		)
		(min_thickness 0.25)
		(keepout
			(tracks not_allowed)
			(vias allowed)
			(pads allowed)
			(copperpour not_allowed)
			(footprints allowed)
		)
		(placement
			(enabled no)
			(sheetname "")
		)
		(fill yes
			(thermal_gap 0.5)
			(thermal_bridge_width 0.5)
			(island_removal_mode 0)
		)
		(polygon
			(pts
				(arc
					(start 172.30217 -244.935248)
					(mid 171.64177 -244.935248)
					(end 172.30217 -244.935248)
				)
			)
		)
	)
	(zone
		(layers "In1.Cu" "In2.Cu")
		(hatch none 0.5)
		(connect_pads
			(clearance 0)
		)
		(min_thickness 0.25)
		(keepout
			(tracks not_allowed)
			(vias allowed)
			(pads allowed)
			(copperpour not_allowed)
			(footprints allowed)
		)
		(placement
			(enabled no)
			(sheetname "")
		)
		(fill yes
			(thermal_gap 0.5)
			(thermal_bridge_width 0.5)
			(island_removal_mode 0)
		)
		(polygon
			(pts
				(arc
					(start 52.214272 -229.635304)
					(mid 51.553872 -229.635304)
					(end 52.214272 -229.635304)
				)
			)
		)
	)
	(zone
		(layers "In1.Cu" "In2.Cu")
		(hatch none 0.5)
		(connect_pads
			(clearance 0)
		)
		(min_thickness 0.25)
		(keepout
			(tracks not_allowed)
			(vias allowed)
			(pads allowed)
			(copperpour not_allowed)
			(footprints allowed)
		)
		(placement
			(enabled no)
			(sheetname "")
		)
		(fill yes
			(thermal_gap 0.5)
			(thermal_bridge_width 0.5)
			(island_removal_mode 0)
		)
		(polygon
			(pts
				(arc
					(start 292.610286 -212.635084)
					(mid 291.949886 -212.635084)
					(end 292.610286 -212.635084)
				)
			)
		)
	)
	(zone
		(layers "In1.Cu" "In2.Cu")
		(hatch none 0.5)
		(connect_pads
			(clearance 0)
		)
		(min_thickness 0.25)
		(keepout
			(tracks not_allowed)
			(vias allowed)
			(pads allowed)
			(copperpour not_allowed)
			(footprints allowed)
		)
		(placement
			(enabled no)
			(sheetname "")
		)
		(fill yes
			(thermal_gap 0.5)
			(thermal_bridge_width 0.5)
			(island_removal_mode 0)
		)
		(polygon
			(pts
				(arc
					(start 191.490346 -270.435324)
					(mid 190.829946 -270.435324)
					(end 191.490346 -270.435324)
				)
			)
		)
	)
	(zone
		(layers "In1.Cu" "In2.Cu")
		(hatch none 0.5)
		(connect_pads
			(clearance 0)
		)
		(min_thickness 0.25)
		(keepout
			(tracks not_allowed)
			(vias allowed)
			(pads allowed)
			(copperpour not_allowed)
			(footprints allowed)
		)
		(placement
			(enabled no)
			(sheetname "")
		)
		(fill yes
			(thermal_gap 0.5)
			(thermal_bridge_width 0.5)
			(island_removal_mode 0)
		)
		(polygon
			(pts
				(arc
					(start 69.33438 -376.861578)
					(mid 69.325144 -376.881502)
					(end 69.321934 -376.903234)
				)
				(arc
					(start 69.321934 -377.097798)
					(mid 69.344252 -377.15168)
					(end 69.398134 -377.173998)
				)
				(arc
					(start 70.083934 -377.173998)
					(mid 70.137816 -377.15168)
					(end 70.160134 -377.097798)
				)
				(arc
					(start 70.160134 -376.903234)
					(mid 70.156966 -376.88149)
					(end 70.147688 -376.861578)
				)
				(arc
					(start 69.954902 -376.565414)
					(mid 69.94268 -376.52373)
					(end 69.955156 -376.482102)
				)
				(arc
					(start 70.147688 -376.188478)
					(mid 70.156924 -376.168554)
					(end 70.160134 -376.146822)
				)
				(arc
					(start 70.160134 -375.952258)
					(mid 70.137816 -375.898376)
					(end 70.083934 -375.876058)
				)
				(arc
					(start 69.398134 -375.876058)
					(mid 69.344252 -375.898376)
					(end 69.321934 -375.952258)
				)
				(arc
					(start 69.321934 -376.148092)
					(mid 69.325102 -376.169836)
					(end 69.33438 -376.189748)
				)
				(arc
					(start 69.526912 -376.483372)
					(mid 69.539314 -376.525028)
					(end 69.526912 -376.566684)
				)
			)
		)
	)
	(zone
		(layers "In1.Cu" "In2.Cu")
		(hatch none 0.5)
		(connect_pads
			(clearance 0)
		)
		(min_thickness 0.25)
		(keepout
			(tracks not_allowed)
			(vias allowed)
			(pads allowed)
			(copperpour not_allowed)
			(footprints allowed)
		)
		(placement
			(enabled no)
			(sheetname "")
		)
		(fill yes
			(thermal_gap 0.5)
			(thermal_bridge_width 0.5)
			(island_removal_mode 0)
		)
		(polygon
			(pts
				(arc
					(start 277.522432 -208.385156)
					(mid 276.862032 -208.385156)
					(end 277.522432 -208.385156)
				)
			)
		)
	)
	(zone
		(layers "In1.Cu" "In2.Cu")
		(hatch none 0.5)
		(connect_pads
			(clearance 0)
		)
		(min_thickness 0.25)
		(keepout
			(tracks not_allowed)
			(vias allowed)
			(pads allowed)
			(copperpour not_allowed)
			(footprints allowed)
		)
		(placement
			(enabled no)
			(sheetname "")
		)
		(fill yes
			(thermal_gap 0.5)
			(thermal_bridge_width 0.5)
			(island_removal_mode 0)
		)
		(polygon
			(pts
				(arc
					(start 17.938242 -288.285428)
					(mid 17.277842 -288.285428)
					(end 17.938242 -288.285428)
				)
			)
		)
	)
	(zone
		(layers "In1.Cu" "In2.Cu")
		(hatch none 0.5)
		(connect_pads
			(clearance 0)
		)
		(min_thickness 0.25)
		(keepout
			(tracks not_allowed)
			(vias allowed)
			(pads allowed)
			(copperpour not_allowed)
			(footprints allowed)
		)
		(placement
			(enabled no)
			(sheetname "")
		)
		(fill yes
			(thermal_gap 0.5)
			(thermal_bridge_width 0.5)
			(island_removal_mode 0)
		)
		(polygon
			(pts
				(arc
					(start 22.03831 -208.38541)
					(mid 21.37791 -208.38541)
					(end 22.03831 -208.38541)
				)
			)
		)
	)
	(zone
		(layers "In1.Cu" "In2.Cu")
		(hatch none 0.5)
		(connect_pads
			(clearance 0)
		)
		(min_thickness 0.25)
		(keepout
			(tracks not_allowed)
			(vias allowed)
			(pads allowed)
			(copperpour not_allowed)
			(footprints allowed)
		)
		(placement
			(enabled no)
			(sheetname "")
		)
		(fill yes
			(thermal_gap 0.5)
			(thermal_bridge_width 0.5)
			(island_removal_mode 0)
		)
		(polygon
			(pts
				(arc
					(start 187.390278 -241.535204)
					(mid 186.729878 -241.535204)
					(end 187.390278 -241.535204)
				)
			)
		)
	)
	(zone
		(layers "In1.Cu" "In2.Cu")
		(hatch none 0.5)
		(connect_pads
			(clearance 0)
		)
		(min_thickness 0.25)
		(keepout
			(tracks not_allowed)
			(vias allowed)
			(pads allowed)
			(copperpour not_allowed)
			(footprints allowed)
		)
		(placement
			(enabled no)
			(sheetname "")
		)
		(fill yes
			(thermal_gap 0.5)
			(thermal_bridge_width 0.5)
			(island_removal_mode 0)
		)
		(polygon
			(pts
				(arc
					(start 176.402238 -289.135312)
					(mid 175.741838 -289.135312)
					(end 176.402238 -289.135312)
				)
			)
		)
	)
	(zone
		(layers "In1.Cu" "In2.Cu")
		(hatch none 0.5)
		(connect_pads
			(clearance 0)
		)
		(min_thickness 0.25)
		(keepout
			(tracks not_allowed)
			(vias allowed)
			(pads allowed)
			(copperpour not_allowed)
			(footprints allowed)
		)
		(placement
			(enabled no)
			(sheetname "")
		)
		(fill yes
			(thermal_gap 0.5)
			(thermal_bridge_width 0.5)
			(island_removal_mode 0)
		)
		(polygon
			(pts
				(arc
					(start 22.03831 -250.885198)
					(mid 21.37791 -250.885198)
					(end 22.03831 -250.885198)
				)
			)
		)
	)
	(zone
		(layers "In1.Cu" "In2.Cu")
		(hatch none 0.5)
		(connect_pads
			(clearance 0)
		)
		(min_thickness 0.25)
		(keepout
			(tracks not_allowed)
			(vias allowed)
			(pads allowed)
			(copperpour not_allowed)
			(footprints allowed)
		)
		(placement
			(enabled no)
			(sheetname "")
		)
		(fill yes
			(thermal_gap 0.5)
			(thermal_bridge_width 0.5)
			(island_removal_mode 0)
		)
		(polygon
			(pts
				(arc
					(start 194.934332 -314.635388)
					(mid 194.273932 -314.635388)
					(end 194.934332 -314.635388)
				)
			)
		)
	)
	(zone
		(layers "In1.Cu" "In2.Cu")
		(hatch none 0.5)
		(connect_pads
			(clearance 0)
		)
		(min_thickness 0.25)
		(keepout
			(tracks not_allowed)
			(vias allowed)
			(pads allowed)
			(copperpour not_allowed)
			(footprints allowed)
		)
		(placement
			(enabled no)
			(sheetname "")
		)
		(fill yes
			(thermal_gap 0.5)
			(thermal_bridge_width 0.5)
			(island_removal_mode 0)
		)
		(polygon
			(pts
				(arc
					(start 202.478132 -237.285276)
					(mid 201.817732 -237.285276)
					(end 202.478132 -237.285276)
				)
			)
		)
	)
	(zone
		(layers "In1.Cu" "In2.Cu")
		(hatch none 0.5)
		(connect_pads
			(clearance 0)
		)
		(min_thickness 0.25)
		(keepout
			(tracks not_allowed)
			(vias allowed)
			(pads allowed)
			(copperpour not_allowed)
			(footprints allowed)
		)
		(placement
			(enabled no)
			(sheetname "")
		)
		(fill yes
			(thermal_gap 0.5)
			(thermal_bridge_width 0.5)
			(island_removal_mode 0)
		)
		(polygon
			(pts
				(arc
					(start 142.188438 -376.73661)
					(mid 142.179202 -376.756534)
					(end 142.175992 -376.778266)
				)
				(arc
					(start 142.175992 -376.97283)
					(mid 142.19831 -377.026712)
					(end 142.252192 -377.04903)
				)
				(arc
					(start 142.937992 -377.04903)
					(mid 142.991874 -377.026712)
					(end 143.014192 -376.97283)
				)
				(arc
					(start 143.014192 -376.778266)
					(mid 143.011024 -376.756522)
					(end 143.001746 -376.73661)
				)
				(arc
					(start 142.80896 -376.440446)
					(mid 142.796738 -376.398762)
					(end 142.809214 -376.357134)
				)
				(arc
					(start 143.001746 -376.06351)
					(mid 143.010982 -376.043586)
					(end 143.014192 -376.021854)
				)
				(arc
					(start 143.014192 -375.82729)
					(mid 142.991874 -375.773408)
					(end 142.937992 -375.75109)
				)
				(arc
					(start 142.252192 -375.75109)
					(mid 142.19831 -375.773408)
					(end 142.175992 -375.82729)
				)
				(arc
					(start 142.175992 -376.023124)
					(mid 142.17916 -376.044868)
					(end 142.188438 -376.06478)
				)
				(arc
					(start 142.38097 -376.358404)
					(mid 142.393372 -376.40006)
					(end 142.38097 -376.441716)
				)
			)
		)
	)
	(zone
		(layers "In1.Cu" "In2.Cu")
		(hatch none 0.5)
		(connect_pads
			(clearance 0)
		)
		(min_thickness 0.25)
		(keepout
			(tracks not_allowed)
			(vias allowed)
			(pads allowed)
			(copperpour not_allowed)
			(footprints allowed)
		)
		(placement
			(enabled no)
			(sheetname "")
		)
		(fill yes
			(thermal_gap 0.5)
			(thermal_bridge_width 0.5)
			(island_removal_mode 0)
		)
		(polygon
			(pts
				(arc
					(start 450.4182 -313.784996)
					(mid 449.7578 -313.784996)
					(end 450.4182 -313.784996)
				)
			)
		)
	)
	(zone
		(layers "In1.Cu" "In2.Cu")
		(hatch none 0.5)
		(connect_pads
			(clearance 0)
		)
		(min_thickness 0.25)
		(keepout
			(tracks not_allowed)
			(vias allowed)
			(pads allowed)
			(copperpour not_allowed)
			(footprints allowed)
		)
		(placement
			(enabled no)
			(sheetname "")
		)
		(fill yes
			(thermal_gap 0.5)
			(thermal_bridge_width 0.5)
			(island_removal_mode 0)
		)
		(polygon
			(pts
				(arc
					(start 288.510218 -308.685184)
					(mid 287.849818 -308.685184)
					(end 288.510218 -308.685184)
				)
			)
		)
	)
	(zone
		(layers "In1.Cu" "In2.Cu")
		(hatch none 0.5)
		(connect_pads
			(clearance 0)
		)
		(min_thickness 0.25)
		(keepout
			(tracks not_allowed)
			(vias allowed)
			(pads allowed)
			(copperpour not_allowed)
			(footprints allowed)
		)
		(placement
			(enabled no)
			(sheetname "")
		)
		(fill yes
			(thermal_gap 0.5)
			(thermal_bridge_width 0.5)
			(island_removal_mode 0)
		)
		(polygon
			(pts
				(arc
					(start 442.8744 -238.985044)
					(mid 442.214 -238.985044)
					(end 442.8744 -238.985044)
				)
			)
		)
	)
	(zone
		(layers "In1.Cu" "In2.Cu")
		(hatch none 0.5)
		(connect_pads
			(clearance 0)
		)
		(min_thickness 0.25)
		(keepout
			(tracks not_allowed)
			(vias allowed)
			(pads allowed)
			(copperpour not_allowed)
			(footprints allowed)
		)
		(placement
			(enabled no)
			(sheetname "")
		)
		(fill yes
			(thermal_gap 0.5)
			(thermal_bridge_width 0.5)
			(island_removal_mode 0)
		)
		(polygon
			(pts
				(arc
					(start 191.490346 -266.185396)
					(mid 190.829946 -266.185396)
					(end 191.490346 -266.185396)
				)
			)
		)
	)
	(zone
		(layers "In1.Cu" "In2.Cu")
		(hatch none 0.5)
		(connect_pads
			(clearance 0)
		)
		(min_thickness 0.25)
		(keepout
			(tracks not_allowed)
			(vias allowed)
			(pads allowed)
			(copperpour not_allowed)
			(footprints allowed)
		)
		(placement
			(enabled no)
			(sheetname "")
		)
		(fill yes
			(thermal_gap 0.5)
			(thermal_bridge_width 0.5)
			(island_removal_mode 0)
		)
		(polygon
			(pts
				(arc
					(start 427.786292 -277.235158)
					(mid 427.125892 -277.235158)
					(end 427.786292 -277.235158)
				)
			)
		)
	)
	(zone
		(layers "In1.Cu" "In2.Cu")
		(hatch none 0.5)
		(connect_pads
			(clearance 0)
		)
		(min_thickness 0.25)
		(keepout
			(tracks not_allowed)
			(vias allowed)
			(pads allowed)
			(copperpour not_allowed)
			(footprints allowed)
		)
		(placement
			(enabled no)
			(sheetname "")
		)
		(fill yes
			(thermal_gap 0.5)
			(thermal_bridge_width 0.5)
			(island_removal_mode 0)
		)
		(polygon
			(pts
				(arc
					(start 431.88636 -279.785064)
					(mid 431.22596 -279.785064)
					(end 431.88636 -279.785064)
				)
			)
		)
	)
	(zone
		(layers "In1.Cu" "In2.Cu")
		(hatch none 0.5)
		(connect_pads
			(clearance 0)
		)
		(min_thickness 0.25)
		(keepout
			(tracks not_allowed)
			(vias allowed)
			(pads allowed)
			(copperpour not_allowed)
			(footprints allowed)
		)
		(placement
			(enabled no)
			(sheetname "")
		)
		(fill yes
			(thermal_gap 0.5)
			(thermal_bridge_width 0.5)
			(island_removal_mode 0)
		)
		(polygon
			(pts
				(arc
					(start 25.482296 -233.885232)
					(mid 24.821896 -233.885232)
					(end 25.482296 -233.885232)
				)
			)
		)
	)
	(zone
		(layers "In1.Cu" "In2.Cu")
		(hatch none 0.5)
		(connect_pads
			(clearance 0)
		)
		(min_thickness 0.25)
		(keepout
			(tracks not_allowed)
			(vias allowed)
			(pads allowed)
			(copperpour not_allowed)
			(footprints allowed)
		)
		(placement
			(enabled no)
			(sheetname "")
		)
		(fill yes
			(thermal_gap 0.5)
			(thermal_bridge_width 0.5)
			(island_removal_mode 0)
		)
		(polygon
			(pts
				(arc
					(start 17.938242 -263.635236)
					(mid 17.277842 -263.635236)
					(end 17.938242 -263.635236)
				)
			)
		)
	)
	(zone
		(layers "In1.Cu" "In2.Cu")
		(hatch none 0.5)
		(connect_pads
			(clearance 0)
		)
		(min_thickness 0.25)
		(keepout
			(tracks not_allowed)
			(vias allowed)
			(pads allowed)
			(copperpour not_allowed)
			(footprints allowed)
		)
		(placement
			(enabled no)
			(sheetname "")
		)
		(fill yes
			(thermal_gap 0.5)
			(thermal_bridge_width 0.5)
			(island_removal_mode 0)
		)
		(polygon
			(pts
				(arc
					(start 187.390278 -288.285428)
					(mid 186.729878 -288.285428)
					(end 187.390278 -288.285428)
				)
			)
		)
	)
	(zone
		(layers "In1.Cu" "In2.Cu")
		(hatch none 0.5)
		(connect_pads
			(clearance 0)
		)
		(min_thickness 0.25)
		(keepout
			(tracks not_allowed)
			(vias allowed)
			(pads allowed)
			(copperpour not_allowed)
			(footprints allowed)
		)
		(placement
			(enabled no)
			(sheetname "")
		)
		(fill yes
			(thermal_gap 0.5)
			(thermal_bridge_width 0.5)
			(island_removal_mode 0)
		)
		(polygon
			(pts
				(arc
					(start 427.786292 -305.28514)
					(mid 427.125892 -305.28514)
					(end 427.786292 -305.28514)
				)
			)
		)
	)
	(zone
		(layers "In1.Cu" "In2.Cu")
		(hatch none 0.5)
		(connect_pads
			(clearance 0)
		)
		(min_thickness 0.25)
		(keepout
			(tracks not_allowed)
			(vias allowed)
			(pads allowed)
			(copperpour not_allowed)
			(footprints allowed)
		)
		(placement
			(enabled no)
			(sheetname "")
		)
		(fill yes
			(thermal_gap 0.5)
			(thermal_bridge_width 0.5)
			(island_removal_mode 0)
		)
		(polygon
			(pts
				(arc
					(start 44.670218 -261.08533)
					(mid 44.009818 -261.08533)
					(end 44.670218 -261.08533)
				)
			)
		)
	)
	(zone
		(layers "In1.Cu" "In2.Cu")
		(hatch none 0.5)
		(connect_pads
			(clearance 0)
		)
		(min_thickness 0.25)
		(keepout
			(tracks not_allowed)
			(vias allowed)
			(pads allowed)
			(copperpour not_allowed)
			(footprints allowed)
		)
		(placement
			(enabled no)
			(sheetname "")
		)
		(fill yes
			(thermal_gap 0.5)
			(thermal_bridge_width 0.5)
			(island_removal_mode 0)
		)
		(polygon
			(pts
				(arc
					(start 269.978378 -296.78503)
					(mid 269.317978 -296.78503)
					(end 269.978378 -296.78503)
				)
			)
		)
	)
	(zone
		(layers "In1.Cu" "In2.Cu")
		(hatch none 0.5)
		(connect_pads
			(clearance 0)
		)
		(min_thickness 0.25)
		(keepout
			(tracks not_allowed)
			(vias allowed)
			(pads allowed)
			(copperpour not_allowed)
			(footprints allowed)
		)
		(placement
			(enabled no)
			(sheetname "")
		)
		(fill yes
			(thermal_gap 0.5)
			(thermal_bridge_width 0.5)
			(island_removal_mode 0)
		)
		(polygon
			(pts
				(arc
					(start 33.026096 -220.28531)
					(mid 32.365696 -220.28531)
					(end 33.026096 -220.28531)
				)
			)
		)
	)
	(zone
		(layers "In1.Cu" "In2.Cu")
		(hatch none 0.5)
		(connect_pads
			(clearance 0)
		)
		(min_thickness 0.25)
		(keepout
			(tracks not_allowed)
			(vias allowed)
			(pads allowed)
			(copperpour not_allowed)
			(footprints allowed)
		)
		(placement
			(enabled no)
			(sheetname "")
		)
		(fill yes
			(thermal_gap 0.5)
			(thermal_bridge_width 0.5)
			(island_removal_mode 0)
		)
		(polygon
			(pts
				(arc
					(start 288.510218 -276.38502)
					(mid 287.849818 -276.38502)
					(end 288.510218 -276.38502)
				)
			)
		)
	)
	(zone
		(layers "In1.Cu" "In2.Cu")
		(hatch none 0.5)
		(connect_pads
			(clearance 0)
		)
		(min_thickness 0.25)
		(keepout
			(tracks not_allowed)
			(vias allowed)
			(pads allowed)
			(copperpour not_allowed)
			(footprints allowed)
		)
		(placement
			(enabled no)
			(sheetname "")
		)
		(fill yes
			(thermal_gap 0.5)
			(thermal_bridge_width 0.5)
			(island_removal_mode 0)
		)
		(polygon
			(pts
				(arc
					(start 280.966164 -198.185024)
					(mid 280.305764 -198.185024)
					(end 280.966164 -198.185024)
				)
			)
		)
	)
	(zone
		(layers "In1.Cu" "In2.Cu")
		(hatch none 0.5)
		(connect_pads
			(clearance 0)
		)
		(min_thickness 0.25)
		(keepout
			(tracks not_allowed)
			(vias allowed)
			(pads allowed)
			(copperpour not_allowed)
			(footprints allowed)
		)
		(placement
			(enabled no)
			(sheetname "")
		)
		(fill yes
			(thermal_gap 0.5)
			(thermal_bridge_width 0.5)
			(island_removal_mode 0)
		)
		(polygon
			(pts
				(arc
					(start 273.422364 -238.985044)
					(mid 272.761964 -238.985044)
					(end 273.422364 -238.985044)
				)
			)
		)
	)
	(zone
		(layers "In1.Cu" "In2.Cu")
		(hatch none 0.5)
		(connect_pads
			(clearance 0)
		)
		(min_thickness 0.25)
		(keepout
			(tracks not_allowed)
			(vias allowed)
			(pads allowed)
			(copperpour not_allowed)
			(footprints allowed)
		)
		(placement
			(enabled no)
			(sheetname "")
		)
		(fill yes
			(thermal_gap 0.5)
			(thermal_bridge_width 0.5)
			(island_removal_mode 0)
		)
		(polygon
			(pts
				(arc
					(start 454.518268 -221.985078)
					(mid 453.857868 -221.985078)
					(end 454.518268 -221.985078)
				)
			)
		)
	)
	(zone
		(layers "In1.Cu" "In2.Cu")
		(hatch none 0.5)
		(connect_pads
			(clearance 0)
		)
		(min_thickness 0.25)
		(keepout
			(tracks not_allowed)
			(vias allowed)
			(pads allowed)
			(copperpour not_allowed)
			(footprints allowed)
		)
		(placement
			(enabled no)
			(sheetname "")
		)
		(fill yes
			(thermal_gap 0.5)
			(thermal_bridge_width 0.5)
			(island_removal_mode 0)
		)
		(polygon
			(pts
				(arc
					(start 202.478132 -288.285428)
					(mid 201.817732 -288.285428)
					(end 202.478132 -288.285428)
				)
			)
		)
	)
	(zone
		(layers "In1.Cu" "In2.Cu")
		(hatch none 0.5)
		(connect_pads
			(clearance 0)
		)
		(min_thickness 0.25)
		(keepout
			(tracks not_allowed)
			(vias allowed)
			(pads allowed)
			(copperpour not_allowed)
			(footprints allowed)
		)
		(placement
			(enabled no)
			(sheetname "")
		)
		(fill yes
			(thermal_gap 0.5)
			(thermal_bridge_width 0.5)
			(island_removal_mode 0)
		)
		(polygon
			(pts
				(arc
					(start 269.978378 -254.284988)
					(mid 269.317978 -254.284988)
					(end 269.978378 -254.284988)
				)
			)
		)
	)
	(zone
		(layers "In1.Cu" "In2.Cu")
		(hatch none 0.5)
		(connect_pads
			(clearance 0)
		)
		(min_thickness 0.25)
		(keepout
			(tracks not_allowed)
			(vias allowed)
			(pads allowed)
			(copperpour not_allowed)
			(footprints allowed)
		)
		(placement
			(enabled no)
			(sheetname "")
		)
		(fill yes
			(thermal_gap 0.5)
			(thermal_bridge_width 0.5)
			(island_removal_mode 0)
		)
		(polygon
			(pts
				(arc
					(start 183.946292 -221.985332)
					(mid 183.285892 -221.985332)
					(end 183.946292 -221.985332)
				)
			)
		)
	)
	(zone
		(layers "In1.Cu" "In2.Cu")
		(hatch none 0.5)
		(connect_pads
			(clearance 0)
		)
		(min_thickness 0.25)
		(keepout
			(tracks not_allowed)
			(vias allowed)
			(pads allowed)
			(copperpour not_allowed)
			(footprints allowed)
		)
		(placement
			(enabled no)
			(sheetname "")
		)
		(fill yes
			(thermal_gap 0.5)
			(thermal_bridge_width 0.5)
			(island_removal_mode 0)
		)
		(polygon
			(pts
				(arc
					(start 442.8744 -277.235158)
					(mid 442.214 -277.235158)
					(end 442.8744 -277.235158)
				)
			)
		)
	)
	(zone
		(layers "In1.Cu" "In2.Cu")
		(hatch none 0.5)
		(connect_pads
			(clearance 0)
		)
		(min_thickness 0.25)
		(keepout
			(tracks not_allowed)
			(vias allowed)
			(pads allowed)
			(copperpour not_allowed)
			(footprints allowed)
		)
		(placement
			(enabled no)
			(sheetname "")
		)
		(fill yes
			(thermal_gap 0.5)
			(thermal_bridge_width 0.5)
			(island_removal_mode 0)
		)
		(polygon
			(pts
				(arc
					(start 420.242238 -268.735048)
					(mid 419.581838 -268.735048)
					(end 420.242238 -268.735048)
				)
			)
		)
	)
	(zone
		(layers "In1.Cu" "In2.Cu")
		(hatch none 0.5)
		(connect_pads
			(clearance 0)
		)
		(min_thickness 0.25)
		(keepout
			(tracks not_allowed)
			(vias allowed)
			(pads allowed)
			(copperpour not_allowed)
			(footprints allowed)
		)
		(placement
			(enabled no)
			(sheetname "")
		)
		(fill yes
			(thermal_gap 0.5)
			(thermal_bridge_width 0.5)
			(island_removal_mode 0)
		)
		(polygon
			(pts
				(arc
					(start 199.0344 -204.985366)
					(mid 198.374 -204.985366)
					(end 199.0344 -204.985366)
				)
			)
		)
	)
	(zone
		(layers "In1.Cu" "In2.Cu")
		(hatch none 0.5)
		(connect_pads
			(clearance 0)
		)
		(min_thickness 0.25)
		(keepout
			(tracks not_allowed)
			(vias allowed)
			(pads allowed)
			(copperpour not_allowed)
			(footprints allowed)
		)
		(placement
			(enabled no)
			(sheetname "")
		)
		(fill yes
			(thermal_gap 0.5)
			(thermal_bridge_width 0.5)
			(island_removal_mode 0)
		)
		(polygon
			(pts
				(arc
					(start 424.342306 -228.785166)
					(mid 423.681906 -228.785166)
					(end 424.342306 -228.785166)
				)
			)
		)
	)
	(zone
		(layers "In1.Cu" "In2.Cu")
		(hatch none 0.5)
		(connect_pads
			(clearance 0)
		)
		(min_thickness 0.25)
		(keepout
			(tracks not_allowed)
			(vias allowed)
			(pads allowed)
			(copperpour not_allowed)
			(footprints allowed)
		)
		(placement
			(enabled no)
			(sheetname "")
		)
		(fill yes
			(thermal_gap 0.5)
			(thermal_bridge_width 0.5)
			(island_removal_mode 0)
		)
		(polygon
			(pts
				(arc
					(start 439.430414 -307.835046)
					(mid 438.770014 -307.835046)
					(end 439.430414 -307.835046)
				)
			)
		)
	)
	(zone
		(layers "In1.Cu" "In2.Cu")
		(hatch none 0.5)
		(connect_pads
			(clearance 0)
		)
		(min_thickness 0.25)
		(keepout
			(tracks not_allowed)
			(vias allowed)
			(pads allowed)
			(copperpour not_allowed)
			(footprints allowed)
		)
		(placement
			(enabled no)
			(sheetname "")
		)
		(fill yes
			(thermal_gap 0.5)
			(thermal_bridge_width 0.5)
			(island_removal_mode 0)
		)
		(polygon
			(pts
				(arc
					(start 17.938242 -218.585288)
					(mid 17.277842 -218.585288)
					(end 17.938242 -218.585288)
				)
			)
		)
	)
	(zone
		(layers "In1.Cu" "In2.Cu")
		(hatch none 0.5)
		(connect_pads
			(clearance 0)
		)
		(min_thickness 0.25)
		(keepout
			(tracks not_allowed)
			(vias allowed)
			(pads allowed)
			(copperpour not_allowed)
			(footprints allowed)
		)
		(placement
			(enabled no)
			(sheetname "")
		)
		(fill yes
			(thermal_gap 0.5)
			(thermal_bridge_width 0.5)
			(island_removal_mode 0)
		)
		(polygon
			(pts
				(arc
					(start 439.430414 -290.83508)
					(mid 438.770014 -290.83508)
					(end 439.430414 -290.83508)
				)
			)
		)
	)
	(zone
		(layers "In1.Cu" "In2.Cu")
		(hatch none 0.5)
		(connect_pads
			(clearance 0)
		)
		(min_thickness 0.25)
		(keepout
			(tracks not_allowed)
			(vias allowed)
			(pads allowed)
			(copperpour not_allowed)
			(footprints allowed)
		)
		(placement
			(enabled no)
			(sheetname "")
		)
		(fill yes
			(thermal_gap 0.5)
			(thermal_bridge_width 0.5)
			(island_removal_mode 0)
		)
		(polygon
			(pts
				(arc
					(start 435.330346 -291.684964)
					(mid 434.669946 -291.684964)
					(end 435.330346 -291.684964)
				)
			)
		)
	)
	(zone
		(layers "In1.Cu" "In2.Cu")
		(hatch none 0.5)
		(connect_pads
			(clearance 0)
		)
		(min_thickness 0.25)
		(keepout
			(tracks not_allowed)
			(vias allowed)
			(pads allowed)
			(copperpour not_allowed)
			(footprints allowed)
		)
		(placement
			(enabled no)
			(sheetname "")
		)
		(fill yes
			(thermal_gap 0.5)
			(thermal_bridge_width 0.5)
			(island_removal_mode 0)
		)
		(polygon
			(pts
				(arc
					(start 450.4182 -261.93496)
					(mid 449.7578 -261.93496)
					(end 450.4182 -261.93496)
				)
			)
		)
	)
	(zone
		(layers "In1.Cu" "In2.Cu")
		(hatch none 0.5)
		(connect_pads
			(clearance 0)
		)
		(min_thickness 0.25)
		(keepout
			(tracks not_allowed)
			(vias allowed)
			(pads allowed)
			(copperpour not_allowed)
			(footprints allowed)
		)
		(placement
			(enabled no)
			(sheetname "")
		)
		(fill yes
			(thermal_gap 0.5)
			(thermal_bridge_width 0.5)
			(island_removal_mode 0)
		)
		(polygon
			(pts
				(arc
					(start 288.510218 -282.33497)
					(mid 287.849818 -282.33497)
					(end 288.510218 -282.33497)
				)
			)
		)
	)
	(zone
		(layers "In1.Cu" "In2.Cu")
		(hatch none 0.5)
		(connect_pads
			(clearance 0)
		)
		(min_thickness 0.25)
		(keepout
			(tracks not_allowed)
			(vias allowed)
			(pads allowed)
			(copperpour not_allowed)
			(footprints allowed)
		)
		(placement
			(enabled no)
			(sheetname "")
		)
		(fill yes
			(thermal_gap 0.5)
			(thermal_bridge_width 0.5)
			(island_removal_mode 0)
		)
		(polygon
			(pts
				(arc
					(start 273.422364 -224.534984)
					(mid 272.761964 -224.534984)
					(end 273.422364 -224.534984)
				)
			)
		)
	)
	(zone
		(layers "In1.Cu" "In2.Cu")
		(hatch none 0.5)
		(connect_pads
			(clearance 0)
		)
		(min_thickness 0.25)
		(keepout
			(tracks not_allowed)
			(vias allowed)
			(pads allowed)
			(copperpour not_allowed)
			(footprints allowed)
		)
		(placement
			(enabled no)
			(sheetname "")
		)
		(fill yes
			(thermal_gap 0.5)
			(thermal_bridge_width 0.5)
			(island_removal_mode 0)
		)
		(polygon
			(pts
				(arc
					(start 442.8744 -286.585152)
					(mid 442.214 -286.585152)
					(end 442.8744 -286.585152)
				)
			)
		)
	)
	(zone
		(layers "In1.Cu" "In2.Cu")
		(hatch none 0.5)
		(connect_pads
			(clearance 0)
		)
		(min_thickness 0.25)
		(keepout
			(tracks not_allowed)
			(vias allowed)
			(pads allowed)
			(copperpour not_allowed)
			(footprints allowed)
		)
		(placement
			(enabled no)
			(sheetname "")
		)
		(fill yes
			(thermal_gap 0.5)
			(thermal_bridge_width 0.5)
			(island_removal_mode 0)
		)
		(polygon
			(pts
				(arc
					(start 450.4182 -282.33497)
					(mid 449.7578 -282.33497)
					(end 450.4182 -282.33497)
				)
			)
		)
	)
	(zone
		(layers "In1.Cu" "In2.Cu")
		(hatch none 0.5)
		(connect_pads
			(clearance 0)
		)
		(min_thickness 0.25)
		(keepout
			(tracks not_allowed)
			(vias allowed)
			(pads allowed)
			(copperpour not_allowed)
			(footprints allowed)
		)
		(placement
			(enabled no)
			(sheetname "")
		)
		(fill yes
			(thermal_gap 0.5)
			(thermal_bridge_width 0.5)
			(island_removal_mode 0)
		)
		(polygon
			(pts
				(arc
					(start 296.054272 -248.335038)
					(mid 295.393872 -248.335038)
					(end 296.054272 -248.335038)
				)
			)
		)
	)
	(zone
		(layers "In1.Cu" "In2.Cu")
		(hatch none 0.5)
		(connect_pads
			(clearance 0)
		)
		(min_thickness 0.25)
		(keepout
			(tracks not_allowed)
			(vias allowed)
			(pads allowed)
			(copperpour not_allowed)
			(footprints allowed)
		)
		(placement
			(enabled no)
			(sheetname "")
		)
		(fill yes
			(thermal_gap 0.5)
			(thermal_bridge_width 0.5)
			(island_removal_mode 0)
		)
		(polygon
			(pts
				(arc
					(start 439.430414 -231.335072)
					(mid 438.770014 -231.335072)
					(end 439.430414 -231.335072)
				)
			)
		)
	)
	(zone
		(layers "In1.Cu" "In2.Cu")
		(hatch none 0.5)
		(connect_pads
			(clearance 0)
		)
		(min_thickness 0.25)
		(keepout
			(tracks not_allowed)
			(vias allowed)
			(pads allowed)
			(copperpour not_allowed)
			(footprints allowed)
		)
		(placement
			(enabled no)
			(sheetname "")
		)
		(fill yes
			(thermal_gap 0.5)
			(thermal_bridge_width 0.5)
			(island_removal_mode 0)
		)
		(polygon
			(pts
				(arc
					(start 427.786292 -308.685184)
					(mid 427.125892 -308.685184)
					(end 427.786292 -308.685184)
				)
			)
		)
	)
	(zone
		(layers "In1.Cu" "In2.Cu")
		(hatch none 0.5)
		(connect_pads
			(clearance 0)
		)
		(min_thickness 0.25)
		(keepout
			(tracks not_allowed)
			(vias allowed)
			(pads allowed)
			(copperpour not_allowed)
			(footprints allowed)
		)
		(placement
			(enabled no)
			(sheetname "")
		)
		(fill yes
			(thermal_gap 0.5)
			(thermal_bridge_width 0.5)
			(island_removal_mode 0)
		)
		(polygon
			(pts
				(arc
					(start 22.03831 -278.085296)
					(mid 21.37791 -278.085296)
					(end 22.03831 -278.085296)
				)
			)
		)
	)
	(zone
		(layers "In1.Cu" "In2.Cu")
		(hatch none 0.5)
		(connect_pads
			(clearance 0)
		)
		(min_thickness 0.25)
		(keepout
			(tracks not_allowed)
			(vias allowed)
			(pads allowed)
			(copperpour not_allowed)
			(footprints allowed)
		)
		(placement
			(enabled no)
			(sheetname "")
		)
		(fill yes
			(thermal_gap 0.5)
			(thermal_bridge_width 0.5)
			(island_removal_mode 0)
		)
		(polygon
			(pts
				(arc
					(start 427.786292 -313.784996)
					(mid 427.125892 -313.784996)
					(end 427.786292 -313.784996)
				)
			)
		)
	)
	(zone
		(layers "In1.Cu" "In2.Cu")
		(hatch none 0.5)
		(connect_pads
			(clearance 0)
		)
		(min_thickness 0.25)
		(keepout
			(tracks not_allowed)
			(vias allowed)
			(pads allowed)
			(copperpour not_allowed)
			(footprints allowed)
		)
		(placement
			(enabled no)
			(sheetname "")
		)
		(fill yes
			(thermal_gap 0.5)
			(thermal_bridge_width 0.5)
			(island_removal_mode 0)
		)
		(polygon
			(pts
				(arc
					(start 277.522432 -197.33514)
					(mid 276.862032 -197.33514)
					(end 277.522432 -197.33514)
				)
			)
		)
	)
	(zone
		(layers "In1.Cu" "In2.Cu")
		(hatch none 0.5)
		(connect_pads
			(clearance 0)
		)
		(min_thickness 0.25)
		(keepout
			(tracks not_allowed)
			(vias allowed)
			(pads allowed)
			(copperpour not_allowed)
			(footprints allowed)
		)
		(placement
			(enabled no)
			(sheetname "")
		)
		(fill yes
			(thermal_gap 0.5)
			(thermal_bridge_width 0.5)
			(island_removal_mode 0)
		)
		(polygon
			(pts
				(arc
					(start 25.482296 -254.285242)
					(mid 24.821896 -254.285242)
					(end 25.482296 -254.285242)
				)
			)
		)
	)
	(zone
		(layers "In1.Cu" "In2.Cu")
		(hatch none 0.5)
		(connect_pads
			(clearance 0)
		)
		(min_thickness 0.25)
		(keepout
			(tracks not_allowed)
			(vias allowed)
			(pads allowed)
			(copperpour not_allowed)
			(footprints allowed)
		)
		(placement
			(enabled no)
			(sheetname "")
		)
		(fill yes
			(thermal_gap 0.5)
			(thermal_bridge_width 0.5)
			(island_removal_mode 0)
		)
		(polygon
			(pts
				(arc
					(start 48.888904 -375.906284)
					(mid 48.908828 -375.91552)
					(end 48.93056 -375.91873)
				)
				(arc
					(start 49.125124 -375.91873)
					(mid 49.179006 -375.896412)
					(end 49.201324 -375.84253)
				)
				(arc
					(start 49.201324 -375.15673)
					(mid 49.179006 -375.102848)
					(end 49.125124 -375.08053)
				)
				(arc
					(start 48.93056 -375.08053)
					(mid 48.908816 -375.083698)
					(end 48.888904 -375.092976)
				)
				(arc
					(start 48.59274 -375.285762)
					(mid 48.551056 -375.297984)
					(end 48.509428 -375.285508)
				)
				(arc
					(start 48.215804 -375.092976)
					(mid 48.19588 -375.08374)
					(end 48.174148 -375.08053)
				)
				(arc
					(start 47.979584 -375.08053)
					(mid 47.925702 -375.102848)
					(end 47.903384 -375.15673)
				)
				(arc
					(start 47.903384 -375.84253)
					(mid 47.925702 -375.896412)
					(end 47.979584 -375.91873)
				)
				(arc
					(start 48.175418 -375.91873)
					(mid 48.197162 -375.915562)
					(end 48.217074 -375.906284)
				)
				(arc
					(start 48.510698 -375.713752)
					(mid 48.552354 -375.70135)
					(end 48.59401 -375.713752)
				)
			)
		)
	)
	(zone
		(layers "In1.Cu" "In2.Cu")
		(hatch none 0.5)
		(connect_pads
			(clearance 0)
		)
		(min_thickness 0.25)
		(keepout
			(tracks not_allowed)
			(vias allowed)
			(pads allowed)
			(copperpour not_allowed)
			(footprints allowed)
		)
		(placement
			(enabled no)
			(sheetname "")
		)
		(fill yes
			(thermal_gap 0.5)
			(thermal_bridge_width 0.5)
			(island_removal_mode 0)
		)
		(polygon
			(pts
				(arc
					(start 179.846224 -282.335224)
					(mid 179.185824 -282.335224)
					(end 179.846224 -282.335224)
				)
			)
		)
	)
	(zone
		(layers "In1.Cu" "In2.Cu")
		(hatch none 0.5)
		(connect_pads
			(clearance 0)
		)
		(min_thickness 0.25)
		(keepout
			(tracks not_allowed)
			(vias allowed)
			(pads allowed)
			(copperpour not_allowed)
			(footprints allowed)
		)
		(placement
			(enabled no)
			(sheetname "")
		)
		(fill yes
			(thermal_gap 0.5)
			(thermal_bridge_width 0.5)
			(island_removal_mode 0)
		)
		(polygon
			(pts
				(arc
					(start 172.30217 -276.385274)
					(mid 171.64177 -276.385274)
					(end 172.30217 -276.385274)
				)
			)
		)
	)
	(zone
		(layers "In1.Cu" "In2.Cu")
		(hatch none 0.5)
		(connect_pads
			(clearance 0)
		)
		(min_thickness 0.25)
		(keepout
			(tracks not_allowed)
			(vias allowed)
			(pads allowed)
			(copperpour not_allowed)
			(footprints allowed)
		)
		(placement
			(enabled no)
			(sheetname "")
		)
		(fill yes
			(thermal_gap 0.5)
			(thermal_bridge_width 0.5)
			(island_removal_mode 0)
		)
		(polygon
			(pts
				(arc
					(start 25.482296 -291.685218)
					(mid 24.821896 -291.685218)
					(end 25.482296 -291.685218)
				)
			)
		)
	)
	(zone
		(layers "In1.Cu" "In2.Cu")
		(hatch none 0.5)
		(connect_pads
			(clearance 0)
		)
		(min_thickness 0.25)
		(keepout
			(tracks not_allowed)
			(vias allowed)
			(pads allowed)
			(copperpour not_allowed)
			(footprints allowed)
		)
		(placement
			(enabled no)
			(sheetname "")
		)
		(fill yes
			(thermal_gap 0.5)
			(thermal_bridge_width 0.5)
			(island_removal_mode 0)
		)
		(polygon
			(pts
				(arc
					(start 442.8744 -261.93496)
					(mid 442.214 -261.93496)
					(end 442.8744 -261.93496)
				)
			)
		)
	)
	(zone
		(layers "In1.Cu" "In2.Cu")
		(hatch none 0.5)
		(connect_pads
			(clearance 0)
		)
		(min_thickness 0.25)
		(keepout
			(tracks not_allowed)
			(vias allowed)
			(pads allowed)
			(copperpour not_allowed)
			(footprints allowed)
		)
		(placement
			(enabled no)
			(sheetname "")
		)
		(fill yes
			(thermal_gap 0.5)
			(thermal_bridge_width 0.5)
			(island_removal_mode 0)
		)
		(polygon
			(pts
				(arc
					(start 285.066232 -221.985078)
					(mid 284.405832 -221.985078)
					(end 285.066232 -221.985078)
				)
			)
		)
	)
	(zone
		(layers "In1.Cu" "In2.Cu")
		(hatch none 0.5)
		(connect_pads
			(clearance 0)
		)
		(min_thickness 0.25)
		(keepout
			(tracks not_allowed)
			(vias allowed)
			(pads allowed)
			(copperpour not_allowed)
			(footprints allowed)
		)
		(placement
			(enabled no)
			(sheetname "")
		)
		(fill yes
			(thermal_gap 0.5)
			(thermal_bridge_width 0.5)
			(island_removal_mode 0)
		)
		(polygon
			(pts
				(arc
					(start 33.026096 -243.235226)
					(mid 32.365696 -243.235226)
					(end 33.026096 -243.235226)
				)
			)
		)
	)
	(zone
		(layers "In1.Cu" "In2.Cu")
		(hatch none 0.5)
		(connect_pads
			(clearance 0)
		)
		(min_thickness 0.25)
		(keepout
			(tracks not_allowed)
			(vias allowed)
			(pads allowed)
			(copperpour not_allowed)
			(footprints allowed)
		)
		(placement
			(enabled no)
			(sheetname "")
		)
		(fill yes
			(thermal_gap 0.5)
			(thermal_bridge_width 0.5)
			(island_removal_mode 0)
		)
		(polygon
			(pts
				(arc
					(start 33.026096 -210.935316)
					(mid 32.365696 -210.935316)
					(end 33.026096 -210.935316)
				)
			)
		)
	)
	(zone
		(layers "In1.Cu" "In2.Cu")
		(hatch none 0.5)
		(connect_pads
			(clearance 0)
		)
		(min_thickness 0.25)
		(keepout
			(tracks not_allowed)
			(vias allowed)
			(pads allowed)
			(copperpour not_allowed)
			(footprints allowed)
		)
		(placement
			(enabled no)
			(sheetname "")
		)
		(fill yes
			(thermal_gap 0.5)
			(thermal_bridge_width 0.5)
			(island_removal_mode 0)
		)
		(polygon
			(pts
				(arc
					(start 100.80117 -292.411404)
					(mid 100.49637 -292.716204)
					(end 100.80117 -293.021004)
				)
				(arc
					(start 101.741224 -293.021004)
					(mid 102.046024 -292.716204)
					(end 101.741224 -292.411404)
				)
			)
		)
	)
	(zone
		(layers "In1.Cu" "In2.Cu")
		(hatch none 0.5)
		(connect_pads
			(clearance 0)
		)
		(min_thickness 0.25)
		(keepout
			(tracks not_allowed)
			(vias allowed)
			(pads allowed)
			(copperpour not_allowed)
			(footprints allowed)
		)
		(placement
			(enabled no)
			(sheetname "")
		)
		(fill yes
			(thermal_gap 0.5)
			(thermal_bridge_width 0.5)
			(island_removal_mode 0)
		)
		(polygon
			(pts
				(arc
					(start 450.4182 -302.73498)
					(mid 449.7578 -302.73498)
					(end 450.4182 -302.73498)
				)
			)
		)
	)
	(zone
		(layers "In1.Cu" "In2.Cu")
		(hatch none 0.5)
		(connect_pads
			(clearance 0)
		)
		(min_thickness 0.25)
		(keepout
			(tracks not_allowed)
			(vias allowed)
			(pads allowed)
			(copperpour not_allowed)
			(footprints allowed)
		)
		(placement
			(enabled no)
			(sheetname "")
		)
		(fill yes
			(thermal_gap 0.5)
			(thermal_bridge_width 0.5)
			(island_removal_mode 0)
		)
		(polygon
			(pts
				(arc
					(start 29.582364 -228.78542)
					(mid 28.921964 -228.78542)
					(end 29.582364 -228.78542)
				)
			)
		)
	)
	(zone
		(layers "In1.Cu" "In2.Cu")
		(hatch none 0.5)
		(connect_pads
			(clearance 0)
		)
		(min_thickness 0.25)
		(keepout
			(tracks not_allowed)
			(vias allowed)
			(pads allowed)
			(copperpour not_allowed)
			(footprints allowed)
		)
		(placement
			(enabled no)
			(sheetname "")
		)
		(fill yes
			(thermal_gap 0.5)
			(thermal_bridge_width 0.5)
			(island_removal_mode 0)
		)
		(polygon
			(pts
				(arc
					(start 172.30217 -302.735234)
					(mid 171.64177 -302.735234)
					(end 172.30217 -302.735234)
				)
			)
		)
	)
	(zone
		(layers "In1.Cu" "In2.Cu")
		(hatch none 0.5)
		(connect_pads
			(clearance 0)
		)
		(min_thickness 0.25)
		(keepout
			(tracks not_allowed)
			(vias allowed)
			(pads allowed)
			(copperpour not_allowed)
			(footprints allowed)
		)
		(placement
			(enabled no)
			(sheetname "")
		)
		(fill yes
			(thermal_gap 0.5)
			(thermal_bridge_width 0.5)
			(island_removal_mode 0)
		)
		(polygon
			(pts
				(arc
					(start 277.522432 -290.83508)
					(mid 276.862032 -290.83508)
					(end 277.522432 -290.83508)
				)
			)
		)
	)
	(zone
		(layers "In1.Cu" "In2.Cu")
		(hatch none 0.5)
		(connect_pads
			(clearance 0)
		)
		(min_thickness 0.25)
		(keepout
			(tracks not_allowed)
			(vias allowed)
			(pads allowed)
			(copperpour not_allowed)
			(footprints allowed)
		)
		(placement
			(enabled no)
			(sheetname "")
		)
		(fill yes
			(thermal_gap 0.5)
			(thermal_bridge_width 0.5)
			(island_removal_mode 0)
		)
		(polygon
			(pts
				(arc
					(start 269.978378 -217.73515)
					(mid 269.317978 -217.73515)
					(end 269.978378 -217.73515)
				)
			)
		)
	)
	(zone
		(layers "In1.Cu" "In2.Cu")
		(hatch none 0.5)
		(connect_pads
			(clearance 0)
		)
		(min_thickness 0.25)
		(keepout
			(tracks not_allowed)
			(vias allowed)
			(pads allowed)
			(copperpour not_allowed)
			(footprints allowed)
		)
		(placement
			(enabled no)
			(sheetname "")
		)
		(fill yes
			(thermal_gap 0.5)
			(thermal_bridge_width 0.5)
			(island_removal_mode 0)
		)
		(polygon
			(pts
				(arc
					(start 431.88636 -269.585186)
					(mid 431.22596 -269.585186)
					(end 431.88636 -269.585186)
				)
			)
		)
	)
	(zone
		(layers "In1.Cu" "In2.Cu")
		(hatch none 0.5)
		(connect_pads
			(clearance 0)
		)
		(min_thickness 0.25)
		(keepout
			(tracks not_allowed)
			(vias allowed)
			(pads allowed)
			(copperpour not_allowed)
			(footprints allowed)
		)
		(placement
			(enabled no)
			(sheetname "")
		)
		(fill yes
			(thermal_gap 0.5)
			(thermal_bridge_width 0.5)
			(island_removal_mode 0)
		)
		(polygon
			(pts
				(arc
					(start 194.934332 -221.135194)
					(mid 194.273932 -221.135194)
					(end 194.934332 -221.135194)
				)
			)
		)
	)
	(zone
		(layers "In1.Cu" "In2.Cu")
		(hatch none 0.5)
		(connect_pads
			(clearance 0)
		)
		(min_thickness 0.25)
		(keepout
			(tracks not_allowed)
			(vias allowed)
			(pads allowed)
			(copperpour not_allowed)
			(footprints allowed)
		)
		(placement
			(enabled no)
			(sheetname "")
		)
		(fill yes
			(thermal_gap 0.5)
			(thermal_bridge_width 0.5)
			(island_removal_mode 0)
		)
		(polygon
			(pts
				(arc
					(start 439.430414 -285.735014)
					(mid 438.770014 -285.735014)
					(end 439.430414 -285.735014)
				)
			)
		)
	)
	(zone
		(layers "In1.Cu" "In2.Cu")
		(hatch none 0.5)
		(connect_pads
			(clearance 0)
		)
		(min_thickness 0.25)
		(keepout
			(tracks not_allowed)
			(vias allowed)
			(pads allowed)
			(copperpour not_allowed)
			(footprints allowed)
		)
		(placement
			(enabled no)
			(sheetname "")
		)
		(fill yes
			(thermal_gap 0.5)
			(thermal_bridge_width 0.5)
			(island_removal_mode 0)
		)
		(polygon
			(pts
				(arc
					(start 300.15434 -228.785166)
					(mid 299.49394 -228.785166)
					(end 300.15434 -228.785166)
				)
			)
		)
	)
	(zone
		(layers "In1.Cu" "In2.Cu")
		(hatch none 0.5)
		(connect_pads
			(clearance 0)
		)
		(min_thickness 0.25)
		(keepout
			(tracks not_allowed)
			(vias allowed)
			(pads allowed)
			(copperpour not_allowed)
			(footprints allowed)
		)
		(placement
			(enabled no)
			(sheetname "")
		)
		(fill yes
			(thermal_gap 0.5)
			(thermal_bridge_width 0.5)
			(island_removal_mode 0)
		)
		(polygon
			(pts
				(arc
					(start 191.490346 -312.935366)
					(mid 190.829946 -312.935366)
					(end 191.490346 -312.935366)
				)
			)
		)
	)
	(zone
		(layers "In1.Cu" "In2.Cu")
		(hatch none 0.5)
		(connect_pads
			(clearance 0)
		)
		(min_thickness 0.25)
		(keepout
			(tracks not_allowed)
			(vias allowed)
			(pads allowed)
			(copperpour not_allowed)
			(footprints allowed)
		)
		(placement
			(enabled no)
			(sheetname "")
		)
		(fill yes
			(thermal_gap 0.5)
			(thermal_bridge_width 0.5)
			(island_removal_mode 0)
		)
		(polygon
			(pts
				(arc
					(start 446.974468 -199.035162)
					(mid 446.314068 -199.035162)
					(end 446.974468 -199.035162)
				)
			)
		)
	)
	(zone
		(layers "In1.Cu" "In2.Cu")
		(hatch none 0.5)
		(connect_pads
			(clearance 0)
		)
		(min_thickness 0.25)
		(keepout
			(tracks not_allowed)
			(vias allowed)
			(pads allowed)
			(copperpour not_allowed)
			(footprints allowed)
		)
		(placement
			(enabled no)
			(sheetname "")
		)
		(fill yes
			(thermal_gap 0.5)
			(thermal_bridge_width 0.5)
			(island_removal_mode 0)
		)
		(polygon
			(pts
				(arc
					(start 454.518268 -296.78503)
					(mid 453.857868 -296.78503)
					(end 454.518268 -296.78503)
				)
			)
		)
	)
	(zone
		(layers "In1.Cu" "In2.Cu")
		(hatch none 0.5)
		(connect_pads
			(clearance 0)
		)
		(min_thickness 0.25)
		(keepout
			(tracks not_allowed)
			(vias allowed)
			(pads allowed)
			(copperpour not_allowed)
			(footprints allowed)
		)
		(placement
			(enabled no)
			(sheetname "")
		)
		(fill yes
			(thermal_gap 0.5)
			(thermal_bridge_width 0.5)
			(island_removal_mode 0)
		)
		(polygon
			(pts
				(arc
					(start 40.57015 -226.23526)
					(mid 39.90975 -226.23526)
					(end 40.57015 -226.23526)
				)
			)
		)
	)
	(zone
		(layers "In1.Cu" "In2.Cu")
		(hatch none 0.5)
		(connect_pads
			(clearance 0)
		)
		(min_thickness 0.25)
		(keepout
			(tracks not_allowed)
			(vias allowed)
			(pads allowed)
			(copperpour not_allowed)
			(footprints allowed)
		)
		(placement
			(enabled no)
			(sheetname "")
		)
		(fill yes
			(thermal_gap 0.5)
			(thermal_bridge_width 0.5)
			(island_removal_mode 0)
		)
		(polygon
			(pts
				(arc
					(start 277.522432 -281.485086)
					(mid 276.862032 -281.485086)
					(end 277.522432 -281.485086)
				)
			)
		)
	)
	(zone
		(layers "In1.Cu" "In2.Cu")
		(hatch none 0.5)
		(connect_pads
			(clearance 0)
		)
		(min_thickness 0.25)
		(keepout
			(tracks not_allowed)
			(vias allowed)
			(pads allowed)
			(copperpour not_allowed)
			(footprints allowed)
		)
		(placement
			(enabled no)
			(sheetname "")
		)
		(fill yes
			(thermal_gap 0.5)
			(thermal_bridge_width 0.5)
			(island_removal_mode 0)
		)
		(polygon
			(pts
				(arc
					(start 172.30217 -305.285394)
					(mid 171.64177 -305.285394)
					(end 172.30217 -305.285394)
				)
			)
		)
	)
	(zone
		(layers "In1.Cu" "In2.Cu")
		(hatch none 0.5)
		(connect_pads
			(clearance 0)
		)
		(min_thickness 0.25)
		(keepout
			(tracks not_allowed)
			(vias allowed)
			(pads allowed)
			(copperpour not_allowed)
			(footprints allowed)
		)
		(placement
			(enabled no)
			(sheetname "")
		)
		(fill yes
			(thermal_gap 0.5)
			(thermal_bridge_width 0.5)
			(island_removal_mode 0)
		)
		(polygon
			(pts
				(arc
					(start 273.422364 -250.03506)
					(mid 272.761964 -250.03506)
					(end 273.422364 -250.03506)
				)
			)
		)
	)
	(zone
		(layers "In1.Cu" "In2.Cu")
		(hatch none 0.5)
		(connect_pads
			(clearance 0)
		)
		(min_thickness 0.25)
		(keepout
			(tracks not_allowed)
			(vias allowed)
			(pads allowed)
			(copperpour not_allowed)
			(footprints allowed)
		)
		(placement
			(enabled no)
			(sheetname "")
		)
		(fill yes
			(thermal_gap 0.5)
			(thermal_bridge_width 0.5)
			(island_removal_mode 0)
		)
		(polygon
			(pts
				(arc
					(start 52.214272 -303.585372)
					(mid 51.553872 -303.585372)
					(end 52.214272 -303.585372)
				)
			)
		)
	)
	(zone
		(layers "In1.Cu" "In2.Cu")
		(hatch none 0.5)
		(connect_pads
			(clearance 0)
		)
		(min_thickness 0.25)
		(keepout
			(tracks not_allowed)
			(vias allowed)
			(pads allowed)
			(copperpour not_allowed)
			(footprints allowed)
		)
		(placement
			(enabled no)
			(sheetname "")
		)
		(fill yes
			(thermal_gap 0.5)
			(thermal_bridge_width 0.5)
			(island_removal_mode 0)
		)
		(polygon
			(pts
				(arc
					(start 95.031052 -375.906284)
					(mid 95.050976 -375.91552)
					(end 95.072708 -375.91873)
				)
				(arc
					(start 95.267272 -375.91873)
					(mid 95.321154 -375.896412)
					(end 95.343472 -375.84253)
				)
				(arc
					(start 95.343472 -375.15673)
					(mid 95.321154 -375.102848)
					(end 95.267272 -375.08053)
				)
				(arc
					(start 95.072708 -375.08053)
					(mid 95.050964 -375.083698)
					(end 95.031052 -375.092976)
				)
				(arc
					(start 94.734888 -375.285762)
					(mid 94.693204 -375.297984)
					(end 94.651576 -375.285508)
				)
				(arc
					(start 94.357952 -375.092976)
					(mid 94.338028 -375.08374)
					(end 94.316296 -375.08053)
				)
				(arc
					(start 94.121732 -375.08053)
					(mid 94.06785 -375.102848)
					(end 94.045532 -375.15673)
				)
				(arc
					(start 94.045532 -375.84253)
					(mid 94.06785 -375.896412)
					(end 94.121732 -375.91873)
				)
				(arc
					(start 94.317566 -375.91873)
					(mid 94.33931 -375.915562)
					(end 94.359222 -375.906284)
				)
				(arc
					(start 94.652846 -375.713752)
					(mid 94.694502 -375.70135)
					(end 94.736158 -375.713752)
				)
			)
		)
	)
	(zone
		(layers "In1.Cu" "In2.Cu")
		(hatch none 0.5)
		(connect_pads
			(clearance 0)
		)
		(min_thickness 0.25)
		(keepout
			(tracks not_allowed)
			(vias allowed)
			(pads allowed)
			(copperpour not_allowed)
			(footprints allowed)
		)
		(placement
			(enabled no)
			(sheetname "")
		)
		(fill yes
			(thermal_gap 0.5)
			(thermal_bridge_width 0.5)
			(island_removal_mode 0)
		)
		(polygon
			(pts
				(arc
					(start 450.4182 -230.485188)
					(mid 449.7578 -230.485188)
					(end 450.4182 -230.485188)
				)
			)
		)
	)
	(zone
		(layers "In1.Cu" "In2.Cu")
		(hatch none 0.5)
		(connect_pads
			(clearance 0)
		)
		(min_thickness 0.25)
		(keepout
			(tracks not_allowed)
			(vias allowed)
			(pads allowed)
			(copperpour not_allowed)
			(footprints allowed)
		)
		(placement
			(enabled no)
			(sheetname "")
		)
		(fill yes
			(thermal_gap 0.5)
			(thermal_bridge_width 0.5)
			(island_removal_mode 0)
		)
		(polygon
			(pts
				(arc
					(start 442.8744 -222.834962)
					(mid 442.214 -222.834962)
					(end 442.8744 -222.834962)
				)
			)
		)
	)
	(zone
		(layers "In1.Cu" "In2.Cu")
		(hatch none 0.5)
		(connect_pads
			(clearance 0)
		)
		(min_thickness 0.25)
		(keepout
			(tracks not_allowed)
			(vias allowed)
			(pads allowed)
			(copperpour not_allowed)
			(footprints allowed)
		)
		(placement
			(enabled no)
			(sheetname "")
		)
		(fill yes
			(thermal_gap 0.5)
			(thermal_bridge_width 0.5)
			(island_removal_mode 0)
		)
		(polygon
			(pts
				(arc
					(start 40.57015 -220.28531)
					(mid 39.90975 -220.28531)
					(end 40.57015 -220.28531)
				)
			)
		)
	)
	(zone
		(layers "In1.Cu" "In2.Cu")
		(hatch none 0.5)
		(connect_pads
			(clearance 0)
		)
		(min_thickness 0.25)
		(keepout
			(tracks not_allowed)
			(vias allowed)
			(pads allowed)
			(copperpour not_allowed)
			(footprints allowed)
		)
		(placement
			(enabled no)
			(sheetname "")
		)
		(fill yes
			(thermal_gap 0.5)
			(thermal_bridge_width 0.5)
			(island_removal_mode 0)
		)
		(polygon
			(pts
				(arc
					(start 194.934332 -263.635236)
					(mid 194.273932 -263.635236)
					(end 194.934332 -263.635236)
				)
			)
		)
	)
	(zone
		(layers "In1.Cu" "In2.Cu")
		(hatch none 0.5)
		(connect_pads
			(clearance 0)
		)
		(min_thickness 0.25)
		(keepout
			(tracks not_allowed)
			(vias allowed)
			(pads allowed)
			(copperpour not_allowed)
			(footprints allowed)
		)
		(placement
			(enabled no)
			(sheetname "")
		)
		(fill yes
			(thermal_gap 0.5)
			(thermal_bridge_width 0.5)
			(island_removal_mode 0)
		)
		(polygon
			(pts
				(arc
					(start 277.522432 -273.835114)
					(mid 276.862032 -273.835114)
					(end 277.522432 -273.835114)
				)
			)
		)
	)
	(zone
		(layers "In1.Cu" "In2.Cu")
		(hatch none 0.5)
		(connect_pads
			(clearance 0)
		)
		(min_thickness 0.25)
		(keepout
			(tracks not_allowed)
			(vias allowed)
			(pads allowed)
			(copperpour not_allowed)
			(footprints allowed)
		)
		(placement
			(enabled no)
			(sheetname "")
		)
		(fill yes
			(thermal_gap 0.5)
			(thermal_bridge_width 0.5)
			(island_removal_mode 0)
		)
		(polygon
			(pts
				(arc
					(start 25.482296 -227.935282)
					(mid 24.821896 -227.935282)
					(end 25.482296 -227.935282)
				)
			)
		)
	)
	(zone
		(layers "In1.Cu" "In2.Cu")
		(hatch none 0.5)
		(connect_pads
			(clearance 0)
		)
		(min_thickness 0.25)
		(keepout
			(tracks not_allowed)
			(vias allowed)
			(pads allowed)
			(copperpour not_allowed)
			(footprints allowed)
		)
		(placement
			(enabled no)
			(sheetname "")
		)
		(fill yes
			(thermal_gap 0.5)
			(thermal_bridge_width 0.5)
			(island_removal_mode 0)
		)
		(polygon
			(pts
				(arc
					(start 22.03831 -306.135278)
					(mid 21.37791 -306.135278)
					(end 22.03831 -306.135278)
				)
			)
		)
	)
	(zone
		(layers "In1.Cu" "In2.Cu")
		(hatch none 0.5)
		(connect_pads
			(clearance 0)
		)
		(min_thickness 0.25)
		(keepout
			(tracks not_allowed)
			(vias allowed)
			(pads allowed)
			(copperpour not_allowed)
			(footprints allowed)
		)
		(placement
			(enabled no)
			(sheetname "")
		)
		(fill yes
			(thermal_gap 0.5)
			(thermal_bridge_width 0.5)
			(island_removal_mode 0)
		)
		(polygon
			(pts
				(arc
					(start 435.330346 -313.784996)
					(mid 434.669946 -313.784996)
					(end 435.330346 -313.784996)
				)
			)
		)
	)
	(zone
		(layers "In1.Cu" "In2.Cu")
		(hatch none 0.5)
		(connect_pads
			(clearance 0)
		)
		(min_thickness 0.25)
		(keepout
			(tracks not_allowed)
			(vias allowed)
			(pads allowed)
			(copperpour not_allowed)
			(footprints allowed)
		)
		(placement
			(enabled no)
			(sheetname "")
		)
		(fill yes
			(thermal_gap 0.5)
			(thermal_bridge_width 0.5)
			(island_removal_mode 0)
		)
		(polygon
			(pts
				(arc
					(start 179.846224 -301.035212)
					(mid 179.185824 -301.035212)
					(end 179.846224 -301.035212)
				)
			)
		)
	)
	(zone
		(layers "In1.Cu" "In2.Cu")
		(hatch none 0.5)
		(connect_pads
			(clearance 0)
		)
		(min_thickness 0.25)
		(keepout
			(tracks not_allowed)
			(vias allowed)
			(pads allowed)
			(copperpour not_allowed)
			(footprints allowed)
		)
		(placement
			(enabled no)
			(sheetname "")
		)
		(fill yes
			(thermal_gap 0.5)
			(thermal_bridge_width 0.5)
			(island_removal_mode 0)
		)
		(polygon
			(pts
				(arc
					(start 40.57015 -291.685218)
					(mid 39.90975 -291.685218)
					(end 40.57015 -291.685218)
				)
			)
		)
	)
	(zone
		(layers "In1.Cu" "In2.Cu")
		(hatch none 0.5)
		(connect_pads
			(clearance 0)
		)
		(min_thickness 0.25)
		(keepout
			(tracks not_allowed)
			(vias allowed)
			(pads allowed)
			(copperpour not_allowed)
			(footprints allowed)
		)
		(placement
			(enabled no)
			(sheetname "")
		)
		(fill yes
			(thermal_gap 0.5)
			(thermal_bridge_width 0.5)
			(island_removal_mode 0)
		)
		(polygon
			(pts
				(arc
					(start 191.490346 -267.885418)
					(mid 190.829946 -267.885418)
					(end 191.490346 -267.885418)
				)
			)
		)
	)
	(zone
		(layers "In1.Cu" "In2.Cu")
		(hatch none 0.5)
		(connect_pads
			(clearance 0)
		)
		(min_thickness 0.25)
		(keepout
			(tracks not_allowed)
			(vias allowed)
			(pads allowed)
			(copperpour not_allowed)
			(footprints allowed)
		)
		(placement
			(enabled no)
			(sheetname "")
		)
		(fill yes
			(thermal_gap 0.5)
			(thermal_bridge_width 0.5)
			(island_removal_mode 0)
		)
		(polygon
			(pts
				(arc
					(start 179.846224 -254.285242)
					(mid 179.185824 -254.285242)
					(end 179.846224 -254.285242)
				)
			)
		)
	)
	(zone
		(layers "In1.Cu" "In2.Cu")
		(hatch none 0.5)
		(connect_pads
			(clearance 0)
		)
		(min_thickness 0.25)
		(keepout
			(tracks not_allowed)
			(vias allowed)
			(pads allowed)
			(copperpour not_allowed)
			(footprints allowed)
		)
		(placement
			(enabled no)
			(sheetname "")
		)
		(fill yes
			(thermal_gap 0.5)
			(thermal_bridge_width 0.5)
			(island_removal_mode 0)
		)
		(polygon
			(pts
				(arc
					(start 202.478132 -318.035432)
					(mid 201.817732 -318.035432)
					(end 202.478132 -318.035432)
				)
			)
		)
	)
	(zone
		(layers "In1.Cu" "In2.Cu")
		(hatch none 0.5)
		(connect_pads
			(clearance 0)
		)
		(min_thickness 0.25)
		(keepout
			(tracks not_allowed)
			(vias allowed)
			(pads allowed)
			(copperpour not_allowed)
			(footprints allowed)
		)
		(placement
			(enabled no)
			(sheetname "")
		)
		(fill yes
			(thermal_gap 0.5)
			(thermal_bridge_width 0.5)
			(island_removal_mode 0)
		)
		(polygon
			(pts
				(arc
					(start 25.482296 -216.885266)
					(mid 24.821896 -216.885266)
					(end 25.482296 -216.885266)
				)
			)
		)
	)
	(zone
		(layers "In1.Cu" "In2.Cu")
		(hatch none 0.5)
		(connect_pads
			(clearance 0)
		)
		(min_thickness 0.25)
		(keepout
			(tracks not_allowed)
			(vias allowed)
			(pads allowed)
			(copperpour not_allowed)
			(footprints allowed)
		)
		(placement
			(enabled no)
			(sheetname "")
		)
		(fill yes
			(thermal_gap 0.5)
			(thermal_bridge_width 0.5)
			(island_removal_mode 0)
		)
		(polygon
			(pts
				(arc
					(start 43.783504 -373.442484)
					(mid 43.803428 -373.45172)
					(end 43.82516 -373.45493)
				)
				(arc
					(start 44.019724 -373.45493)
					(mid 44.073606 -373.432612)
					(end 44.095924 -373.37873)
				)
				(arc
					(start 44.095924 -372.69293)
					(mid 44.073606 -372.639048)
					(end 44.019724 -372.61673)
				)
				(arc
					(start 43.82516 -372.61673)
					(mid 43.803416 -372.619898)
					(end 43.783504 -372.629176)
				)
				(arc
					(start 43.48734 -372.821962)
					(mid 43.445656 -372.834184)
					(end 43.404028 -372.821708)
				)
				(arc
					(start 43.110404 -372.629176)
					(mid 43.09048 -372.61994)
					(end 43.068748 -372.61673)
				)
				(arc
					(start 42.874184 -372.61673)
					(mid 42.820302 -372.639048)
					(end 42.797984 -372.69293)
				)
				(arc
					(start 42.797984 -373.37873)
					(mid 42.820302 -373.432612)
					(end 42.874184 -373.45493)
				)
				(arc
					(start 43.070018 -373.45493)
					(mid 43.091762 -373.451762)
					(end 43.111674 -373.442484)
				)
				(arc
					(start 43.405298 -373.249952)
					(mid 43.446954 -373.23755)
					(end 43.48861 -373.249952)
				)
			)
		)
	)
	(zone
		(layers "In1.Cu" "In2.Cu")
		(hatch none 0.5)
		(connect_pads
			(clearance 0)
		)
		(min_thickness 0.25)
		(keepout
			(tracks not_allowed)
			(vias allowed)
			(pads allowed)
			(copperpour not_allowed)
			(footprints allowed)
		)
		(placement
			(enabled no)
			(sheetname "")
		)
		(fill yes
			(thermal_gap 0.5)
			(thermal_bridge_width 0.5)
			(island_removal_mode 0)
		)
		(polygon
			(pts
				(arc
					(start 44.670218 -303.585372)
					(mid 44.009818 -303.585372)
					(end 44.670218 -303.585372)
				)
			)
		)
	)
	(zone
		(layers "In1.Cu" "In2.Cu")
		(hatch none 0.5)
		(connect_pads
			(clearance 0)
		)
		(min_thickness 0.25)
		(keepout
			(tracks not_allowed)
			(vias allowed)
			(pads allowed)
			(copperpour not_allowed)
			(footprints allowed)
		)
		(placement
			(enabled no)
			(sheetname "")
		)
		(fill yes
			(thermal_gap 0.5)
			(thermal_bridge_width 0.5)
			(island_removal_mode 0)
		)
		(polygon
			(pts
				(arc
					(start 52.214272 -267.885418)
					(mid 51.553872 -267.885418)
					(end 52.214272 -267.885418)
				)
			)
		)
	)
	(zone
		(layers "In1.Cu" "In2.Cu")
		(hatch none 0.5)
		(connect_pads
			(clearance 0)
		)
		(min_thickness 0.25)
		(keepout
			(tracks not_allowed)
			(vias allowed)
			(pads allowed)
			(copperpour not_allowed)
			(footprints allowed)
		)
		(placement
			(enabled no)
			(sheetname "")
		)
		(fill yes
			(thermal_gap 0.5)
			(thermal_bridge_width 0.5)
			(island_removal_mode 0)
		)
		(polygon
			(pts
				(arc
					(start 292.610286 -208.385156)
					(mid 291.949886 -208.385156)
					(end 292.610286 -208.385156)
				)
			)
		)
	)
	(zone
		(layers "In1.Cu" "In2.Cu")
		(hatch none 0.5)
		(connect_pads
			(clearance 0)
		)
		(min_thickness 0.25)
		(keepout
			(tracks not_allowed)
			(vias allowed)
			(pads allowed)
			(copperpour not_allowed)
			(footprints allowed)
		)
		(placement
			(enabled no)
			(sheetname "")
		)
		(fill yes
			(thermal_gap 0.5)
			(thermal_bridge_width 0.5)
			(island_removal_mode 0)
		)
		(polygon
			(pts
				(arc
					(start 48.114204 -215.185244)
					(mid 47.453804 -215.185244)
					(end 48.114204 -215.185244)
				)
			)
		)
	)
	(zone
		(layers "In1.Cu" "In2.Cu")
		(hatch none 0.5)
		(connect_pads
			(clearance 0)
		)
		(min_thickness 0.25)
		(keepout
			(tracks not_allowed)
			(vias allowed)
			(pads allowed)
			(copperpour not_allowed)
			(footprints allowed)
		)
		(placement
			(enabled no)
			(sheetname "")
		)
		(fill yes
			(thermal_gap 0.5)
			(thermal_bridge_width 0.5)
			(island_removal_mode 0)
		)
		(polygon
			(pts
				(arc
					(start 442.8744 -241.53495)
					(mid 442.214 -241.53495)
					(end 442.8744 -241.53495)
				)
			)
		)
	)
	(zone
		(layers "In1.Cu" "In2.Cu")
		(hatch none 0.5)
		(connect_pads
			(clearance 0)
		)
		(min_thickness 0.25)
		(keepout
			(tracks not_allowed)
			(vias allowed)
			(pads allowed)
			(copperpour not_allowed)
			(footprints allowed)
		)
		(placement
			(enabled no)
			(sheetname "")
		)
		(fill yes
			(thermal_gap 0.5)
			(thermal_bridge_width 0.5)
			(island_removal_mode 0)
		)
		(polygon
			(pts
				(arc
					(start 48.114204 -304.435256)
					(mid 47.453804 -304.435256)
					(end 48.114204 -304.435256)
				)
			)
		)
	)
	(zone
		(layers "In1.Cu" "In2.Cu")
		(hatch none 0.5)
		(connect_pads
			(clearance 0)
		)
		(min_thickness 0.25)
		(keepout
			(tracks not_allowed)
			(vias allowed)
			(pads allowed)
			(copperpour not_allowed)
			(footprints allowed)
		)
		(placement
			(enabled no)
			(sheetname "")
		)
		(fill yes
			(thermal_gap 0.5)
			(thermal_bridge_width 0.5)
			(island_removal_mode 0)
		)
		(polygon
			(pts
				(arc
					(start 393.352274 -7.672324)
					(mid 393.374592 -7.618442)
					(end 393.428474 -7.596124)
				)
				(arc
					(start 394.465048 -7.596124)
					(mid 394.51893 -7.618442)
					(end 394.541248 -7.672324)
				)
				(arc
					(start 394.541248 -9.071864)
					(mid 394.51893 -9.125746)
					(end 394.465048 -9.148064)
				)
				(arc
					(start 393.428474 -9.148064)
					(mid 393.374592 -9.125746)
					(end 393.352274 -9.071864)
				)
			)
		)
	)
	(zone
		(layers "In1.Cu" "In2.Cu")
		(hatch none 0.5)
		(connect_pads
			(clearance 0)
		)
		(min_thickness 0.25)
		(keepout
			(tracks not_allowed)
			(vias allowed)
			(pads allowed)
			(copperpour not_allowed)
			(footprints allowed)
		)
		(placement
			(enabled no)
			(sheetname "")
		)
		(fill yes
			(thermal_gap 0.5)
			(thermal_bridge_width 0.5)
			(island_removal_mode 0)
		)
		(polygon
			(pts
				(arc
					(start 285.066232 -269.585186)
					(mid 284.405832 -269.585186)
					(end 285.066232 -269.585186)
				)
			)
		)
	)
	(zone
		(layers "In1.Cu" "In2.Cu")
		(hatch none 0.5)
		(connect_pads
			(clearance 0)
		)
		(min_thickness 0.25)
		(keepout
			(tracks not_allowed)
			(vias allowed)
			(pads allowed)
			(copperpour not_allowed)
			(footprints allowed)
		)
		(placement
			(enabled no)
			(sheetname "")
		)
		(fill yes
			(thermal_gap 0.5)
			(thermal_bridge_width 0.5)
			(island_removal_mode 0)
		)
		(polygon
			(pts
				(arc
					(start 454.518268 -309.535068)
					(mid 453.857868 -309.535068)
					(end 454.518268 -309.535068)
				)
			)
		)
	)
	(zone
		(layers "In1.Cu" "In2.Cu")
		(hatch none 0.5)
		(connect_pads
			(clearance 0)
		)
		(min_thickness 0.25)
		(keepout
			(tracks not_allowed)
			(vias allowed)
			(pads allowed)
			(copperpour not_allowed)
			(footprints allowed)
		)
		(placement
			(enabled no)
			(sheetname "")
		)
		(fill yes
			(thermal_gap 0.5)
			(thermal_bridge_width 0.5)
			(island_removal_mode 0)
		)
		(polygon
			(pts
				(arc
					(start 450.4182 -250.03506)
					(mid 449.7578 -250.03506)
					(end 450.4182 -250.03506)
				)
			)
		)
	)
	(zone
		(layers "In1.Cu" "In2.Cu")
		(hatch none 0.5)
		(connect_pads
			(clearance 0)
		)
		(min_thickness 0.25)
		(keepout
			(tracks not_allowed)
			(vias allowed)
			(pads allowed)
			(copperpour not_allowed)
			(footprints allowed)
		)
		(placement
			(enabled no)
			(sheetname "")
		)
		(fill yes
			(thermal_gap 0.5)
			(thermal_bridge_width 0.5)
			(island_removal_mode 0)
		)
		(polygon
			(pts
				(arc
					(start 427.786292 -210.935062)
					(mid 427.125892 -210.935062)
					(end 427.786292 -210.935062)
				)
			)
		)
	)
	(zone
		(layers "In1.Cu" "In2.Cu")
		(hatch none 0.5)
		(connect_pads
			(clearance 0)
		)
		(min_thickness 0.25)
		(keepout
			(tracks not_allowed)
			(vias allowed)
			(pads allowed)
			(copperpour not_allowed)
			(footprints allowed)
		)
		(placement
			(enabled no)
			(sheetname "")
		)
		(fill yes
			(thermal_gap 0.5)
			(thermal_bridge_width 0.5)
			(island_removal_mode 0)
		)
		(polygon
			(pts
				(arc
					(start 280.966164 -295.085008)
					(mid 280.305764 -295.085008)
					(end 280.966164 -295.085008)
				)
			)
		)
	)
	(zone
		(layers "In1.Cu" "In2.Cu")
		(hatch none 0.5)
		(connect_pads
			(clearance 0)
		)
		(min_thickness 0.25)
		(keepout
			(tracks not_allowed)
			(vias allowed)
			(pads allowed)
			(copperpour not_allowed)
			(footprints allowed)
		)
		(placement
			(enabled no)
			(sheetname "")
		)
		(fill yes
			(thermal_gap 0.5)
			(thermal_bridge_width 0.5)
			(island_removal_mode 0)
		)
		(polygon
			(pts
				(arc
					(start 194.934332 -199.8853)
					(mid 194.273932 -199.8853)
					(end 194.934332 -199.8853)
				)
			)
		)
	)
	(zone
		(layers "In1.Cu" "In2.Cu")
		(hatch none 0.5)
		(connect_pads
			(clearance 0)
		)
		(min_thickness 0.25)
		(keepout
			(tracks not_allowed)
			(vias allowed)
			(pads allowed)
			(copperpour not_allowed)
			(footprints allowed)
		)
		(placement
			(enabled no)
			(sheetname "")
		)
		(fill yes
			(thermal_gap 0.5)
			(thermal_bridge_width 0.5)
			(island_removal_mode 0)
		)
		(polygon
			(pts
				(arc
					(start 427.786292 -248.335038)
					(mid 427.125892 -248.335038)
					(end 427.786292 -248.335038)
				)
			)
		)
	)
	(zone
		(layers "In1.Cu" "In2.Cu")
		(hatch none 0.5)
		(connect_pads
			(clearance 0)
		)
		(min_thickness 0.25)
		(keepout
			(tracks not_allowed)
			(vias allowed)
			(pads allowed)
			(copperpour not_allowed)
			(footprints allowed)
		)
		(placement
			(enabled no)
			(sheetname "")
		)
		(fill yes
			(thermal_gap 0.5)
			(thermal_bridge_width 0.5)
			(island_removal_mode 0)
		)
		(polygon
			(pts
				(arc
					(start 29.582364 -204.985366)
					(mid 28.921964 -204.985366)
					(end 29.582364 -204.985366)
				)
			)
		)
	)
	(zone
		(layers "In1.Cu" "In2.Cu")
		(hatch none 0.5)
		(connect_pads
			(clearance 0)
		)
		(min_thickness 0.25)
		(keepout
			(tracks not_allowed)
			(vias allowed)
			(pads allowed)
			(copperpour not_allowed)
			(footprints allowed)
		)
		(placement
			(enabled no)
			(sheetname "")
		)
		(fill yes
			(thermal_gap 0.5)
			(thermal_bridge_width 0.5)
			(island_removal_mode 0)
		)
		(polygon
			(pts
				(arc
					(start 285.066232 -264.48512)
					(mid 284.405832 -264.48512)
					(end 285.066232 -264.48512)
				)
			)
		)
	)
	(zone
		(layers "In1.Cu" "In2.Cu")
		(hatch none 0.5)
		(connect_pads
			(clearance 0)
		)
		(min_thickness 0.25)
		(keepout
			(tracks not_allowed)
			(vias allowed)
			(pads allowed)
			(copperpour not_allowed)
			(footprints allowed)
		)
		(placement
			(enabled no)
			(sheetname "")
		)
		(fill yes
			(thermal_gap 0.5)
			(thermal_bridge_width 0.5)
			(island_removal_mode 0)
		)
		(polygon
			(pts
				(arc
					(start 424.342306 -199.035162)
					(mid 423.681906 -199.035162)
					(end 424.342306 -199.035162)
				)
			)
		)
	)
	(zone
		(layers "In1.Cu" "In2.Cu")
		(hatch none 0.5)
		(connect_pads
			(clearance 0)
		)
		(min_thickness 0.25)
		(keepout
			(tracks not_allowed)
			(vias allowed)
			(pads allowed)
			(copperpour not_allowed)
			(footprints allowed)
		)
		(placement
			(enabled no)
			(sheetname "")
		)
		(fill yes
			(thermal_gap 0.5)
			(thermal_bridge_width 0.5)
			(island_removal_mode 0)
		)
		(polygon
			(pts
				(arc
					(start 454.518268 -252.584966)
					(mid 453.857868 -252.584966)
					(end 454.518268 -252.584966)
				)
			)
		)
	)
	(zone
		(layers "In1.Cu" "In2.Cu")
		(hatch none 0.5)
		(connect_pads
			(clearance 0)
		)
		(min_thickness 0.25)
		(keepout
			(tracks not_allowed)
			(vias allowed)
			(pads allowed)
			(copperpour not_allowed)
			(footprints allowed)
		)
		(placement
			(enabled no)
			(sheetname "")
		)
		(fill yes
			(thermal_gap 0.5)
			(thermal_bridge_width 0.5)
			(island_removal_mode 0)
		)
		(polygon
			(pts
				(arc
					(start 52.214272 -234.73537)
					(mid 51.553872 -234.73537)
					(end 52.214272 -234.73537)
				)
			)
		)
	)
	(zone
		(layers "In1.Cu" "In2.Cu")
		(hatch none 0.5)
		(connect_pads
			(clearance 0)
		)
		(min_thickness 0.25)
		(keepout
			(tracks not_allowed)
			(vias allowed)
			(pads allowed)
			(copperpour not_allowed)
			(footprints allowed)
		)
		(placement
			(enabled no)
			(sheetname "")
		)
		(fill yes
			(thermal_gap 0.5)
			(thermal_bridge_width 0.5)
			(island_removal_mode 0)
		)
		(polygon
			(pts
				(arc
					(start 300.15434 -223.6851)
					(mid 299.49394 -223.6851)
					(end 300.15434 -223.6851)
				)
			)
		)
	)
	(zone
		(layers "In1.Cu" "In2.Cu")
		(hatch none 0.5)
		(connect_pads
			(clearance 0)
		)
		(min_thickness 0.25)
		(keepout
			(tracks not_allowed)
			(vias allowed)
			(pads allowed)
			(copperpour not_allowed)
			(footprints allowed)
		)
		(placement
			(enabled no)
			(sheetname "")
		)
		(fill yes
			(thermal_gap 0.5)
			(thermal_bridge_width 0.5)
			(island_removal_mode 0)
		)
		(polygon
			(pts
				(arc
					(start 292.610286 -306.135024)
					(mid 291.949886 -306.135024)
					(end 292.610286 -306.135024)
				)
			)
		)
	)
	(zone
		(layers "In1.Cu" "In2.Cu")
		(hatch none 0.5)
		(connect_pads
			(clearance 0)
		)
		(min_thickness 0.25)
		(keepout
			(tracks not_allowed)
			(vias allowed)
			(pads allowed)
			(copperpour not_allowed)
			(footprints allowed)
		)
		(placement
			(enabled no)
			(sheetname "")
		)
		(fill yes
			(thermal_gap 0.5)
			(thermal_bridge_width 0.5)
			(island_removal_mode 0)
		)
		(polygon
			(pts
				(arc
					(start 431.88636 -208.385156)
					(mid 431.22596 -208.385156)
					(end 431.88636 -208.385156)
				)
			)
		)
	)
	(zone
		(layers "In1.Cu" "In2.Cu")
		(hatch none 0.5)
		(connect_pads
			(clearance 0)
		)
		(min_thickness 0.25)
		(keepout
			(tracks not_allowed)
			(vias allowed)
			(pads allowed)
			(copperpour not_allowed)
			(footprints allowed)
		)
		(placement
			(enabled no)
			(sheetname "")
		)
		(fill yes
			(thermal_gap 0.5)
			(thermal_bridge_width 0.5)
			(island_removal_mode 0)
		)
		(polygon
			(pts
				(arc
					(start 420.242238 -205.834996)
					(mid 419.581838 -205.834996)
					(end 420.242238 -205.834996)
				)
			)
		)
	)
	(zone
		(layers "In1.Cu" "In2.Cu")
		(hatch none 0.5)
		(connect_pads
			(clearance 0)
		)
		(min_thickness 0.25)
		(keepout
			(tracks not_allowed)
			(vias allowed)
			(pads allowed)
			(copperpour not_allowed)
			(footprints allowed)
		)
		(placement
			(enabled no)
			(sheetname "")
		)
		(fill yes
			(thermal_gap 0.5)
			(thermal_bridge_width 0.5)
			(island_removal_mode 0)
		)
		(polygon
			(pts
				(arc
					(start 88.223852 -375.906284)
					(mid 88.243776 -375.91552)
					(end 88.265508 -375.91873)
				)
				(arc
					(start 88.460072 -375.91873)
					(mid 88.513954 -375.896412)
					(end 88.536272 -375.84253)
				)
				(arc
					(start 88.536272 -375.15673)
					(mid 88.513954 -375.102848)
					(end 88.460072 -375.08053)
				)
				(arc
					(start 88.265508 -375.08053)
					(mid 88.243764 -375.083698)
					(end 88.223852 -375.092976)
				)
				(arc
					(start 87.927688 -375.285762)
					(mid 87.886004 -375.297984)
					(end 87.844376 -375.285508)
				)
				(arc
					(start 87.550752 -375.092976)
					(mid 87.530828 -375.08374)
					(end 87.509096 -375.08053)
				)
				(arc
					(start 87.314532 -375.08053)
					(mid 87.26065 -375.102848)
					(end 87.238332 -375.15673)
				)
				(arc
					(start 87.238332 -375.84253)
					(mid 87.26065 -375.896412)
					(end 87.314532 -375.91873)
				)
				(arc
					(start 87.510366 -375.91873)
					(mid 87.53211 -375.915562)
					(end 87.552022 -375.906284)
				)
				(arc
					(start 87.845646 -375.713752)
					(mid 87.887302 -375.70135)
					(end 87.928958 -375.713752)
				)
			)
		)
	)
	(zone
		(layers "In1.Cu" "In2.Cu")
		(hatch none 0.5)
		(connect_pads
			(clearance 0)
		)
		(min_thickness 0.25)
		(keepout
			(tracks not_allowed)
			(vias allowed)
			(pads allowed)
			(copperpour not_allowed)
			(footprints allowed)
		)
		(placement
			(enabled no)
			(sheetname "")
		)
		(fill yes
			(thermal_gap 0.5)
			(thermal_bridge_width 0.5)
			(island_removal_mode 0)
		)
		(polygon
			(pts
				(arc
					(start 33.026096 -305.285394)
					(mid 32.365696 -305.285394)
					(end 33.026096 -305.285394)
				)
			)
		)
	)
	(zone
		(layers "In1.Cu" "In2.Cu")
		(hatch none 0.5)
		(connect_pads
			(clearance 0)
		)
		(min_thickness 0.25)
		(keepout
			(tracks not_allowed)
			(vias allowed)
			(pads allowed)
			(copperpour not_allowed)
			(footprints allowed)
		)
		(placement
			(enabled no)
			(sheetname "")
		)
		(fill yes
			(thermal_gap 0.5)
			(thermal_bridge_width 0.5)
			(island_removal_mode 0)
		)
		(polygon
			(pts
				(arc
					(start 431.88636 -287.435036)
					(mid 431.22596 -287.435036)
					(end 431.88636 -287.435036)
				)
			)
		)
	)
	(zone
		(layers "In1.Cu" "In2.Cu")
		(hatch none 0.5)
		(connect_pads
			(clearance 0)
		)
		(min_thickness 0.25)
		(keepout
			(tracks not_allowed)
			(vias allowed)
			(pads allowed)
			(copperpour not_allowed)
			(footprints allowed)
		)
		(placement
			(enabled no)
			(sheetname "")
		)
		(fill yes
			(thermal_gap 0.5)
			(thermal_bridge_width 0.5)
			(island_removal_mode 0)
		)
		(polygon
			(pts
				(arc
					(start 37.126164 -212.635338)
					(mid 36.465764 -212.635338)
					(end 37.126164 -212.635338)
				)
			)
		)
	)
	(zone
		(layers "In1.Cu" "In2.Cu")
		(hatch none 0.5)
		(connect_pads
			(clearance 0)
		)
		(min_thickness 0.25)
		(keepout
			(tracks not_allowed)
			(vias allowed)
			(pads allowed)
			(copperpour not_allowed)
			(footprints allowed)
		)
		(placement
			(enabled no)
			(sheetname "")
		)
		(fill yes
			(thermal_gap 0.5)
			(thermal_bridge_width 0.5)
			(island_removal_mode 0)
		)
		(polygon
			(pts
				(arc
					(start 119.392446 -370.978684)
					(mid 119.41237 -370.98792)
					(end 119.434102 -370.99113)
				)
				(arc
					(start 119.628666 -370.99113)
					(mid 119.682548 -370.968812)
					(end 119.704866 -370.91493)
				)
				(arc
					(start 119.704866 -370.22913)
					(mid 119.682548 -370.175248)
					(end 119.628666 -370.15293)
				)
				(arc
					(start 119.434102 -370.15293)
					(mid 119.412358 -370.156098)
					(end 119.392446 -370.165376)
				)
				(arc
					(start 119.096282 -370.358162)
					(mid 119.054598 -370.370384)
					(end 119.01297 -370.357908)
				)
				(arc
					(start 118.719346 -370.165376)
					(mid 118.699422 -370.15614)
					(end 118.67769 -370.15293)
				)
				(arc
					(start 118.483126 -370.15293)
					(mid 118.429244 -370.175248)
					(end 118.406926 -370.22913)
				)
				(arc
					(start 118.406926 -370.91493)
					(mid 118.429244 -370.968812)
					(end 118.483126 -370.99113)
				)
				(arc
					(start 118.67896 -370.99113)
					(mid 118.700704 -370.987962)
					(end 118.720616 -370.978684)
				)
				(arc
					(start 119.01424 -370.786152)
					(mid 119.055896 -370.77375)
					(end 119.097552 -370.786152)
				)
			)
		)
	)
	(zone
		(layers "In1.Cu" "In2.Cu")
		(hatch none 0.5)
		(connect_pads
			(clearance 0)
		)
		(min_thickness 0.25)
		(keepout
			(tracks not_allowed)
			(vias allowed)
			(pads allowed)
			(copperpour not_allowed)
			(footprints allowed)
		)
		(placement
			(enabled no)
			(sheetname "")
		)
		(fill yes
			(thermal_gap 0.5)
			(thermal_bridge_width 0.5)
			(island_removal_mode 0)
		)
		(polygon
			(pts
				(arc
					(start 269.978378 -206.685134)
					(mid 269.317978 -206.685134)
					(end 269.978378 -206.685134)
				)
			)
		)
	)
	(zone
		(layers "In1.Cu" "In2.Cu")
		(hatch none 0.5)
		(connect_pads
			(clearance 0)
		)
		(min_thickness 0.25)
		(keepout
			(tracks not_allowed)
			(vias allowed)
			(pads allowed)
			(copperpour not_allowed)
			(footprints allowed)
		)
		(placement
			(enabled no)
			(sheetname "")
		)
		(fill yes
			(thermal_gap 0.5)
			(thermal_bridge_width 0.5)
			(island_removal_mode 0)
		)
		(polygon
			(pts
				(arc
					(start 269.978378 -250.884944)
					(mid 269.317978 -250.884944)
					(end 269.978378 -250.884944)
				)
			)
		)
	)
	(zone
		(layers "In1.Cu" "In2.Cu")
		(hatch none 0.5)
		(connect_pads
			(clearance 0)
		)
		(min_thickness 0.25)
		(keepout
			(tracks not_allowed)
			(vias allowed)
			(pads allowed)
			(copperpour not_allowed)
			(footprints allowed)
		)
		(placement
			(enabled no)
			(sheetname "")
		)
		(fill yes
			(thermal_gap 0.5)
			(thermal_bridge_width 0.5)
			(island_removal_mode 0)
		)
		(polygon
			(pts
				(arc
					(start 442.8744 -239.835182)
					(mid 442.214 -239.835182)
					(end 442.8744 -239.835182)
				)
			)
		)
	)
	(zone
		(layers "In1.Cu" "In2.Cu")
		(hatch none 0.5)
		(connect_pads
			(clearance 0)
		)
		(min_thickness 0.25)
		(keepout
			(tracks not_allowed)
			(vias allowed)
			(pads allowed)
			(copperpour not_allowed)
			(footprints allowed)
		)
		(placement
			(enabled no)
			(sheetname "")
		)
		(fill yes
			(thermal_gap 0.5)
			(thermal_bridge_width 0.5)
			(island_removal_mode 0)
		)
		(polygon
			(pts
				(arc
					(start 202.478132 -274.685252)
					(mid 201.817732 -274.685252)
					(end 202.478132 -274.685252)
				)
			)
		)
	)
	(zone
		(layers "In1.Cu" "In2.Cu")
		(hatch none 0.5)
		(connect_pads
			(clearance 0)
		)
		(min_thickness 0.25)
		(keepout
			(tracks not_allowed)
			(vias allowed)
			(pads allowed)
			(copperpour not_allowed)
			(footprints allowed)
		)
		(placement
			(enabled no)
			(sheetname "")
		)
		(fill yes
			(thermal_gap 0.5)
			(thermal_bridge_width 0.5)
			(island_removal_mode 0)
		)
		(polygon
			(pts
				(arc
					(start 280.966164 -285.735014)
					(mid 280.305764 -285.735014)
					(end 280.966164 -285.735014)
				)
			)
		)
	)
	(zone
		(layers "In1.Cu" "In2.Cu")
		(hatch none 0.5)
		(connect_pads
			(clearance 0)
		)
		(min_thickness 0.25)
		(keepout
			(tracks not_allowed)
			(vias allowed)
			(pads allowed)
			(copperpour not_allowed)
			(footprints allowed)
		)
		(placement
			(enabled no)
			(sheetname "")
		)
		(fill yes
			(thermal_gap 0.5)
			(thermal_bridge_width 0.5)
			(island_removal_mode 0)
		)
		(polygon
			(pts
				(arc
					(start 401.741386 -11.91768)
					(mid 401.719068 -11.971562)
					(end 401.665186 -11.99388)
				)
				(arc
					(start 400.628612 -11.99388)
					(mid 400.57473 -11.971562)
					(end 400.552412 -11.91768)
				)
				(arc
					(start 400.552412 -10.51814)
					(mid 400.57473 -10.464258)
					(end 400.628612 -10.44194)
				)
				(arc
					(start 401.665186 -10.44194)
					(mid 401.719068 -10.464258)
					(end 401.741386 -10.51814)
				)
			)
		)
	)
	(zone
		(layers "In1.Cu" "In2.Cu")
		(hatch none 0.5)
		(connect_pads
			(clearance 0)
		)
		(min_thickness 0.25)
		(keepout
			(tracks not_allowed)
			(vias allowed)
			(pads allowed)
			(copperpour not_allowed)
			(footprints allowed)
		)
		(placement
			(enabled no)
			(sheetname "")
		)
		(fill yes
			(thermal_gap 0.5)
			(thermal_bridge_width 0.5)
			(island_removal_mode 0)
		)
		(polygon
			(pts
				(arc
					(start 439.430414 -296.78503)
					(mid 438.770014 -296.78503)
					(end 439.430414 -296.78503)
				)
			)
		)
	)
	(zone
		(layers "In1.Cu" "In2.Cu")
		(hatch none 0.5)
		(connect_pads
			(clearance 0)
		)
		(min_thickness 0.25)
		(keepout
			(tracks not_allowed)
			(vias allowed)
			(pads allowed)
			(copperpour not_allowed)
			(footprints allowed)
		)
		(placement
			(enabled no)
			(sheetname "")
		)
		(fill yes
			(thermal_gap 0.5)
			(thermal_bridge_width 0.5)
			(island_removal_mode 0)
		)
		(polygon
			(pts
				(arc
					(start 431.88636 -309.535068)
					(mid 431.22596 -309.535068)
					(end 431.88636 -309.535068)
				)
			)
		)
	)
	(zone
		(layers "In1.Cu" "In2.Cu")
		(hatch none 0.5)
		(connect_pads
			(clearance 0)
		)
		(min_thickness 0.25)
		(keepout
			(tracks not_allowed)
			(vias allowed)
			(pads allowed)
			(copperpour not_allowed)
			(footprints allowed)
		)
		(placement
			(enabled no)
			(sheetname "")
		)
		(fill yes
			(thermal_gap 0.5)
			(thermal_bridge_width 0.5)
			(island_removal_mode 0)
		)
		(polygon
			(pts
				(arc
					(start 33.026096 -299.335444)
					(mid 32.365696 -299.335444)
					(end 33.026096 -299.335444)
				)
			)
		)
	)
	(zone
		(layers "In1.Cu" "In2.Cu")
		(hatch none 0.5)
		(connect_pads
			(clearance 0)
		)
		(min_thickness 0.25)
		(keepout
			(tracks not_allowed)
			(vias allowed)
			(pads allowed)
			(copperpour not_allowed)
			(footprints allowed)
		)
		(placement
			(enabled no)
			(sheetname "")
		)
		(fill yes
			(thermal_gap 0.5)
			(thermal_bridge_width 0.5)
			(island_removal_mode 0)
		)
		(polygon
			(pts
				(arc
					(start 44.670218 -292.535356)
					(mid 44.009818 -292.535356)
					(end 44.670218 -292.535356)
				)
			)
		)
	)
	(zone
		(layers "In1.Cu" "In2.Cu")
		(hatch none 0.5)
		(connect_pads
			(clearance 0)
		)
		(min_thickness 0.25)
		(keepout
			(tracks not_allowed)
			(vias allowed)
			(pads allowed)
			(copperpour not_allowed)
			(footprints allowed)
		)
		(placement
			(enabled no)
			(sheetname "")
		)
		(fill yes
			(thermal_gap 0.5)
			(thermal_bridge_width 0.5)
			(island_removal_mode 0)
		)
		(polygon
			(pts
				(arc
					(start 177.832258 -45.55871)
					(mid 177.88614 -45.581028)
					(end 177.908458 -45.63491)
				)
				(arc
					(start 177.908458 -46.464982)
					(mid 177.88614 -46.518864)
					(end 177.832258 -46.541182)
				)
				(arc
					(start 176.384458 -46.541182)
					(mid 176.330576 -46.518864)
					(end 176.308258 -46.464982)
				)
				(arc
					(start 176.308258 -45.63491)
					(mid 176.330576 -45.581028)
					(end 176.384458 -45.55871)
				)
			)
		)
	)
	(zone
		(layers "In1.Cu" "In2.Cu")
		(hatch none 0.5)
		(connect_pads
			(clearance 0)
		)
		(min_thickness 0.25)
		(keepout
			(tracks not_allowed)
			(vias allowed)
			(pads allowed)
			(copperpour not_allowed)
			(footprints allowed)
		)
		(placement
			(enabled no)
			(sheetname "")
		)
		(fill yes
			(thermal_gap 0.5)
			(thermal_bridge_width 0.5)
			(island_removal_mode 0)
		)
		(polygon
			(pts
				(arc
					(start 17.938242 -216.885266)
					(mid 17.277842 -216.885266)
					(end 17.938242 -216.885266)
				)
			)
		)
	)
	(zone
		(layers "In1.Cu" "In2.Cu")
		(hatch none 0.5)
		(connect_pads
			(clearance 0)
		)
		(min_thickness 0.25)
		(keepout
			(tracks not_allowed)
			(vias allowed)
			(pads allowed)
			(copperpour not_allowed)
			(footprints allowed)
		)
		(placement
			(enabled no)
			(sheetname "")
		)
		(fill yes
			(thermal_gap 0.5)
			(thermal_bridge_width 0.5)
			(island_removal_mode 0)
		)
		(polygon
			(pts
				(arc
					(start 300.15434 -269.585186)
					(mid 299.49394 -269.585186)
					(end 300.15434 -269.585186)
				)
			)
		)
	)
	(zone
		(layers "In1.Cu" "In2.Cu")
		(hatch none 0.5)
		(connect_pads
			(clearance 0)
		)
		(min_thickness 0.25)
		(keepout
			(tracks not_allowed)
			(vias allowed)
			(pads allowed)
			(copperpour not_allowed)
			(footprints allowed)
		)
		(placement
			(enabled no)
			(sheetname "")
		)
		(fill yes
			(thermal_gap 0.5)
			(thermal_bridge_width 0.5)
			(island_removal_mode 0)
		)
		(polygon
			(pts
				(arc
					(start 427.786292 -297.635168)
					(mid 427.125892 -297.635168)
					(end 427.786292 -297.635168)
				)
			)
		)
	)
	(zone
		(layers "In1.Cu" "In2.Cu")
		(hatch none 0.5)
		(connect_pads
			(clearance 0)
		)
		(min_thickness 0.25)
		(keepout
			(tracks not_allowed)
			(vias allowed)
			(pads allowed)
			(copperpour not_allowed)
			(footprints allowed)
		)
		(placement
			(enabled no)
			(sheetname "")
		)
		(fill yes
			(thermal_gap 0.5)
			(thermal_bridge_width 0.5)
			(island_removal_mode 0)
		)
		(polygon
			(pts
				(arc
					(start 179.846224 -278.935434)
					(mid 179.185824 -278.935434)
					(end 179.846224 -278.935434)
				)
			)
		)
	)
	(zone
		(layers "In1.Cu" "In2.Cu")
		(hatch none 0.5)
		(connect_pads
			(clearance 0)
		)
		(min_thickness 0.25)
		(keepout
			(tracks not_allowed)
			(vias allowed)
			(pads allowed)
			(copperpour not_allowed)
			(footprints allowed)
		)
		(placement
			(enabled no)
			(sheetname "")
		)
		(fill yes
			(thermal_gap 0.5)
			(thermal_bridge_width 0.5)
			(island_removal_mode 0)
		)
		(polygon
			(pts
				(arc
					(start 427.786292 -199.885046)
					(mid 427.125892 -199.885046)
					(end 427.786292 -199.885046)
				)
			)
		)
	)
	(zone
		(layers "In1.Cu" "In2.Cu")
		(hatch none 0.5)
		(connect_pads
			(clearance 0)
		)
		(min_thickness 0.25)
		(keepout
			(tracks not_allowed)
			(vias allowed)
			(pads allowed)
			(copperpour not_allowed)
			(footprints allowed)
		)
		(placement
			(enabled no)
			(sheetname "")
		)
		(fill yes
			(thermal_gap 0.5)
			(thermal_bridge_width 0.5)
			(island_removal_mode 0)
		)
		(polygon
			(pts
				(arc
					(start 446.974468 -269.585186)
					(mid 446.314068 -269.585186)
					(end 446.974468 -269.585186)
				)
			)
		)
	)
	(zone
		(layers "In1.Cu" "In2.Cu")
		(hatch none 0.5)
		(connect_pads
			(clearance 0)
		)
		(min_thickness 0.25)
		(keepout
			(tracks not_allowed)
			(vias allowed)
			(pads allowed)
			(copperpour not_allowed)
			(footprints allowed)
		)
		(placement
			(enabled no)
			(sheetname "")
		)
		(fill yes
			(thermal_gap 0.5)
			(thermal_bridge_width 0.5)
			(island_removal_mode 0)
		)
		(polygon
			(pts
				(arc
					(start 280.966164 -213.484968)
					(mid 280.305764 -213.484968)
					(end 280.966164 -213.484968)
				)
			)
		)
	)
	(zone
		(layers "In1.Cu" "In2.Cu")
		(hatch none 0.5)
		(connect_pads
			(clearance 0)
		)
		(min_thickness 0.25)
		(keepout
			(tracks not_allowed)
			(vias allowed)
			(pads allowed)
			(copperpour not_allowed)
			(footprints allowed)
		)
		(placement
			(enabled no)
			(sheetname "")
		)
		(fill yes
			(thermal_gap 0.5)
			(thermal_bridge_width 0.5)
			(island_removal_mode 0)
		)
		(polygon
			(pts
				(arc
					(start 280.966164 -295.935146)
					(mid 280.305764 -295.935146)
					(end 280.966164 -295.935146)
				)
			)
		)
	)
	(zone
		(layers "In1.Cu" "In2.Cu")
		(hatch none 0.5)
		(connect_pads
			(clearance 0)
		)
		(min_thickness 0.25)
		(keepout
			(tracks not_allowed)
			(vias allowed)
			(pads allowed)
			(copperpour not_allowed)
			(footprints allowed)
		)
		(placement
			(enabled no)
			(sheetname "")
		)
		(fill yes
			(thermal_gap 0.5)
			(thermal_bridge_width 0.5)
			(island_removal_mode 0)
		)
		(polygon
			(pts
				(arc
					(start 420.242238 -218.585034)
					(mid 419.581838 -218.585034)
					(end 420.242238 -218.585034)
				)
			)
		)
	)
	(zone
		(layers "In1.Cu" "In2.Cu")
		(hatch none 0.5)
		(connect_pads
			(clearance 0)
		)
		(min_thickness 0.25)
		(keepout
			(tracks not_allowed)
			(vias allowed)
			(pads allowed)
			(copperpour not_allowed)
			(footprints allowed)
		)
		(placement
			(enabled no)
			(sheetname "")
		)
		(fill yes
			(thermal_gap 0.5)
			(thermal_bridge_width 0.5)
			(island_removal_mode 0)
		)
		(polygon
			(pts
				(arc
					(start 172.30217 -251.735336)
					(mid 171.64177 -251.735336)
					(end 172.30217 -251.735336)
				)
			)
		)
	)
	(zone
		(layers "In1.Cu" "In2.Cu")
		(hatch none 0.5)
		(connect_pads
			(clearance 0)
		)
		(min_thickness 0.25)
		(keepout
			(tracks not_allowed)
			(vias allowed)
			(pads allowed)
			(copperpour not_allowed)
			(footprints allowed)
		)
		(placement
			(enabled no)
			(sheetname "")
		)
		(fill yes
			(thermal_gap 0.5)
			(thermal_bridge_width 0.5)
			(island_removal_mode 0)
		)
		(polygon
			(pts
				(arc
					(start 296.054272 -238.985044)
					(mid 295.393872 -238.985044)
					(end 296.054272 -238.985044)
				)
			)
		)
	)
	(zone
		(layers "In1.Cu" "In2.Cu")
		(hatch none 0.5)
		(connect_pads
			(clearance 0)
		)
		(min_thickness 0.25)
		(keepout
			(tracks not_allowed)
			(vias allowed)
			(pads allowed)
			(copperpour not_allowed)
			(footprints allowed)
		)
		(placement
			(enabled no)
			(sheetname "")
		)
		(fill yes
			(thermal_gap 0.5)
			(thermal_bridge_width 0.5)
			(island_removal_mode 0)
		)
		(polygon
			(pts
				(arc
					(start 33.026096 -274.685252)
					(mid 32.365696 -274.685252)
					(end 33.026096 -274.685252)
				)
			)
		)
	)
	(zone
		(layers "In1.Cu" "In2.Cu")
		(hatch none 0.5)
		(connect_pads
			(clearance 0)
		)
		(min_thickness 0.25)
		(keepout
			(tracks not_allowed)
			(vias allowed)
			(pads allowed)
			(copperpour not_allowed)
			(footprints allowed)
		)
		(placement
			(enabled no)
			(sheetname "")
		)
		(fill yes
			(thermal_gap 0.5)
			(thermal_bridge_width 0.5)
			(island_removal_mode 0)
		)
		(polygon
			(pts
				(arc
					(start 187.390278 -246.63527)
					(mid 186.729878 -246.63527)
					(end 187.390278 -246.63527)
				)
			)
		)
	)
	(zone
		(layers "In1.Cu" "In2.Cu")
		(hatch none 0.5)
		(connect_pads
			(clearance 0)
		)
		(min_thickness 0.25)
		(keepout
			(tracks not_allowed)
			(vias allowed)
			(pads allowed)
			(copperpour not_allowed)
			(footprints allowed)
		)
		(placement
			(enabled no)
			(sheetname "")
		)
		(fill yes
			(thermal_gap 0.5)
			(thermal_bridge_width 0.5)
			(island_removal_mode 0)
		)
		(polygon
			(pts
				(arc
					(start 176.402238 -290.835334)
					(mid 175.741838 -290.835334)
					(end 176.402238 -290.835334)
				)
			)
		)
	)
	(zone
		(layers "In1.Cu" "In2.Cu")
		(hatch none 0.5)
		(connect_pads
			(clearance 0)
		)
		(min_thickness 0.25)
		(keepout
			(tracks not_allowed)
			(vias allowed)
			(pads allowed)
			(copperpour not_allowed)
			(footprints allowed)
		)
		(placement
			(enabled no)
			(sheetname "")
		)
		(fill yes
			(thermal_gap 0.5)
			(thermal_bridge_width 0.5)
			(island_removal_mode 0)
		)
		(polygon
			(pts
				(arc
					(start 343.398856 -417.242244)
					(mid 343.421174 -417.296126)
					(end 343.475056 -417.318444)
				)
				(arc
					(start 343.670636 -417.318444)
					(mid 343.692512 -417.315312)
					(end 343.712546 -417.305998)
				)
				(arc
					(start 344.00617 -417.113466)
					(mid 344.047826 -417.101064)
					(end 344.089482 -417.113466)
				)
				(arc
					(start 344.384376 -417.305998)
					(mid 344.4043 -417.315234)
					(end 344.426032 -417.318444)
				)
				(arc
					(start 344.620596 -417.318444)
					(mid 344.674478 -417.296126)
					(end 344.696796 -417.242244)
				)
				(arc
					(start 344.696796 -416.556444)
					(mid 344.674478 -416.502562)
					(end 344.620596 -416.480244)
				)
				(arc
					(start 344.426032 -416.480244)
					(mid 344.404288 -416.483412)
					(end 344.384376 -416.49269)
				)
				(arc
					(start 344.088212 -416.685476)
					(mid 344.046528 -416.697698)
					(end 344.0049 -416.685222)
				)
				(arc
					(start 343.711276 -416.49269)
					(mid 343.691352 -416.483454)
					(end 343.66962 -416.480244)
				)
				(arc
					(start 343.475056 -416.480244)
					(mid 343.421174 -416.502562)
					(end 343.398856 -416.556444)
				)
			)
		)
	)
	(zone
		(layers "In1.Cu" "In2.Cu")
		(hatch none 0.5)
		(connect_pads
			(clearance 0)
		)
		(min_thickness 0.25)
		(keepout
			(tracks not_allowed)
			(vias allowed)
			(pads allowed)
			(copperpour not_allowed)
			(footprints allowed)
		)
		(placement
			(enabled no)
			(sheetname "")
		)
		(fill yes
			(thermal_gap 0.5)
			(thermal_bridge_width 0.5)
			(island_removal_mode 0)
		)
		(polygon
			(pts
				(arc
					(start 145.112994 -370.978684)
					(mid 145.132918 -370.98792)
					(end 145.15465 -370.99113)
				)
				(arc
					(start 145.349214 -370.99113)
					(mid 145.403096 -370.968812)
					(end 145.425414 -370.91493)
				)
				(arc
					(start 145.425414 -370.22913)
					(mid 145.403096 -370.175248)
					(end 145.349214 -370.15293)
				)
				(arc
					(start 145.15465 -370.15293)
					(mid 145.132906 -370.156098)
					(end 145.112994 -370.165376)
				)
				(arc
					(start 144.81683 -370.358162)
					(mid 144.775146 -370.370384)
					(end 144.733518 -370.357908)
				)
				(arc
					(start 144.439894 -370.165376)
					(mid 144.41997 -370.15614)
					(end 144.398238 -370.15293)
				)
				(arc
					(start 144.203674 -370.15293)
					(mid 144.149792 -370.175248)
					(end 144.127474 -370.22913)
				)
				(arc
					(start 144.127474 -370.91493)
					(mid 144.149792 -370.968812)
					(end 144.203674 -370.99113)
				)
				(arc
					(start 144.399508 -370.99113)
					(mid 144.421252 -370.987962)
					(end 144.441164 -370.978684)
				)
				(arc
					(start 144.734788 -370.786152)
					(mid 144.776444 -370.77375)
					(end 144.8181 -370.786152)
				)
			)
		)
	)
	(zone
		(layers "In1.Cu" "In2.Cu")
		(hatch none 0.5)
		(connect_pads
			(clearance 0)
		)
		(min_thickness 0.25)
		(keepout
			(tracks not_allowed)
			(vias allowed)
			(pads allowed)
			(copperpour not_allowed)
			(footprints allowed)
		)
		(placement
			(enabled no)
			(sheetname "")
		)
		(fill yes
			(thermal_gap 0.5)
			(thermal_bridge_width 0.5)
			(island_removal_mode 0)
		)
		(polygon
			(pts
				(arc
					(start 420.242238 -313.784996)
					(mid 419.581838 -313.784996)
					(end 420.242238 -313.784996)
				)
			)
		)
	)
	(zone
		(layers "In1.Cu" "In2.Cu")
		(hatch none 0.5)
		(connect_pads
			(clearance 0)
		)
		(min_thickness 0.25)
		(keepout
			(tracks not_allowed)
			(vias allowed)
			(pads allowed)
			(copperpour not_allowed)
			(footprints allowed)
		)
		(placement
			(enabled no)
			(sheetname "")
		)
		(fill yes
			(thermal_gap 0.5)
			(thermal_bridge_width 0.5)
			(island_removal_mode 0)
		)
		(polygon
			(pts
				(arc
					(start 420.242238 -306.985162)
					(mid 419.581838 -306.985162)
					(end 420.242238 -306.985162)
				)
			)
		)
	)
	(zone
		(layers "In1.Cu" "In2.Cu")
		(hatch none 0.5)
		(connect_pads
			(clearance 0)
		)
		(min_thickness 0.25)
		(keepout
			(tracks not_allowed)
			(vias allowed)
			(pads allowed)
			(copperpour not_allowed)
			(footprints allowed)
		)
		(placement
			(enabled no)
			(sheetname "")
		)
		(fill yes
			(thermal_gap 0.5)
			(thermal_bridge_width 0.5)
			(island_removal_mode 0)
		)
		(polygon
			(pts
				(arc
					(start 179.846224 -268.735302)
					(mid 179.185824 -268.735302)
					(end 179.846224 -268.735302)
				)
			)
		)
	)
	(zone
		(layers "In1.Cu" "In2.Cu")
		(hatch none 0.5)
		(connect_pads
			(clearance 0)
		)
		(min_thickness 0.25)
		(keepout
			(tracks not_allowed)
			(vias allowed)
			(pads allowed)
			(copperpour not_allowed)
			(footprints allowed)
		)
		(placement
			(enabled no)
			(sheetname "")
		)
		(fill yes
			(thermal_gap 0.5)
			(thermal_bridge_width 0.5)
			(island_removal_mode 0)
		)
		(polygon
			(pts
				(arc
					(start 37.126164 -208.38541)
					(mid 36.465764 -208.38541)
					(end 37.126164 -208.38541)
				)
			)
		)
	)
	(zone
		(layers "In1.Cu" "In2.Cu")
		(hatch none 0.5)
		(connect_pads
			(clearance 0)
		)
		(min_thickness 0.25)
		(keepout
			(tracks not_allowed)
			(vias allowed)
			(pads allowed)
			(copperpour not_allowed)
			(footprints allowed)
		)
		(placement
			(enabled no)
			(sheetname "")
		)
		(fill yes
			(thermal_gap 0.5)
			(thermal_bridge_width 0.5)
			(island_removal_mode 0)
		)
		(polygon
			(pts
				(arc
					(start 78.209394 -408.860244)
					(mid 78.231712 -408.914126)
					(end 78.285594 -408.936444)
				)
				(arc
					(start 78.481174 -408.936444)
					(mid 78.50305 -408.933312)
					(end 78.523084 -408.923998)
				)
				(arc
					(start 78.816708 -408.731466)
					(mid 78.858364 -408.719064)
					(end 78.90002 -408.731466)
				)
				(arc
					(start 79.194914 -408.923998)
					(mid 79.214838 -408.933234)
					(end 79.23657 -408.936444)
				)
				(arc
					(start 79.431134 -408.936444)
					(mid 79.485016 -408.914126)
					(end 79.507334 -408.860244)
				)
				(arc
					(start 79.507334 -408.174444)
					(mid 79.485016 -408.120562)
					(end 79.431134 -408.098244)
				)
				(arc
					(start 79.23657 -408.098244)
					(mid 79.214826 -408.101412)
					(end 79.194914 -408.11069)
				)
				(arc
					(start 78.89875 -408.303476)
					(mid 78.857066 -408.315698)
					(end 78.815438 -408.303222)
				)
				(arc
					(start 78.521814 -408.11069)
					(mid 78.50189 -408.101454)
					(end 78.480158 -408.098244)
				)
				(arc
					(start 78.285594 -408.098244)
					(mid 78.231712 -408.120562)
					(end 78.209394 -408.174444)
				)
			)
		)
	)
	(zone
		(layers "In1.Cu" "In2.Cu")
		(hatch none 0.5)
		(connect_pads
			(clearance 0)
		)
		(min_thickness 0.25)
		(keepout
			(tracks not_allowed)
			(vias allowed)
			(pads allowed)
			(copperpour not_allowed)
			(footprints allowed)
		)
		(placement
			(enabled no)
			(sheetname "")
		)
		(fill yes
			(thermal_gap 0.5)
			(thermal_bridge_width 0.5)
			(island_removal_mode 0)
		)
		(polygon
			(pts
				(arc
					(start 17.938242 -248.335292)
					(mid 17.277842 -248.335292)
					(end 17.938242 -248.335292)
				)
			)
		)
	)
	(zone
		(layers "In1.Cu" "In2.Cu")
		(hatch none 0.5)
		(connect_pads
			(clearance 0)
		)
		(min_thickness 0.25)
		(keepout
			(tracks not_allowed)
			(vias allowed)
			(pads allowed)
			(copperpour not_allowed)
			(footprints allowed)
		)
		(placement
			(enabled no)
			(sheetname "")
		)
		(fill yes
			(thermal_gap 0.5)
			(thermal_bridge_width 0.5)
			(island_removal_mode 0)
		)
		(polygon
			(pts
				(arc
					(start 315.829696 -417.242244)
					(mid 315.852014 -417.296126)
					(end 315.905896 -417.318444)
				)
				(arc
					(start 316.101476 -417.318444)
					(mid 316.123352 -417.315312)
					(end 316.143386 -417.305998)
				)
				(arc
					(start 316.43701 -417.113466)
					(mid 316.478666 -417.101064)
					(end 316.520322 -417.113466)
				)
				(arc
					(start 316.815216 -417.305998)
					(mid 316.83514 -417.315234)
					(end 316.856872 -417.318444)
				)
				(arc
					(start 317.051436 -417.318444)
					(mid 317.105318 -417.296126)
					(end 317.127636 -417.242244)
				)
				(arc
					(start 317.127636 -416.556444)
					(mid 317.105318 -416.502562)
					(end 317.051436 -416.480244)
				)
				(arc
					(start 316.856872 -416.480244)
					(mid 316.835128 -416.483412)
					(end 316.815216 -416.49269)
				)
				(arc
					(start 316.519052 -416.685476)
					(mid 316.477368 -416.697698)
					(end 316.43574 -416.685222)
				)
				(arc
					(start 316.142116 -416.49269)
					(mid 316.122192 -416.483454)
					(end 316.10046 -416.480244)
				)
				(arc
					(start 315.905896 -416.480244)
					(mid 315.852014 -416.502562)
					(end 315.829696 -416.556444)
				)
			)
		)
	)
	(zone
		(layers "In1.Cu" "In2.Cu")
		(hatch none 0.5)
		(connect_pads
			(clearance 0)
		)
		(min_thickness 0.25)
		(keepout
			(tracks not_allowed)
			(vias allowed)
			(pads allowed)
			(copperpour not_allowed)
			(footprints allowed)
		)
		(placement
			(enabled no)
			(sheetname "")
		)
		(fill yes
			(thermal_gap 0.5)
			(thermal_bridge_width 0.5)
			(island_removal_mode 0)
		)
		(polygon
			(pts
				(arc
					(start 52.214272 -287.43529)
					(mid 51.553872 -287.43529)
					(end 52.214272 -287.43529)
				)
			)
		)
	)
	(zone
		(layers "In1.Cu" "In2.Cu")
		(hatch none 0.5)
		(connect_pads
			(clearance 0)
		)
		(min_thickness 0.25)
		(keepout
			(tracks not_allowed)
			(vias allowed)
			(pads allowed)
			(copperpour not_allowed)
			(footprints allowed)
		)
		(placement
			(enabled no)
			(sheetname "")
		)
		(fill yes
			(thermal_gap 0.5)
			(thermal_bridge_width 0.5)
			(island_removal_mode 0)
		)
		(polygon
			(pts
				(arc
					(start 300.15434 -275.535136)
					(mid 299.49394 -275.535136)
					(end 300.15434 -275.535136)
				)
			)
		)
	)
	(zone
		(layers "In1.Cu" "In2.Cu")
		(hatch none 0.5)
		(connect_pads
			(clearance 0)
		)
		(min_thickness 0.25)
		(keepout
			(tracks not_allowed)
			(vias allowed)
			(pads allowed)
			(copperpour not_allowed)
			(footprints allowed)
		)
		(placement
			(enabled no)
			(sheetname "")
		)
		(fill yes
			(thermal_gap 0.5)
			(thermal_bridge_width 0.5)
			(island_removal_mode 0)
		)
		(polygon
			(pts
				(arc
					(start 52.214272 -298.485306)
					(mid 51.553872 -298.485306)
					(end 52.214272 -298.485306)
				)
			)
		)
	)
	(zone
		(layers "In1.Cu" "In2.Cu")
		(hatch none 0.5)
		(connect_pads
			(clearance 0)
		)
		(min_thickness 0.25)
		(keepout
			(tracks not_allowed)
			(vias allowed)
			(pads allowed)
			(copperpour not_allowed)
			(footprints allowed)
		)
		(placement
			(enabled no)
			(sheetname "")
		)
		(fill yes
			(thermal_gap 0.5)
			(thermal_bridge_width 0.5)
			(island_removal_mode 0)
		)
		(polygon
			(pts
				(arc
					(start 450.4182 -216.885012)
					(mid 449.7578 -216.885012)
					(end 450.4182 -216.885012)
				)
			)
		)
	)
	(zone
		(layers "In1.Cu" "In2.Cu")
		(hatch none 0.5)
		(connect_pads
			(clearance 0)
		)
		(min_thickness 0.25)
		(keepout
			(tracks not_allowed)
			(vias allowed)
			(pads allowed)
			(copperpour not_allowed)
			(footprints allowed)
		)
		(placement
			(enabled no)
			(sheetname "")
		)
		(fill yes
			(thermal_gap 0.5)
			(thermal_bridge_width 0.5)
			(island_removal_mode 0)
		)
		(polygon
			(pts
				(arc
					(start 280.966164 -207.535018)
					(mid 280.305764 -207.535018)
					(end 280.966164 -207.535018)
				)
			)
		)
	)
	(zone
		(layers "In1.Cu" "In2.Cu")
		(hatch none 0.5)
		(connect_pads
			(clearance 0)
		)
		(min_thickness 0.25)
		(keepout
			(tracks not_allowed)
			(vias allowed)
			(pads allowed)
			(copperpour not_allowed)
			(footprints allowed)
		)
		(placement
			(enabled no)
			(sheetname "")
		)
		(fill yes
			(thermal_gap 0.5)
			(thermal_bridge_width 0.5)
			(island_removal_mode 0)
		)
		(polygon
			(pts
				(arc
					(start 439.430414 -317.18504)
					(mid 438.770014 -317.18504)
					(end 439.430414 -317.18504)
				)
			)
		)
	)
	(zone
		(layers "In1.Cu" "In2.Cu")
		(hatch none 0.5)
		(connect_pads
			(clearance 0)
		)
		(min_thickness 0.25)
		(keepout
			(tracks not_allowed)
			(vias allowed)
			(pads allowed)
			(copperpour not_allowed)
			(footprints allowed)
		)
		(placement
			(enabled no)
			(sheetname "")
		)
		(fill yes
			(thermal_gap 0.5)
			(thermal_bridge_width 0.5)
			(island_removal_mode 0)
		)
		(polygon
			(pts
				(arc
					(start 191.490346 -264.485374)
					(mid 190.829946 -264.485374)
					(end 191.490346 -264.485374)
				)
			)
		)
	)
	(zone
		(layers "In1.Cu" "In2.Cu")
		(hatch none 0.5)
		(connect_pads
			(clearance 0)
		)
		(min_thickness 0.25)
		(keepout
			(tracks not_allowed)
			(vias allowed)
			(pads allowed)
			(copperpour not_allowed)
			(footprints allowed)
		)
		(placement
			(enabled no)
			(sheetname "")
		)
		(fill yes
			(thermal_gap 0.5)
			(thermal_bridge_width 0.5)
			(island_removal_mode 0)
		)
		(polygon
			(pts
				(arc
					(start 424.342306 -220.285056)
					(mid 423.681906 -220.285056)
					(end 424.342306 -220.285056)
				)
			)
		)
	)
	(zone
		(layers "In1.Cu" "In2.Cu")
		(hatch none 0.5)
		(connect_pads
			(clearance 0)
		)
		(min_thickness 0.25)
		(keepout
			(tracks not_allowed)
			(vias allowed)
			(pads allowed)
			(copperpour not_allowed)
			(footprints allowed)
		)
		(placement
			(enabled no)
			(sheetname "")
		)
		(fill yes
			(thermal_gap 0.5)
			(thermal_bridge_width 0.5)
			(island_removal_mode 0)
		)
		(polygon
			(pts
				(arc
					(start 431.88636 -278.085042)
					(mid 431.22596 -278.085042)
					(end 431.88636 -278.085042)
				)
			)
		)
	)
	(zone
		(layers "In1.Cu" "In2.Cu")
		(hatch none 0.5)
		(connect_pads
			(clearance 0)
		)
		(min_thickness 0.25)
		(keepout
			(tracks not_allowed)
			(vias allowed)
			(pads allowed)
			(copperpour not_allowed)
			(footprints allowed)
		)
		(placement
			(enabled no)
			(sheetname "")
		)
		(fill yes
			(thermal_gap 0.5)
			(thermal_bridge_width 0.5)
			(island_removal_mode 0)
		)
		(polygon
			(pts
				(arc
					(start 420.242238 -261.93496)
					(mid 419.581838 -261.93496)
					(end 420.242238 -261.93496)
				)
			)
		)
	)
	(zone
		(layers "In1.Cu" "In2.Cu")
		(hatch none 0.5)
		(connect_pads
			(clearance 0)
		)
		(min_thickness 0.25)
		(keepout
			(tracks not_allowed)
			(vias allowed)
			(pads allowed)
			(copperpour not_allowed)
			(footprints allowed)
		)
		(placement
			(enabled no)
			(sheetname "")
		)
		(fill yes
			(thermal_gap 0.5)
			(thermal_bridge_width 0.5)
			(island_removal_mode 0)
		)
		(polygon
			(pts
				(arc
					(start 17.938242 -284.035246)
					(mid 17.277842 -284.035246)
					(end 17.938242 -284.035246)
				)
			)
		)
	)
	(zone
		(layers "In1.Cu" "In2.Cu")
		(hatch none 0.5)
		(connect_pads
			(clearance 0)
		)
		(min_thickness 0.25)
		(keepout
			(tracks not_allowed)
			(vias allowed)
			(pads allowed)
			(copperpour not_allowed)
			(footprints allowed)
		)
		(placement
			(enabled no)
			(sheetname "")
		)
		(fill yes
			(thermal_gap 0.5)
			(thermal_bridge_width 0.5)
			(island_removal_mode 0)
		)
		(polygon
			(pts
				(arc
					(start 25.482296 -305.285394)
					(mid 24.821896 -305.285394)
					(end 25.482296 -305.285394)
				)
			)
		)
	)
	(zone
		(layers "In1.Cu" "In2.Cu")
		(hatch none 0.5)
		(connect_pads
			(clearance 0)
		)
		(min_thickness 0.25)
		(keepout
			(tracks not_allowed)
			(vias allowed)
			(pads allowed)
			(copperpour not_allowed)
			(footprints allowed)
		)
		(placement
			(enabled no)
			(sheetname "")
		)
		(fill yes
			(thermal_gap 0.5)
			(thermal_bridge_width 0.5)
			(island_removal_mode 0)
		)
		(polygon
			(pts
				(arc
					(start 296.054272 -233.884978)
					(mid 295.393872 -233.884978)
					(end 296.054272 -233.884978)
				)
			)
		)
	)
	(zone
		(layers "In1.Cu" "In2.Cu")
		(hatch none 0.5)
		(connect_pads
			(clearance 0)
		)
		(min_thickness 0.25)
		(keepout
			(tracks not_allowed)
			(vias allowed)
			(pads allowed)
			(copperpour not_allowed)
			(footprints allowed)
		)
		(placement
			(enabled no)
			(sheetname "")
		)
		(fill yes
			(thermal_gap 0.5)
			(thermal_bridge_width 0.5)
			(island_removal_mode 0)
		)
		(polygon
			(pts
				(arc
					(start 17.938242 -306.985416)
					(mid 17.277842 -306.985416)
					(end 17.938242 -306.985416)
				)
			)
		)
	)
	(zone
		(layers "In1.Cu" "In2.Cu")
		(hatch none 0.5)
		(connect_pads
			(clearance 0)
		)
		(min_thickness 0.25)
		(keepout
			(tracks not_allowed)
			(vias allowed)
			(pads allowed)
			(copperpour not_allowed)
			(footprints allowed)
		)
		(placement
			(enabled no)
			(sheetname "")
		)
		(fill yes
			(thermal_gap 0.5)
			(thermal_bridge_width 0.5)
			(island_removal_mode 0)
		)
		(polygon
			(pts
				(arc
					(start 191.490346 -289.135312)
					(mid 190.829946 -289.135312)
					(end 191.490346 -289.135312)
				)
			)
		)
	)
	(zone
		(layers "In1.Cu" "In2.Cu")
		(hatch none 0.5)
		(connect_pads
			(clearance 0)
		)
		(min_thickness 0.25)
		(keepout
			(tracks not_allowed)
			(vias allowed)
			(pads allowed)
			(copperpour not_allowed)
			(footprints allowed)
		)
		(placement
			(enabled no)
			(sheetname "")
		)
		(fill yes
			(thermal_gap 0.5)
			(thermal_bridge_width 0.5)
			(island_removal_mode 0)
		)
		(polygon
			(pts
				(arc
					(start 424.342306 -208.385156)
					(mid 423.681906 -208.385156)
					(end 424.342306 -208.385156)
				)
			)
		)
	)
	(zone
		(layers "In1.Cu" "In2.Cu")
		(hatch none 0.5)
		(connect_pads
			(clearance 0)
		)
		(min_thickness 0.25)
		(keepout
			(tracks not_allowed)
			(vias allowed)
			(pads allowed)
			(copperpour not_allowed)
			(footprints allowed)
		)
		(placement
			(enabled no)
			(sheetname "")
		)
		(fill yes
			(thermal_gap 0.5)
			(thermal_bridge_width 0.5)
			(island_removal_mode 0)
		)
		(polygon
			(pts
				(arc
					(start 431.88636 -296.78503)
					(mid 431.22596 -296.78503)
					(end 431.88636 -296.78503)
				)
			)
		)
	)
	(zone
		(layers "In1.Cu" "In2.Cu")
		(hatch none 0.5)
		(connect_pads
			(clearance 0)
		)
		(min_thickness 0.25)
		(keepout
			(tracks not_allowed)
			(vias allowed)
			(pads allowed)
			(copperpour not_allowed)
			(footprints allowed)
		)
		(placement
			(enabled no)
			(sheetname "")
		)
		(fill yes
			(thermal_gap 0.5)
			(thermal_bridge_width 0.5)
			(island_removal_mode 0)
		)
		(polygon
			(pts
				(arc
					(start 285.066232 -233.035094)
					(mid 284.405832 -233.035094)
					(end 285.066232 -233.035094)
				)
			)
		)
	)
	(zone
		(layers "In1.Cu" "In2.Cu")
		(hatch none 0.5)
		(connect_pads
			(clearance 0)
		)
		(min_thickness 0.25)
		(keepout
			(tracks not_allowed)
			(vias allowed)
			(pads allowed)
			(copperpour not_allowed)
			(footprints allowed)
		)
		(placement
			(enabled no)
			(sheetname "")
		)
		(fill yes
			(thermal_gap 0.5)
			(thermal_bridge_width 0.5)
			(island_removal_mode 0)
		)
		(polygon
			(pts
				(arc
					(start 300.15434 -311.23509)
					(mid 299.49394 -311.23509)
					(end 300.15434 -311.23509)
				)
			)
		)
	)
	(zone
		(layers "In1.Cu" "In2.Cu")
		(hatch none 0.5)
		(connect_pads
			(clearance 0)
		)
		(min_thickness 0.25)
		(keepout
			(tracks not_allowed)
			(vias allowed)
			(pads allowed)
			(copperpour not_allowed)
			(footprints allowed)
		)
		(placement
			(enabled no)
			(sheetname "")
		)
		(fill yes
			(thermal_gap 0.5)
			(thermal_bridge_width 0.5)
			(island_removal_mode 0)
		)
		(polygon
			(pts
				(arc
					(start 202.478132 -316.33541)
					(mid 201.817732 -316.33541)
					(end 202.478132 -316.33541)
				)
			)
		)
	)
	(zone
		(layers "In1.Cu" "In2.Cu")
		(hatch none 0.5)
		(connect_pads
			(clearance 0)
		)
		(min_thickness 0.25)
		(keepout
			(tracks not_allowed)
			(vias allowed)
			(pads allowed)
			(copperpour not_allowed)
			(footprints allowed)
		)
		(placement
			(enabled no)
			(sheetname "")
		)
		(fill yes
			(thermal_gap 0.5)
			(thermal_bridge_width 0.5)
			(island_removal_mode 0)
		)
		(polygon
			(pts
				(arc
					(start 187.390278 -227.935282)
					(mid 186.729878 -227.935282)
					(end 187.390278 -227.935282)
				)
			)
		)
	)
	(zone
		(layers "In1.Cu" "In2.Cu")
		(hatch none 0.5)
		(connect_pads
			(clearance 0)
		)
		(min_thickness 0.25)
		(keepout
			(tracks not_allowed)
			(vias allowed)
			(pads allowed)
			(copperpour not_allowed)
			(footprints allowed)
		)
		(placement
			(enabled no)
			(sheetname "")
		)
		(fill yes
			(thermal_gap 0.5)
			(thermal_bridge_width 0.5)
			(island_removal_mode 0)
		)
		(polygon
			(pts
				(arc
					(start 183.946292 -266.185396)
					(mid 183.285892 -266.185396)
					(end 183.946292 -266.185396)
				)
			)
		)
	)
	(zone
		(layers "In1.Cu" "In2.Cu")
		(hatch none 0.5)
		(connect_pads
			(clearance 0)
		)
		(min_thickness 0.25)
		(keepout
			(tracks not_allowed)
			(vias allowed)
			(pads allowed)
			(copperpour not_allowed)
			(footprints allowed)
		)
		(placement
			(enabled no)
			(sheetname "")
		)
		(fill yes
			(thermal_gap 0.5)
			(thermal_bridge_width 0.5)
			(island_removal_mode 0)
		)
		(polygon
			(pts
				(arc
					(start 191.490346 -240.68532)
					(mid 190.829946 -240.68532)
					(end 191.490346 -240.68532)
				)
			)
		)
	)
	(zone
		(layers "In1.Cu" "In2.Cu")
		(hatch none 0.5)
		(connect_pads
			(clearance 0)
		)
		(min_thickness 0.25)
		(keepout
			(tracks not_allowed)
			(vias allowed)
			(pads allowed)
			(copperpour not_allowed)
			(footprints allowed)
		)
		(placement
			(enabled no)
			(sheetname "")
		)
		(fill yes
			(thermal_gap 0.5)
			(thermal_bridge_width 0.5)
			(island_removal_mode 0)
		)
		(polygon
			(pts
				(arc
					(start 33.026096 -277.235412)
					(mid 32.365696 -277.235412)
					(end 33.026096 -277.235412)
				)
			)
		)
	)
	(zone
		(layers "In1.Cu" "In2.Cu")
		(hatch none 0.5)
		(connect_pads
			(clearance 0)
		)
		(min_thickness 0.25)
		(keepout
			(tracks not_allowed)
			(vias allowed)
			(pads allowed)
			(copperpour not_allowed)
			(footprints allowed)
		)
		(placement
			(enabled no)
			(sheetname "")
		)
		(fill yes
			(thermal_gap 0.5)
			(thermal_bridge_width 0.5)
			(island_removal_mode 0)
		)
		(polygon
			(pts
				(arc
					(start 22.03831 -295.085262)
					(mid 21.37791 -295.085262)
					(end 22.03831 -295.085262)
				)
			)
		)
	)
	(zone
		(layers "In1.Cu" "In2.Cu")
		(hatch none 0.5)
		(connect_pads
			(clearance 0)
		)
		(min_thickness 0.25)
		(keepout
			(tracks not_allowed)
			(vias allowed)
			(pads allowed)
			(copperpour not_allowed)
			(footprints allowed)
		)
		(placement
			(enabled no)
			(sheetname "")
		)
		(fill yes
			(thermal_gap 0.5)
			(thermal_bridge_width 0.5)
			(island_removal_mode 0)
		)
		(polygon
			(pts
				(arc
					(start 292.610286 -292.535102)
					(mid 291.949886 -292.535102)
					(end 292.610286 -292.535102)
				)
			)
		)
	)
	(zone
		(layers "In1.Cu" "In2.Cu")
		(hatch none 0.5)
		(connect_pads
			(clearance 0)
		)
		(min_thickness 0.25)
		(keepout
			(tracks not_allowed)
			(vias allowed)
			(pads allowed)
			(copperpour not_allowed)
			(footprints allowed)
		)
		(placement
			(enabled no)
			(sheetname "")
		)
		(fill yes
			(thermal_gap 0.5)
			(thermal_bridge_width 0.5)
			(island_removal_mode 0)
		)
		(polygon
			(pts
				(arc
					(start 33.026096 -213.485222)
					(mid 32.365696 -213.485222)
					(end 33.026096 -213.485222)
				)
			)
		)
	)
	(zone
		(layers "In1.Cu" "In2.Cu")
		(hatch none 0.5)
		(connect_pads
			(clearance 0)
		)
		(min_thickness 0.25)
		(keepout
			(tracks not_allowed)
			(vias allowed)
			(pads allowed)
			(copperpour not_allowed)
			(footprints allowed)
		)
		(placement
			(enabled no)
			(sheetname "")
		)
		(fill yes
			(thermal_gap 0.5)
			(thermal_bridge_width 0.5)
			(island_removal_mode 0)
		)
		(polygon
			(pts
				(arc
					(start 296.054272 -222.834962)
					(mid 295.393872 -222.834962)
					(end 296.054272 -222.834962)
				)
			)
		)
	)
	(zone
		(layers "In1.Cu" "In2.Cu")
		(hatch none 0.5)
		(connect_pads
			(clearance 0)
		)
		(min_thickness 0.25)
		(keepout
			(tracks not_allowed)
			(vias allowed)
			(pads allowed)
			(copperpour not_allowed)
			(footprints allowed)
		)
		(placement
			(enabled no)
			(sheetname "")
		)
		(fill yes
			(thermal_gap 0.5)
			(thermal_bridge_width 0.5)
			(island_removal_mode 0)
		)
		(polygon
			(pts
				(arc
					(start 424.342306 -266.185142)
					(mid 423.681906 -266.185142)
					(end 424.342306 -266.185142)
				)
			)
		)
	)
	(zone
		(layers "In1.Cu" "In2.Cu")
		(hatch none 0.5)
		(connect_pads
			(clearance 0)
		)
		(min_thickness 0.25)
		(keepout
			(tracks not_allowed)
			(vias allowed)
			(pads allowed)
			(copperpour not_allowed)
			(footprints allowed)
		)
		(placement
			(enabled no)
			(sheetname "")
		)
		(fill yes
			(thermal_gap 0.5)
			(thermal_bridge_width 0.5)
			(island_removal_mode 0)
		)
		(polygon
			(pts
				(arc
					(start 52.214272 -276.385274)
					(mid 51.553872 -276.385274)
					(end 52.214272 -276.385274)
				)
			)
		)
	)
	(zone
		(layers "In1.Cu" "In2.Cu")
		(hatch none 0.5)
		(connect_pads
			(clearance 0)
		)
		(min_thickness 0.25)
		(keepout
			(tracks not_allowed)
			(vias allowed)
			(pads allowed)
			(copperpour not_allowed)
			(footprints allowed)
		)
		(placement
			(enabled no)
			(sheetname "")
		)
		(fill yes
			(thermal_gap 0.5)
			(thermal_bridge_width 0.5)
			(island_removal_mode 0)
		)
		(polygon
			(pts
				(arc
					(start 25.482296 -263.635236)
					(mid 24.821896 -263.635236)
					(end 25.482296 -263.635236)
				)
			)
		)
	)
	(zone
		(layers "In1.Cu" "In2.Cu")
		(hatch none 0.5)
		(connect_pads
			(clearance 0)
		)
		(min_thickness 0.25)
		(keepout
			(tracks not_allowed)
			(vias allowed)
			(pads allowed)
			(copperpour not_allowed)
			(footprints allowed)
		)
		(placement
			(enabled no)
			(sheetname "")
		)
		(fill yes
			(thermal_gap 0.5)
			(thermal_bridge_width 0.5)
			(island_removal_mode 0)
		)
		(polygon
			(pts
				(arc
					(start 424.342306 -201.585068)
					(mid 423.681906 -201.585068)
					(end 424.342306 -201.585068)
				)
			)
		)
	)
	(zone
		(layers "In1.Cu" "In2.Cu")
		(hatch none 0.5)
		(connect_pads
			(clearance 0)
		)
		(min_thickness 0.25)
		(keepout
			(tracks not_allowed)
			(vias allowed)
			(pads allowed)
			(copperpour not_allowed)
			(footprints allowed)
		)
		(placement
			(enabled no)
			(sheetname "")
		)
		(fill yes
			(thermal_gap 0.5)
			(thermal_bridge_width 0.5)
			(island_removal_mode 0)
		)
		(polygon
			(pts
				(arc
					(start 269.978378 -242.385088)
					(mid 269.317978 -242.385088)
					(end 269.978378 -242.385088)
				)
			)
		)
	)
	(zone
		(layers "In1.Cu" "In2.Cu")
		(hatch none 0.5)
		(connect_pads
			(clearance 0)
		)
		(min_thickness 0.25)
		(keepout
			(tracks not_allowed)
			(vias allowed)
			(pads allowed)
			(copperpour not_allowed)
			(footprints allowed)
		)
		(placement
			(enabled no)
			(sheetname "")
		)
		(fill yes
			(thermal_gap 0.5)
			(thermal_bridge_width 0.5)
			(island_removal_mode 0)
		)
		(polygon
			(pts
				(arc
					(start 300.15434 -231.335072)
					(mid 299.49394 -231.335072)
					(end 300.15434 -231.335072)
				)
			)
		)
	)
	(zone
		(layers "In1.Cu" "In2.Cu")
		(hatch none 0.5)
		(connect_pads
			(clearance 0)
		)
		(min_thickness 0.25)
		(keepout
			(tracks not_allowed)
			(vias allowed)
			(pads allowed)
			(copperpour not_allowed)
			(footprints allowed)
		)
		(placement
			(enabled no)
			(sheetname "")
		)
		(fill yes
			(thermal_gap 0.5)
			(thermal_bridge_width 0.5)
			(island_removal_mode 0)
		)
		(polygon
			(pts
				(arc
					(start 288.510218 -278.93518)
					(mid 287.849818 -278.93518)
					(end 288.510218 -278.93518)
				)
			)
		)
	)
	(zone
		(layers "In1.Cu" "In2.Cu")
		(hatch none 0.5)
		(connect_pads
			(clearance 0)
		)
		(min_thickness 0.25)
		(keepout
			(tracks not_allowed)
			(vias allowed)
			(pads allowed)
			(copperpour not_allowed)
			(footprints allowed)
		)
		(placement
			(enabled no)
			(sheetname "")
		)
		(fill yes
			(thermal_gap 0.5)
			(thermal_bridge_width 0.5)
			(island_removal_mode 0)
		)
		(polygon
			(pts
				(arc
					(start 426.47743 -17.967198)
					(mid 426.499748 -18.02108)
					(end 426.55363 -18.043398)
				)
				(arc
					(start 426.74921 -18.043398)
					(mid 426.771086 -18.040266)
					(end 426.79112 -18.030952)
				)
				(arc
					(start 427.084744 -17.83842)
					(mid 427.1264 -17.826018)
					(end 427.168056 -17.83842)
				)
				(arc
					(start 427.46295 -18.030952)
					(mid 427.482874 -18.040188)
					(end 427.504606 -18.043398)
				)
				(arc
					(start 427.69917 -18.043398)
					(mid 427.753052 -18.02108)
					(end 427.77537 -17.967198)
				)
				(arc
					(start 427.77537 -17.281398)
					(mid 427.753052 -17.227516)
					(end 427.69917 -17.205198)
				)
				(arc
					(start 427.504606 -17.205198)
					(mid 427.482862 -17.208366)
					(end 427.46295 -17.217644)
				)
				(arc
					(start 427.166786 -17.41043)
					(mid 427.125102 -17.422652)
					(end 427.083474 -17.410176)
				)
				(arc
					(start 426.78985 -17.217644)
					(mid 426.769926 -17.208408)
					(end 426.748194 -17.205198)
				)
				(arc
					(start 426.55363 -17.205198)
					(mid 426.499748 -17.227516)
					(end 426.47743 -17.281398)
				)
			)
		)
	)
	(zone
		(layers "In1.Cu" "In2.Cu")
		(hatch none 0.5)
		(connect_pads
			(clearance 0)
		)
		(min_thickness 0.25)
		(keepout
			(tracks not_allowed)
			(vias allowed)
			(pads allowed)
			(copperpour not_allowed)
			(footprints allowed)
		)
		(placement
			(enabled no)
			(sheetname "")
		)
		(fill yes
			(thermal_gap 0.5)
			(thermal_bridge_width 0.5)
			(island_removal_mode 0)
		)
		(polygon
			(pts
				(arc
					(start 280.966164 -216.885012)
					(mid 280.305764 -216.885012)
					(end 280.966164 -216.885012)
				)
			)
		)
	)
	(zone
		(layers "In1.Cu" "In2.Cu")
		(hatch none 0.5)
		(connect_pads
			(clearance 0)
		)
		(min_thickness 0.25)
		(keepout
			(tracks not_allowed)
			(vias allowed)
			(pads allowed)
			(copperpour not_allowed)
			(footprints allowed)
		)
		(placement
			(enabled no)
			(sheetname "")
		)
		(fill yes
			(thermal_gap 0.5)
			(thermal_bridge_width 0.5)
			(island_removal_mode 0)
		)
		(polygon
			(pts
				(arc
					(start 427.786292 -254.284988)
					(mid 427.125892 -254.284988)
					(end 427.786292 -254.284988)
				)
			)
		)
	)
	(zone
		(layers "In1.Cu" "In2.Cu")
		(hatch none 0.5)
		(connect_pads
			(clearance 0)
		)
		(min_thickness 0.25)
		(keepout
			(tracks not_allowed)
			(vias allowed)
			(pads allowed)
			(copperpour not_allowed)
			(footprints allowed)
		)
		(placement
			(enabled no)
			(sheetname "")
		)
		(fill yes
			(thermal_gap 0.5)
			(thermal_bridge_width 0.5)
			(island_removal_mode 0)
		)
		(polygon
			(pts
				(arc
					(start 446.974468 -284.88513)
					(mid 446.314068 -284.88513)
					(end 446.974468 -284.88513)
				)
			)
		)
	)
	(zone
		(layers "In1.Cu" "In2.Cu")
		(hatch none 0.5)
		(connect_pads
			(clearance 0)
		)
		(min_thickness 0.25)
		(keepout
			(tracks not_allowed)
			(vias allowed)
			(pads allowed)
			(copperpour not_allowed)
			(footprints allowed)
		)
		(placement
			(enabled no)
			(sheetname "")
		)
		(fill yes
			(thermal_gap 0.5)
			(thermal_bridge_width 0.5)
			(island_removal_mode 0)
		)
		(polygon
			(pts
				(arc
					(start 29.582364 -261.08533)
					(mid 28.921964 -261.08533)
					(end 29.582364 -261.08533)
				)
			)
		)
	)
	(zone
		(layers "In1.Cu" "In2.Cu")
		(hatch none 0.5)
		(connect_pads
			(clearance 0)
		)
		(min_thickness 0.25)
		(keepout
			(tracks not_allowed)
			(vias allowed)
			(pads allowed)
			(copperpour not_allowed)
			(footprints allowed)
		)
		(placement
			(enabled no)
			(sheetname "")
		)
		(fill yes
			(thermal_gap 0.5)
			(thermal_bridge_width 0.5)
			(island_removal_mode 0)
		)
		(polygon
			(pts
				(arc
					(start 431.88636 -317.18504)
					(mid 431.22596 -317.18504)
					(end 431.88636 -317.18504)
				)
			)
		)
	)
	(zone
		(layers "In1.Cu" "In2.Cu")
		(hatch none 0.5)
		(connect_pads
			(clearance 0)
		)
		(min_thickness 0.25)
		(keepout
			(tracks not_allowed)
			(vias allowed)
			(pads allowed)
			(copperpour not_allowed)
			(footprints allowed)
		)
		(placement
			(enabled no)
			(sheetname "")
		)
		(fill yes
			(thermal_gap 0.5)
			(thermal_bridge_width 0.5)
			(island_removal_mode 0)
		)
		(polygon
			(pts
				(arc
					(start 40.57015 -301.035212)
					(mid 39.90975 -301.035212)
					(end 40.57015 -301.035212)
				)
			)
		)
	)
	(zone
		(layers "In1.Cu" "In2.Cu")
		(hatch none 0.5)
		(connect_pads
			(clearance 0)
		)
		(min_thickness 0.25)
		(keepout
			(tracks not_allowed)
			(vias allowed)
			(pads allowed)
			(copperpour not_allowed)
			(footprints allowed)
		)
		(placement
			(enabled no)
			(sheetname "")
		)
		(fill yes
			(thermal_gap 0.5)
			(thermal_bridge_width 0.5)
			(island_removal_mode 0)
		)
		(polygon
			(pts
				(arc
					(start 292.610286 -273.835114)
					(mid 291.949886 -273.835114)
					(end 292.610286 -273.835114)
				)
			)
		)
	)
	(zone
		(layers "In1.Cu" "In2.Cu")
		(hatch none 0.5)
		(connect_pads
			(clearance 0)
		)
		(min_thickness 0.25)
		(keepout
			(tracks not_allowed)
			(vias allowed)
			(pads allowed)
			(copperpour not_allowed)
			(footprints allowed)
		)
		(placement
			(enabled no)
			(sheetname "")
		)
		(fill yes
			(thermal_gap 0.5)
			(thermal_bridge_width 0.5)
			(island_removal_mode 0)
		)
		(polygon
			(pts
				(arc
					(start 187.390278 -218.585288)
					(mid 186.729878 -218.585288)
					(end 187.390278 -218.585288)
				)
			)
		)
	)
	(zone
		(layers "In1.Cu" "In2.Cu")
		(hatch none 0.5)
		(connect_pads
			(clearance 0)
		)
		(min_thickness 0.25)
		(keepout
			(tracks not_allowed)
			(vias allowed)
			(pads allowed)
			(copperpour not_allowed)
			(footprints allowed)
		)
		(placement
			(enabled no)
			(sheetname "")
		)
		(fill yes
			(thermal_gap 0.5)
			(thermal_bridge_width 0.5)
			(island_removal_mode 0)
		)
		(polygon
			(pts
				(arc
					(start 273.422364 -291.684964)
					(mid 272.761964 -291.684964)
					(end 273.422364 -291.684964)
				)
			)
		)
	)
	(zone
		(layers "In1.Cu" "In2.Cu")
		(hatch none 0.5)
		(connect_pads
			(clearance 0)
		)
		(min_thickness 0.25)
		(keepout
			(tracks not_allowed)
			(vias allowed)
			(pads allowed)
			(copperpour not_allowed)
			(footprints allowed)
		)
		(placement
			(enabled no)
			(sheetname "")
		)
		(fill yes
			(thermal_gap 0.5)
			(thermal_bridge_width 0.5)
			(island_removal_mode 0)
		)
		(polygon
			(pts
				(arc
					(start 116.127022 -26.792936)
					(mid 116.162943 -26.807815)
					(end 116.177822 -26.843736)
				)
				(arc
					(start 116.177822 -27.351736)
					(mid 116.162943 -27.387657)
					(end 116.127022 -27.402536)
				)
				(arc
					(start 115.470686 -27.402536)
					(mid 115.434765 -27.387657)
					(end 115.419886 -27.351736)
				)
				(arc
					(start 115.419886 -26.843736)
					(mid 115.434765 -26.807815)
					(end 115.470686 -26.792936)
				)
			)
		)
	)
	(zone
		(layers "In1.Cu" "In2.Cu")
		(hatch none 0.5)
		(connect_pads
			(clearance 0)
		)
		(min_thickness 0.25)
		(keepout
			(tracks not_allowed)
			(vias allowed)
			(pads allowed)
			(copperpour not_allowed)
			(footprints allowed)
		)
		(placement
			(enabled no)
			(sheetname "")
		)
		(fill yes
			(thermal_gap 0.5)
			(thermal_bridge_width 0.5)
			(island_removal_mode 0)
		)
		(polygon
			(pts
				(arc
					(start 285.066232 -201.585068)
					(mid 284.405832 -201.585068)
					(end 285.066232 -201.585068)
				)
			)
		)
	)
	(zone
		(layers "In1.Cu" "In2.Cu")
		(hatch none 0.5)
		(connect_pads
			(clearance 0)
		)
		(min_thickness 0.25)
		(keepout
			(tracks not_allowed)
			(vias allowed)
			(pads allowed)
			(copperpour not_allowed)
			(footprints allowed)
		)
		(placement
			(enabled no)
			(sheetname "")
		)
		(fill yes
			(thermal_gap 0.5)
			(thermal_bridge_width 0.5)
			(island_removal_mode 0)
		)
		(polygon
			(pts
				(arc
					(start 43.551602 -11.91768)
					(mid 43.529284 -11.971562)
					(end 43.475402 -11.99388)
				)
				(arc
					(start 42.438828 -11.99388)
					(mid 42.384946 -11.971562)
					(end 42.362628 -11.91768)
				)
				(arc
					(start 42.362628 -10.51814)
					(mid 42.384946 -10.464258)
					(end 42.438828 -10.44194)
				)
				(arc
					(start 43.475402 -10.44194)
					(mid 43.529284 -10.464258)
					(end 43.551602 -10.51814)
				)
			)
		)
	)
	(zone
		(layers "In1.Cu" "In2.Cu")
		(hatch none 0.5)
		(connect_pads
			(clearance 0)
		)
		(min_thickness 0.25)
		(keepout
			(tracks not_allowed)
			(vias allowed)
			(pads allowed)
			(copperpour not_allowed)
			(footprints allowed)
		)
		(placement
			(enabled no)
			(sheetname "")
		)
		(fill yes
			(thermal_gap 0.5)
			(thermal_bridge_width 0.5)
			(island_removal_mode 0)
		)
		(polygon
			(pts
				(arc
					(start 424.342306 -262.785098)
					(mid 423.681906 -262.785098)
					(end 424.342306 -262.785098)
				)
			)
		)
	)
	(zone
		(layers "In1.Cu" "In2.Cu")
		(hatch none 0.5)
		(connect_pads
			(clearance 0)
		)
		(min_thickness 0.25)
		(keepout
			(tracks not_allowed)
			(vias allowed)
			(pads allowed)
			(copperpour not_allowed)
			(footprints allowed)
		)
		(placement
			(enabled no)
			(sheetname "")
		)
		(fill yes
			(thermal_gap 0.5)
			(thermal_bridge_width 0.5)
			(island_removal_mode 0)
		)
		(polygon
			(pts
				(arc
					(start 202.478132 -312.085228)
					(mid 201.817732 -312.085228)
					(end 202.478132 -312.085228)
				)
			)
		)
	)
	(zone
		(layers "In1.Cu" "In2.Cu")
		(hatch none 0.5)
		(connect_pads
			(clearance 0)
		)
		(min_thickness 0.25)
		(keepout
			(tracks not_allowed)
			(vias allowed)
			(pads allowed)
			(copperpour not_allowed)
			(footprints allowed)
		)
		(placement
			(enabled no)
			(sheetname "")
		)
		(fill yes
			(thermal_gap 0.5)
			(thermal_bridge_width 0.5)
			(island_removal_mode 0)
		)
		(polygon
			(pts
				(arc
					(start 44.670218 -312.935366)
					(mid 44.009818 -312.935366)
					(end 44.670218 -312.935366)
				)
			)
		)
	)
	(zone
		(layers "In1.Cu" "In2.Cu")
		(hatch none 0.5)
		(connect_pads
			(clearance 0)
		)
		(min_thickness 0.25)
		(keepout
			(tracks not_allowed)
			(vias allowed)
			(pads allowed)
			(copperpour not_allowed)
			(footprints allowed)
		)
		(placement
			(enabled no)
			(sheetname "")
		)
		(fill yes
			(thermal_gap 0.5)
			(thermal_bridge_width 0.5)
			(island_removal_mode 0)
		)
		(polygon
			(pts
				(arc
					(start 446.974468 -289.135058)
					(mid 446.314068 -289.135058)
					(end 446.974468 -289.135058)
				)
			)
		)
	)
	(zone
		(layers "In1.Cu" "In2.Cu")
		(hatch none 0.5)
		(connect_pads
			(clearance 0)
		)
		(min_thickness 0.25)
		(keepout
			(tracks not_allowed)
			(vias allowed)
			(pads allowed)
			(copperpour not_allowed)
			(footprints allowed)
		)
		(placement
			(enabled no)
			(sheetname "")
		)
		(fill yes
			(thermal_gap 0.5)
			(thermal_bridge_width 0.5)
			(island_removal_mode 0)
		)
		(polygon
			(pts
				(arc
					(start 288.510218 -313.784996)
					(mid 287.849818 -313.784996)
					(end 288.510218 -313.784996)
				)
			)
		)
	)
	(zone
		(layers "In1.Cu" "In2.Cu")
		(hatch none 0.5)
		(connect_pads
			(clearance 0)
		)
		(min_thickness 0.25)
		(keepout
			(tracks not_allowed)
			(vias allowed)
			(pads allowed)
			(copperpour not_allowed)
			(footprints allowed)
		)
		(placement
			(enabled no)
			(sheetname "")
		)
		(fill yes
			(thermal_gap 0.5)
			(thermal_bridge_width 0.5)
			(island_removal_mode 0)
		)
		(polygon
			(pts
				(arc
					(start 48.114204 -211.7852)
					(mid 47.453804 -211.7852)
					(end 48.114204 -211.7852)
				)
			)
		)
	)
	(zone
		(layers "In1.Cu" "In2.Cu")
		(hatch none 0.5)
		(connect_pads
			(clearance 0)
		)
		(min_thickness 0.25)
		(keepout
			(tracks not_allowed)
			(vias allowed)
			(pads allowed)
			(copperpour not_allowed)
			(footprints allowed)
		)
		(placement
			(enabled no)
			(sheetname "")
		)
		(fill yes
			(thermal_gap 0.5)
			(thermal_bridge_width 0.5)
			(island_removal_mode 0)
		)
		(polygon
			(pts
				(arc
					(start 427.786292 -220.285056)
					(mid 427.125892 -220.285056)
					(end 427.786292 -220.285056)
				)
			)
		)
	)
	(zone
		(layers "In1.Cu" "In2.Cu")
		(hatch none 0.5)
		(connect_pads
			(clearance 0)
		)
		(min_thickness 0.25)
		(keepout
			(tracks not_allowed)
			(vias allowed)
			(pads allowed)
			(copperpour not_allowed)
			(footprints allowed)
		)
		(placement
			(enabled no)
			(sheetname "")
		)
		(fill yes
			(thermal_gap 0.5)
			(thermal_bridge_width 0.5)
			(island_removal_mode 0)
		)
		(polygon
			(pts
				(arc
					(start 187.390278 -265.335258)
					(mid 186.729878 -265.335258)
					(end 187.390278 -265.335258)
				)
			)
		)
	)
	(zone
		(layers "In1.Cu" "In2.Cu")
		(hatch none 0.5)
		(connect_pads
			(clearance 0)
		)
		(min_thickness 0.25)
		(keepout
			(tracks not_allowed)
			(vias allowed)
			(pads allowed)
			(copperpour not_allowed)
			(footprints allowed)
		)
		(placement
			(enabled no)
			(sheetname "")
		)
		(fill yes
			(thermal_gap 0.5)
			(thermal_bridge_width 0.5)
			(island_removal_mode 0)
		)
		(polygon
			(pts
				(arc
					(start 176.402238 -214.33536)
					(mid 175.741838 -214.33536)
					(end 176.402238 -214.33536)
				)
			)
		)
	)
	(zone
		(layers "In1.Cu" "In2.Cu")
		(hatch none 0.5)
		(connect_pads
			(clearance 0)
		)
		(min_thickness 0.25)
		(keepout
			(tracks not_allowed)
			(vias allowed)
			(pads allowed)
			(copperpour not_allowed)
			(footprints allowed)
		)
		(placement
			(enabled no)
			(sheetname "")
		)
		(fill yes
			(thermal_gap 0.5)
			(thermal_bridge_width 0.5)
			(island_removal_mode 0)
		)
		(polygon
			(pts
				(arc
					(start 273.422364 -261.93496)
					(mid 272.761964 -261.93496)
					(end 273.422364 -261.93496)
				)
			)
		)
	)
	(zone
		(layers "In1.Cu" "In2.Cu")
		(hatch none 0.5)
		(connect_pads
			(clearance 0)
		)
		(min_thickness 0.25)
		(keepout
			(tracks not_allowed)
			(vias allowed)
			(pads allowed)
			(copperpour not_allowed)
			(footprints allowed)
		)
		(placement
			(enabled no)
			(sheetname "")
		)
		(fill yes
			(thermal_gap 0.5)
			(thermal_bridge_width 0.5)
			(island_removal_mode 0)
		)
		(polygon
			(pts
				(arc
					(start 442.8744 -291.684964)
					(mid 442.214 -291.684964)
					(end 442.8744 -291.684964)
				)
			)
		)
	)
	(zone
		(layers "In1.Cu" "In2.Cu")
		(hatch none 0.5)
		(connect_pads
			(clearance 0)
		)
		(min_thickness 0.25)
		(keepout
			(tracks not_allowed)
			(vias allowed)
			(pads allowed)
			(copperpour not_allowed)
			(footprints allowed)
		)
		(placement
			(enabled no)
			(sheetname "")
		)
		(fill yes
			(thermal_gap 0.5)
			(thermal_bridge_width 0.5)
			(island_removal_mode 0)
		)
		(polygon
			(pts
				(arc
					(start 431.88636 -219.435172)
					(mid 431.22596 -219.435172)
					(end 431.88636 -219.435172)
				)
			)
		)
	)
	(zone
		(layers "In1.Cu" "In2.Cu")
		(hatch none 0.5)
		(connect_pads
			(clearance 0)
		)
		(min_thickness 0.25)
		(keepout
			(tracks not_allowed)
			(vias allowed)
			(pads allowed)
			(copperpour not_allowed)
			(footprints allowed)
		)
		(placement
			(enabled no)
			(sheetname "")
		)
		(fill yes
			(thermal_gap 0.5)
			(thermal_bridge_width 0.5)
			(island_removal_mode 0)
		)
		(polygon
			(pts
				(arc
					(start 17.938242 -267.03528)
					(mid 17.277842 -267.03528)
					(end 17.938242 -267.03528)
				)
			)
		)
	)
	(zone
		(layers "In1.Cu" "In2.Cu")
		(hatch none 0.5)
		(connect_pads
			(clearance 0)
		)
		(min_thickness 0.25)
		(keepout
			(tracks not_allowed)
			(vias allowed)
			(pads allowed)
			(copperpour not_allowed)
			(footprints allowed)
		)
		(placement
			(enabled no)
			(sheetname "")
		)
		(fill yes
			(thermal_gap 0.5)
			(thermal_bridge_width 0.5)
			(island_removal_mode 0)
		)
		(polygon
			(pts
				(arc
					(start 44.670218 -304.435256)
					(mid 44.009818 -304.435256)
					(end 44.670218 -304.435256)
				)
			)
		)
	)
	(zone
		(layers "In1.Cu" "In2.Cu")
		(hatch none 0.5)
		(connect_pads
			(clearance 0)
		)
		(min_thickness 0.25)
		(keepout
			(tracks not_allowed)
			(vias allowed)
			(pads allowed)
			(copperpour not_allowed)
			(footprints allowed)
		)
		(placement
			(enabled no)
			(sheetname "")
		)
		(fill yes
			(thermal_gap 0.5)
			(thermal_bridge_width 0.5)
			(island_removal_mode 0)
		)
		(polygon
			(pts
				(arc
					(start 176.402238 -221.985332)
					(mid 175.741838 -221.985332)
					(end 176.402238 -221.985332)
				)
			)
		)
	)
	(zone
		(layers "In1.Cu" "In2.Cu")
		(hatch none 0.5)
		(connect_pads
			(clearance 0)
		)
		(min_thickness 0.25)
		(keepout
			(tracks not_allowed)
			(vias allowed)
			(pads allowed)
			(copperpour not_allowed)
			(footprints allowed)
		)
		(placement
			(enabled no)
			(sheetname "")
		)
		(fill yes
			(thermal_gap 0.5)
			(thermal_bridge_width 0.5)
			(island_removal_mode 0)
		)
		(polygon
			(pts
				(arc
					(start 183.946292 -234.73537)
					(mid 183.285892 -234.73537)
					(end 183.946292 -234.73537)
				)
			)
		)
	)
	(zone
		(layers "In1.Cu" "In2.Cu")
		(hatch none 0.5)
		(connect_pads
			(clearance 0)
		)
		(min_thickness 0.25)
		(keepout
			(tracks not_allowed)
			(vias allowed)
			(pads allowed)
			(copperpour not_allowed)
			(footprints allowed)
		)
		(placement
			(enabled no)
			(sheetname "")
		)
		(fill yes
			(thermal_gap 0.5)
			(thermal_bridge_width 0.5)
			(island_removal_mode 0)
		)
		(polygon
			(pts
				(arc
					(start 427.786292 -216.885012)
					(mid 427.125892 -216.885012)
					(end 427.786292 -216.885012)
				)
			)
		)
	)
	(zone
		(layers "In1.Cu" "In2.Cu")
		(hatch none 0.5)
		(connect_pads
			(clearance 0)
		)
		(min_thickness 0.25)
		(keepout
			(tracks not_allowed)
			(vias allowed)
			(pads allowed)
			(copperpour not_allowed)
			(footprints allowed)
		)
		(placement
			(enabled no)
			(sheetname "")
		)
		(fill yes
			(thermal_gap 0.5)
			(thermal_bridge_width 0.5)
			(island_removal_mode 0)
		)
		(polygon
			(pts
				(arc
					(start 431.88636 -250.884944)
					(mid 431.22596 -250.884944)
					(end 431.88636 -250.884944)
				)
			)
		)
	)
	(zone
		(layers "In1.Cu" "In2.Cu")
		(hatch none 0.5)
		(connect_pads
			(clearance 0)
		)
		(min_thickness 0.25)
		(keepout
			(tracks not_allowed)
			(vias allowed)
			(pads allowed)
			(copperpour not_allowed)
			(footprints allowed)
		)
		(placement
			(enabled no)
			(sheetname "")
		)
		(fill yes
			(thermal_gap 0.5)
			(thermal_bridge_width 0.5)
			(island_removal_mode 0)
		)
		(polygon
			(pts
				(arc
					(start 172.30217 -293.38524)
					(mid 171.64177 -293.38524)
					(end 172.30217 -293.38524)
				)
			)
		)
	)
	(zone
		(layers "In1.Cu" "In2.Cu")
		(hatch none 0.5)
		(connect_pads
			(clearance 0)
		)
		(min_thickness 0.25)
		(keepout
			(tracks not_allowed)
			(vias allowed)
			(pads allowed)
			(copperpour not_allowed)
			(footprints allowed)
		)
		(placement
			(enabled no)
			(sheetname "")
		)
		(fill yes
			(thermal_gap 0.5)
			(thermal_bridge_width 0.5)
			(island_removal_mode 0)
		)
		(polygon
			(pts
				(arc
					(start 424.962066 -385.243578)
					(mid 424.95283 -385.263502)
					(end 424.94962 -385.285234)
				)
				(arc
					(start 424.94962 -385.479798)
					(mid 424.971938 -385.53368)
					(end 425.02582 -385.555998)
				)
				(arc
					(start 425.71162 -385.555998)
					(mid 425.765502 -385.53368)
					(end 425.78782 -385.479798)
				)
				(arc
					(start 425.78782 -385.285234)
					(mid 425.784652 -385.26349)
					(end 425.775374 -385.243578)
				)
				(arc
					(start 425.582588 -384.947414)
					(mid 425.570366 -384.90573)
					(end 425.582842 -384.864102)
				)
				(arc
					(start 425.775374 -384.570478)
					(mid 425.78461 -384.550554)
					(end 425.78782 -384.528822)
				)
				(arc
					(start 425.78782 -384.334258)
					(mid 425.765502 -384.280376)
					(end 425.71162 -384.258058)
				)
				(arc
					(start 425.02582 -384.258058)
					(mid 424.971938 -384.280376)
					(end 424.94962 -384.334258)
				)
				(arc
					(start 424.94962 -384.530092)
					(mid 424.952788 -384.551836)
					(end 424.962066 -384.571748)
				)
				(arc
					(start 425.154598 -384.865372)
					(mid 425.167 -384.907028)
					(end 425.154598 -384.948684)
				)
			)
		)
	)
	(zone
		(layers "In1.Cu" "In2.Cu")
		(hatch none 0.5)
		(connect_pads
			(clearance 0)
		)
		(min_thickness 0.25)
		(keepout
			(tracks not_allowed)
			(vias allowed)
			(pads allowed)
			(copperpour not_allowed)
			(footprints allowed)
		)
		(placement
			(enabled no)
			(sheetname "")
		)
		(fill yes
			(thermal_gap 0.5)
			(thermal_bridge_width 0.5)
			(island_removal_mode 0)
		)
		(polygon
			(pts
				(arc
					(start 52.214272 -304.435256)
					(mid 51.553872 -304.435256)
					(end 52.214272 -304.435256)
				)
			)
		)
	)
	(zone
		(layers "In1.Cu" "In2.Cu")
		(hatch none 0.5)
		(connect_pads
			(clearance 0)
		)
		(min_thickness 0.25)
		(keepout
			(tracks not_allowed)
			(vias allowed)
			(pads allowed)
			(copperpour not_allowed)
			(footprints allowed)
		)
		(placement
			(enabled no)
			(sheetname "")
		)
		(fill yes
			(thermal_gap 0.5)
			(thermal_bridge_width 0.5)
			(island_removal_mode 0)
		)
		(polygon
			(pts
				(arc
					(start 44.670218 -231.335326)
					(mid 44.009818 -231.335326)
					(end 44.670218 -231.335326)
				)
			)
		)
	)
	(zone
		(layers "In1.Cu" "In2.Cu")
		(hatch none 0.5)
		(connect_pads
			(clearance 0)
		)
		(min_thickness 0.25)
		(keepout
			(tracks not_allowed)
			(vias allowed)
			(pads allowed)
			(copperpour not_allowed)
			(footprints allowed)
		)
		(placement
			(enabled no)
			(sheetname "")
		)
		(fill yes
			(thermal_gap 0.5)
			(thermal_bridge_width 0.5)
			(island_removal_mode 0)
		)
		(polygon
			(pts
				(arc
					(start 44.670218 -270.435324)
					(mid 44.009818 -270.435324)
					(end 44.670218 -270.435324)
				)
			)
		)
	)
	(zone
		(layers "In1.Cu" "In2.Cu")
		(hatch none 0.5)
		(connect_pads
			(clearance 0)
		)
		(min_thickness 0.25)
		(keepout
			(tracks not_allowed)
			(vias allowed)
			(pads allowed)
			(copperpour not_allowed)
			(footprints allowed)
		)
		(placement
			(enabled no)
			(sheetname "")
		)
		(fill yes
			(thermal_gap 0.5)
			(thermal_bridge_width 0.5)
			(island_removal_mode 0)
		)
		(polygon
			(pts
				(arc
					(start 177.832258 -48.558704)
					(mid 177.88614 -48.581022)
					(end 177.908458 -48.634904)
				)
				(arc
					(start 177.908458 -49.464976)
					(mid 177.88614 -49.518858)
					(end 177.832258 -49.541176)
				)
				(arc
					(start 176.384458 -49.541176)
					(mid 176.330576 -49.518858)
					(end 176.308258 -49.464976)
				)
				(arc
					(start 176.308258 -48.634904)
					(mid 176.330576 -48.581022)
					(end 176.384458 -48.558704)
				)
			)
		)
	)
	(zone
		(layers "In1.Cu" "In2.Cu")
		(hatch none 0.5)
		(connect_pads
			(clearance 0)
		)
		(min_thickness 0.25)
		(keepout
			(tracks not_allowed)
			(vias allowed)
			(pads allowed)
			(copperpour not_allowed)
			(footprints allowed)
		)
		(placement
			(enabled no)
			(sheetname "")
		)
		(fill yes
			(thermal_gap 0.5)
			(thermal_bridge_width 0.5)
			(island_removal_mode 0)
		)
		(polygon
			(pts
				(arc
					(start 52.214272 -295.085262)
					(mid 51.553872 -295.085262)
					(end 52.214272 -295.085262)
				)
			)
		)
	)
	(zone
		(layers "In1.Cu" "In2.Cu")
		(hatch none 0.5)
		(connect_pads
			(clearance 0)
		)
		(min_thickness 0.25)
		(keepout
			(tracks not_allowed)
			(vias allowed)
			(pads allowed)
			(copperpour not_allowed)
			(footprints allowed)
		)
		(placement
			(enabled no)
			(sheetname "")
		)
		(fill yes
			(thermal_gap 0.5)
			(thermal_bridge_width 0.5)
			(island_removal_mode 0)
		)
		(polygon
			(pts
				(arc
					(start 439.430414 -216.035128)
					(mid 438.770014 -216.035128)
					(end 439.430414 -216.035128)
				)
			)
		)
	)
	(zone
		(layers "In1.Cu" "In2.Cu")
		(hatch none 0.5)
		(connect_pads
			(clearance 0)
		)
		(min_thickness 0.25)
		(keepout
			(tracks not_allowed)
			(vias allowed)
			(pads allowed)
			(copperpour not_allowed)
			(footprints allowed)
		)
		(placement
			(enabled no)
			(sheetname "")
		)
		(fill yes
			(thermal_gap 0.5)
			(thermal_bridge_width 0.5)
			(island_removal_mode 0)
		)
		(polygon
			(pts
				(arc
					(start 183.946292 -272.135346)
					(mid 183.285892 -272.135346)
					(end 183.946292 -272.135346)
				)
			)
		)
	)
	(zone
		(layers "In1.Cu" "In2.Cu")
		(hatch none 0.5)
		(connect_pads
			(clearance 0)
		)
		(min_thickness 0.25)
		(keepout
			(tracks not_allowed)
			(vias allowed)
			(pads allowed)
			(copperpour not_allowed)
			(footprints allowed)
		)
		(placement
			(enabled no)
			(sheetname "")
		)
		(fill yes
			(thermal_gap 0.5)
			(thermal_bridge_width 0.5)
			(island_removal_mode 0)
		)
		(polygon
			(pts
				(arc
					(start 292.610286 -289.135058)
					(mid 291.949886 -289.135058)
					(end 292.610286 -289.135058)
				)
			)
		)
	)
	(zone
		(layers "In1.Cu" "In2.Cu")
		(hatch none 0.5)
		(connect_pads
			(clearance 0)
		)
		(min_thickness 0.25)
		(keepout
			(tracks not_allowed)
			(vias allowed)
			(pads allowed)
			(copperpour not_allowed)
			(footprints allowed)
		)
		(placement
			(enabled no)
			(sheetname "")
		)
		(fill yes
			(thermal_gap 0.5)
			(thermal_bridge_width 0.5)
			(island_removal_mode 0)
		)
		(polygon
			(pts
				(arc
					(start 172.30217 -297.635422)
					(mid 171.64177 -297.635422)
					(end 172.30217 -297.635422)
				)
			)
		)
	)
	(zone
		(layers "In1.Cu" "In2.Cu")
		(hatch none 0.5)
		(connect_pads
			(clearance 0)
		)
		(min_thickness 0.25)
		(keepout
			(tracks not_allowed)
			(vias allowed)
			(pads allowed)
			(copperpour not_allowed)
			(footprints allowed)
		)
		(placement
			(enabled no)
			(sheetname "")
		)
		(fill yes
			(thermal_gap 0.5)
			(thermal_bridge_width 0.5)
			(island_removal_mode 0)
		)
		(polygon
			(pts
				(arc
					(start 199.0344 -276.385274)
					(mid 198.374 -276.385274)
					(end 199.0344 -276.385274)
				)
			)
		)
	)
	(zone
		(layers "In1.Cu" "In2.Cu")
		(hatch none 0.5)
		(connect_pads
			(clearance 0)
		)
		(min_thickness 0.25)
		(keepout
			(tracks not_allowed)
			(vias allowed)
			(pads allowed)
			(copperpour not_allowed)
			(footprints allowed)
		)
		(placement
			(enabled no)
			(sheetname "")
		)
		(fill yes
			(thermal_gap 0.5)
			(thermal_bridge_width 0.5)
			(island_removal_mode 0)
		)
		(polygon
			(pts
				(arc
					(start 273.422364 -310.384952)
					(mid 272.761964 -310.384952)
					(end 273.422364 -310.384952)
				)
			)
		)
	)
	(zone
		(layers "In1.Cu" "In2.Cu")
		(hatch none 0.5)
		(connect_pads
			(clearance 0)
		)
		(min_thickness 0.25)
		(keepout
			(tracks not_allowed)
			(vias allowed)
			(pads allowed)
			(copperpour not_allowed)
			(footprints allowed)
		)
		(placement
			(enabled no)
			(sheetname "")
		)
		(fill yes
			(thermal_gap 0.5)
			(thermal_bridge_width 0.5)
			(island_removal_mode 0)
		)
		(polygon
			(pts
				(arc
					(start 29.582364 -203.285344)
					(mid 28.921964 -203.285344)
					(end 29.582364 -203.285344)
				)
			)
		)
	)
	(zone
		(layers "In1.Cu" "In2.Cu")
		(hatch none 0.5)
		(connect_pads
			(clearance 0)
		)
		(min_thickness 0.25)
		(keepout
			(tracks not_allowed)
			(vias allowed)
			(pads allowed)
			(copperpour not_allowed)
			(footprints allowed)
		)
		(placement
			(enabled no)
			(sheetname "")
		)
		(fill yes
			(thermal_gap 0.5)
			(thermal_bridge_width 0.5)
			(island_removal_mode 0)
		)
		(polygon
			(pts
				(arc
					(start 427.786292 -278.93518)
					(mid 427.125892 -278.93518)
					(end 427.786292 -278.93518)
				)
			)
		)
	)
	(zone
		(layers "In1.Cu" "In2.Cu")
		(hatch none 0.5)
		(connect_pads
			(clearance 0)
		)
		(min_thickness 0.25)
		(keepout
			(tracks not_allowed)
			(vias allowed)
			(pads allowed)
			(copperpour not_allowed)
			(footprints allowed)
		)
		(placement
			(enabled no)
			(sheetname "")
		)
		(fill yes
			(thermal_gap 0.5)
			(thermal_bridge_width 0.5)
			(island_removal_mode 0)
		)
		(polygon
			(pts
				(arc
					(start 389.056372 -417.242244)
					(mid 389.07869 -417.296126)
					(end 389.132572 -417.318444)
				)
				(arc
					(start 389.328152 -417.318444)
					(mid 389.350028 -417.315312)
					(end 389.370062 -417.305998)
				)
				(arc
					(start 389.663686 -417.113466)
					(mid 389.705342 -417.101064)
					(end 389.746998 -417.113466)
				)
				(arc
					(start 390.041892 -417.305998)
					(mid 390.061816 -417.315234)
					(end 390.083548 -417.318444)
				)
				(arc
					(start 390.278112 -417.318444)
					(mid 390.331994 -417.296126)
					(end 390.354312 -417.242244)
				)
				(arc
					(start 390.354312 -416.556444)
					(mid 390.331994 -416.502562)
					(end 390.278112 -416.480244)
				)
				(arc
					(start 390.083548 -416.480244)
					(mid 390.061804 -416.483412)
					(end 390.041892 -416.49269)
				)
				(arc
					(start 389.745728 -416.685476)
					(mid 389.704044 -416.697698)
					(end 389.662416 -416.685222)
				)
				(arc
					(start 389.368792 -416.49269)
					(mid 389.348868 -416.483454)
					(end 389.327136 -416.480244)
				)
				(arc
					(start 389.132572 -416.480244)
					(mid 389.07869 -416.502562)
					(end 389.056372 -416.556444)
				)
			)
		)
	)
	(zone
		(layers "In1.Cu" "In2.Cu")
		(hatch none 0.5)
		(connect_pads
			(clearance 0)
		)
		(min_thickness 0.25)
		(keepout
			(tracks not_allowed)
			(vias allowed)
			(pads allowed)
			(copperpour not_allowed)
			(footprints allowed)
		)
		(placement
			(enabled no)
			(sheetname "")
		)
		(fill yes
			(thermal_gap 0.5)
			(thermal_bridge_width 0.5)
			(island_removal_mode 0)
		)
		(polygon
			(pts
				(arc
					(start 176.402238 -252.58522)
					(mid 175.741838 -252.58522)
					(end 176.402238 -252.58522)
				)
			)
		)
	)
	(zone
		(layers "In1.Cu" "In2.Cu")
		(hatch none 0.5)
		(connect_pads
			(clearance 0)
		)
		(min_thickness 0.25)
		(keepout
			(tracks not_allowed)
			(vias allowed)
			(pads allowed)
			(copperpour not_allowed)
			(footprints allowed)
		)
		(placement
			(enabled no)
			(sheetname "")
		)
		(fill yes
			(thermal_gap 0.5)
			(thermal_bridge_width 0.5)
			(island_removal_mode 0)
		)
		(polygon
			(pts
				(arc
					(start 191.490346 -225.385376)
					(mid 190.829946 -225.385376)
					(end 191.490346 -225.385376)
				)
			)
		)
	)
	(zone
		(layers "In1.Cu" "In2.Cu")
		(hatch none 0.5)
		(connect_pads
			(clearance 0)
		)
		(min_thickness 0.25)
		(keepout
			(tracks not_allowed)
			(vias allowed)
			(pads allowed)
			(copperpour not_allowed)
			(footprints allowed)
		)
		(placement
			(enabled no)
			(sheetname "")
		)
		(fill yes
			(thermal_gap 0.5)
			(thermal_bridge_width 0.5)
			(island_removal_mode 0)
		)
		(polygon
			(pts
				(arc
					(start 435.330346 -233.884978)
					(mid 434.669946 -233.884978)
					(end 435.330346 -233.884978)
				)
			)
		)
	)
	(zone
		(layers "In1.Cu" "In2.Cu")
		(hatch none 0.5)
		(connect_pads
			(clearance 0)
		)
		(min_thickness 0.25)
		(keepout
			(tracks not_allowed)
			(vias allowed)
			(pads allowed)
			(copperpour not_allowed)
			(footprints allowed)
		)
		(placement
			(enabled no)
			(sheetname "")
		)
		(fill yes
			(thermal_gap 0.5)
			(thermal_bridge_width 0.5)
			(island_removal_mode 0)
		)
		(polygon
			(pts
				(arc
					(start 427.786292 -218.585034)
					(mid 427.125892 -218.585034)
					(end 427.786292 -218.585034)
				)
			)
		)
	)
	(zone
		(layers "In1.Cu" "In2.Cu")
		(hatch none 0.5)
		(connect_pads
			(clearance 0)
		)
		(min_thickness 0.25)
		(keepout
			(tracks not_allowed)
			(vias allowed)
			(pads allowed)
			(copperpour not_allowed)
			(footprints allowed)
		)
		(placement
			(enabled no)
			(sheetname "")
		)
		(fill yes
			(thermal_gap 0.5)
			(thermal_bridge_width 0.5)
			(island_removal_mode 0)
		)
		(polygon
			(pts
				(arc
					(start 151.920194 -370.978684)
					(mid 151.940118 -370.98792)
					(end 151.96185 -370.99113)
				)
				(arc
					(start 152.156414 -370.99113)
					(mid 152.210296 -370.968812)
					(end 152.232614 -370.91493)
				)
				(arc
					(start 152.232614 -370.22913)
					(mid 152.210296 -370.175248)
					(end 152.156414 -370.15293)
				)
				(arc
					(start 151.96185 -370.15293)
					(mid 151.940106 -370.156098)
					(end 151.920194 -370.165376)
				)
				(arc
					(start 151.62403 -370.358162)
					(mid 151.582346 -370.370384)
					(end 151.540718 -370.357908)
				)
				(arc
					(start 151.247094 -370.165376)
					(mid 151.22717 -370.15614)
					(end 151.205438 -370.15293)
				)
				(arc
					(start 151.010874 -370.15293)
					(mid 150.956992 -370.175248)
					(end 150.934674 -370.22913)
				)
				(arc
					(start 150.934674 -370.91493)
					(mid 150.956992 -370.968812)
					(end 151.010874 -370.99113)
				)
				(arc
					(start 151.206708 -370.99113)
					(mid 151.228452 -370.987962)
					(end 151.248364 -370.978684)
				)
				(arc
					(start 151.541988 -370.786152)
					(mid 151.583644 -370.77375)
					(end 151.6253 -370.786152)
				)
			)
		)
	)
	(zone
		(layers "In1.Cu" "In2.Cu")
		(hatch none 0.5)
		(connect_pads
			(clearance 0)
		)
		(min_thickness 0.25)
		(keepout
			(tracks not_allowed)
			(vias allowed)
			(pads allowed)
			(copperpour not_allowed)
			(footprints allowed)
		)
		(placement
			(enabled no)
			(sheetname "")
		)
		(fill yes
			(thermal_gap 0.5)
			(thermal_bridge_width 0.5)
			(island_removal_mode 0)
		)
		(polygon
			(pts
				(arc
					(start 435.330346 -226.235006)
					(mid 434.669946 -226.235006)
					(end 435.330346 -226.235006)
				)
			)
		)
	)
	(zone
		(layers "In1.Cu" "In2.Cu")
		(hatch none 0.5)
		(connect_pads
			(clearance 0)
		)
		(min_thickness 0.25)
		(keepout
			(tracks not_allowed)
			(vias allowed)
			(pads allowed)
			(copperpour not_allowed)
			(footprints allowed)
		)
		(placement
			(enabled no)
			(sheetname "")
		)
		(fill yes
			(thermal_gap 0.5)
			(thermal_bridge_width 0.5)
			(island_removal_mode 0)
		)
		(polygon
			(pts
				(arc
					(start 29.582364 -201.585322)
					(mid 28.921964 -201.585322)
					(end 29.582364 -201.585322)
				)
			)
		)
	)
	(zone
		(layers "In1.Cu" "In2.Cu")
		(hatch none 0.5)
		(connect_pads
			(clearance 0)
		)
		(min_thickness 0.25)
		(keepout
			(tracks not_allowed)
			(vias allowed)
			(pads allowed)
			(copperpour not_allowed)
			(footprints allowed)
		)
		(placement
			(enabled no)
			(sheetname "")
		)
		(fill yes
			(thermal_gap 0.5)
			(thermal_bridge_width 0.5)
			(island_removal_mode 0)
		)
		(polygon
			(pts
				(arc
					(start 427.786292 -272.984976)
					(mid 427.125892 -272.984976)
					(end 427.786292 -272.984976)
				)
			)
		)
	)
	(zone
		(layers "In1.Cu" "In2.Cu")
		(hatch none 0.5)
		(connect_pads
			(clearance 0)
		)
		(min_thickness 0.25)
		(keepout
			(tracks not_allowed)
			(vias allowed)
			(pads allowed)
			(copperpour not_allowed)
			(footprints allowed)
		)
		(placement
			(enabled no)
			(sheetname "")
		)
		(fill yes
			(thermal_gap 0.5)
			(thermal_bridge_width 0.5)
			(island_removal_mode 0)
		)
		(polygon
			(pts
				(arc
					(start 48.114204 -253.435358)
					(mid 47.453804 -253.435358)
					(end 48.114204 -253.435358)
				)
			)
		)
	)
	(zone
		(layers "In1.Cu" "In2.Cu")
		(hatch none 0.5)
		(connect_pads
			(clearance 0)
		)
		(min_thickness 0.25)
		(keepout
			(tracks not_allowed)
			(vias allowed)
			(pads allowed)
			(copperpour not_allowed)
			(footprints allowed)
		)
		(placement
			(enabled no)
			(sheetname "")
		)
		(fill yes
			(thermal_gap 0.5)
			(thermal_bridge_width 0.5)
			(island_removal_mode 0)
		)
		(polygon
			(pts
				(arc
					(start 427.786292 -306.985162)
					(mid 427.125892 -306.985162)
					(end 427.786292 -306.985162)
				)
			)
		)
	)
	(zone
		(layers "In1.Cu" "In2.Cu")
		(hatch none 0.5)
		(connect_pads
			(clearance 0)
		)
		(min_thickness 0.25)
		(keepout
			(tracks not_allowed)
			(vias allowed)
			(pads allowed)
			(copperpour not_allowed)
			(footprints allowed)
		)
		(placement
			(enabled no)
			(sheetname "")
		)
		(fill yes
			(thermal_gap 0.5)
			(thermal_bridge_width 0.5)
			(island_removal_mode 0)
		)
		(polygon
			(pts
				(arc
					(start 454.518268 -249.185176)
					(mid 453.857868 -249.185176)
					(end 454.518268 -249.185176)
				)
			)
		)
	)
	(zone
		(layers "In1.Cu" "In2.Cu")
		(hatch none 0.5)
		(connect_pads
			(clearance 0)
		)
		(min_thickness 0.25)
		(keepout
			(tracks not_allowed)
			(vias allowed)
			(pads allowed)
			(copperpour not_allowed)
			(footprints allowed)
		)
		(placement
			(enabled no)
			(sheetname "")
		)
		(fill yes
			(thermal_gap 0.5)
			(thermal_bridge_width 0.5)
			(island_removal_mode 0)
		)
		(polygon
			(pts
				(arc
					(start 40.57015 -318.035432)
					(mid 39.90975 -318.035432)
					(end 40.57015 -318.035432)
				)
			)
		)
	)
	(zone
		(layers "In1.Cu" "In2.Cu")
		(hatch none 0.5)
		(connect_pads
			(clearance 0)
		)
		(min_thickness 0.25)
		(keepout
			(tracks not_allowed)
			(vias allowed)
			(pads allowed)
			(copperpour not_allowed)
			(footprints allowed)
		)
		(placement
			(enabled no)
			(sheetname "")
		)
		(fill yes
			(thermal_gap 0.5)
			(thermal_bridge_width 0.5)
			(island_removal_mode 0)
		)
		(polygon
			(pts
				(arc
					(start 33.026096 -205.83525)
					(mid 32.365696 -205.83525)
					(end 33.026096 -205.83525)
				)
			)
		)
	)
	(zone
		(layers "In1.Cu" "In2.Cu")
		(hatch none 0.5)
		(connect_pads
			(clearance 0)
		)
		(min_thickness 0.25)
		(keepout
			(tracks not_allowed)
			(vias allowed)
			(pads allowed)
			(copperpour not_allowed)
			(footprints allowed)
		)
		(placement
			(enabled no)
			(sheetname "")
		)
		(fill yes
			(thermal_gap 0.5)
			(thermal_bridge_width 0.5)
			(island_removal_mode 0)
		)
		(polygon
			(pts
				(arc
					(start 427.786292 -265.335004)
					(mid 427.125892 -265.335004)
					(end 427.786292 -265.335004)
				)
			)
		)
	)
	(zone
		(layers "In1.Cu" "In2.Cu")
		(hatch none 0.5)
		(connect_pads
			(clearance 0)
		)
		(min_thickness 0.25)
		(keepout
			(tracks not_allowed)
			(vias allowed)
			(pads allowed)
			(copperpour not_allowed)
			(footprints allowed)
		)
		(placement
			(enabled no)
			(sheetname "")
		)
		(fill yes
			(thermal_gap 0.5)
			(thermal_bridge_width 0.5)
			(island_removal_mode 0)
		)
		(polygon
			(pts
				(arc
					(start 172.30217 -295.085262)
					(mid 171.64177 -295.085262)
					(end 172.30217 -295.085262)
				)
			)
		)
	)
	(zone
		(layers "In1.Cu" "In2.Cu")
		(hatch none 0.5)
		(connect_pads
			(clearance 0)
		)
		(min_thickness 0.25)
		(keepout
			(tracks not_allowed)
			(vias allowed)
			(pads allowed)
			(copperpour not_allowed)
			(footprints allowed)
		)
		(placement
			(enabled no)
			(sheetname "")
		)
		(fill yes
			(thermal_gap 0.5)
			(thermal_bridge_width 0.5)
			(island_removal_mode 0)
		)
		(polygon
			(pts
				(arc
					(start 44.670218 -214.33536)
					(mid 44.009818 -214.33536)
					(end 44.670218 -214.33536)
				)
			)
		)
	)
	(zone
		(layers "In1.Cu" "In2.Cu")
		(hatch none 0.5)
		(connect_pads
			(clearance 0)
		)
		(min_thickness 0.25)
		(keepout
			(tracks not_allowed)
			(vias allowed)
			(pads allowed)
			(copperpour not_allowed)
			(footprints allowed)
		)
		(placement
			(enabled no)
			(sheetname "")
		)
		(fill yes
			(thermal_gap 0.5)
			(thermal_bridge_width 0.5)
			(island_removal_mode 0)
		)
		(polygon
			(pts
				(arc
					(start 64.205104 -373.442484)
					(mid 64.225028 -373.45172)
					(end 64.24676 -373.45493)
				)
				(arc
					(start 64.441324 -373.45493)
					(mid 64.495206 -373.432612)
					(end 64.517524 -373.37873)
				)
				(arc
					(start 64.517524 -372.69293)
					(mid 64.495206 -372.639048)
					(end 64.441324 -372.61673)
				)
				(arc
					(start 64.24676 -372.61673)
					(mid 64.225016 -372.619898)
					(end 64.205104 -372.629176)
				)
				(arc
					(start 63.90894 -372.821962)
					(mid 63.867256 -372.834184)
					(end 63.825628 -372.821708)
				)
				(arc
					(start 63.532004 -372.629176)
					(mid 63.51208 -372.61994)
					(end 63.490348 -372.61673)
				)
				(arc
					(start 63.295784 -372.61673)
					(mid 63.241902 -372.639048)
					(end 63.219584 -372.69293)
				)
				(arc
					(start 63.219584 -373.37873)
					(mid 63.241902 -373.432612)
					(end 63.295784 -373.45493)
				)
				(arc
					(start 63.491618 -373.45493)
					(mid 63.513362 -373.451762)
					(end 63.533274 -373.442484)
				)
				(arc
					(start 63.826898 -373.249952)
					(mid 63.868554 -373.23755)
					(end 63.91021 -373.249952)
				)
			)
		)
	)
	(zone
		(layers "In1.Cu" "In2.Cu")
		(hatch none 0.5)
		(connect_pads
			(clearance 0)
		)
		(min_thickness 0.25)
		(keepout
			(tracks not_allowed)
			(vias allowed)
			(pads allowed)
			(copperpour not_allowed)
			(footprints allowed)
		)
		(placement
			(enabled no)
			(sheetname "")
		)
		(fill yes
			(thermal_gap 0.5)
			(thermal_bridge_width 0.5)
			(island_removal_mode 0)
		)
		(polygon
			(pts
				(arc
					(start 273.422364 -312.084974)
					(mid 272.761964 -312.084974)
					(end 273.422364 -312.084974)
				)
			)
		)
	)
	(zone
		(layers "In1.Cu" "In2.Cu")
		(hatch none 0.5)
		(connect_pads
			(clearance 0)
		)
		(min_thickness 0.25)
		(keepout
			(tracks not_allowed)
			(vias allowed)
			(pads allowed)
			(copperpour not_allowed)
			(footprints allowed)
		)
		(placement
			(enabled no)
			(sheetname "")
		)
		(fill yes
			(thermal_gap 0.5)
			(thermal_bridge_width 0.5)
			(island_removal_mode 0)
		)
		(polygon
			(pts
				(arc
					(start 435.330346 -263.634982)
					(mid 434.669946 -263.634982)
					(end 435.330346 -263.634982)
				)
			)
		)
	)
	(zone
		(layers "In1.Cu" "In2.Cu")
		(hatch none 0.5)
		(connect_pads
			(clearance 0)
		)
		(min_thickness 0.25)
		(keepout
			(tracks not_allowed)
			(vias allowed)
			(pads allowed)
			(copperpour not_allowed)
			(footprints allowed)
		)
		(placement
			(enabled no)
			(sheetname "")
		)
		(fill yes
			(thermal_gap 0.5)
			(thermal_bridge_width 0.5)
			(island_removal_mode 0)
		)
		(polygon
			(pts
				(arc
					(start 183.946292 -225.385376)
					(mid 183.285892 -225.385376)
					(end 183.946292 -225.385376)
				)
			)
		)
	)
	(zone
		(layers "In1.Cu" "In2.Cu")
		(hatch none 0.5)
		(connect_pads
			(clearance 0)
		)
		(min_thickness 0.25)
		(keepout
			(tracks not_allowed)
			(vias allowed)
			(pads allowed)
			(copperpour not_allowed)
			(footprints allowed)
		)
		(placement
			(enabled no)
			(sheetname "")
		)
		(fill yes
			(thermal_gap 0.5)
			(thermal_bridge_width 0.5)
			(island_removal_mode 0)
		)
		(polygon
			(pts
				(arc
					(start 33.026096 -285.735268)
					(mid 32.365696 -285.735268)
					(end 33.026096 -285.735268)
				)
			)
		)
	)
	(zone
		(layers "In1.Cu" "In2.Cu")
		(hatch none 0.5)
		(connect_pads
			(clearance 0)
		)
		(min_thickness 0.25)
		(keepout
			(tracks not_allowed)
			(vias allowed)
			(pads allowed)
			(copperpour not_allowed)
			(footprints allowed)
		)
		(placement
			(enabled no)
			(sheetname "")
		)
		(fill yes
			(thermal_gap 0.5)
			(thermal_bridge_width 0.5)
			(island_removal_mode 0)
		)
		(polygon
			(pts
				(arc
					(start 25.482296 -276.385274)
					(mid 24.821896 -276.385274)
					(end 25.482296 -276.385274)
				)
			)
		)
	)
	(zone
		(layers "In1.Cu" "In2.Cu")
		(hatch none 0.5)
		(connect_pads
			(clearance 0)
		)
		(min_thickness 0.25)
		(keepout
			(tracks not_allowed)
			(vias allowed)
			(pads allowed)
			(copperpour not_allowed)
			(footprints allowed)
		)
		(placement
			(enabled no)
			(sheetname "")
		)
		(fill yes
			(thermal_gap 0.5)
			(thermal_bridge_width 0.5)
			(island_removal_mode 0)
		)
		(polygon
			(pts
				(arc
					(start 427.786292 -224.534984)
					(mid 427.125892 -224.534984)
					(end 427.786292 -224.534984)
				)
			)
		)
	)
	(zone
		(layers "In1.Cu" "In2.Cu")
		(hatch none 0.5)
		(connect_pads
			(clearance 0)
		)
		(min_thickness 0.25)
		(keepout
			(tracks not_allowed)
			(vias allowed)
			(pads allowed)
			(copperpour not_allowed)
			(footprints allowed)
		)
		(placement
			(enabled no)
			(sheetname "")
		)
		(fill yes
			(thermal_gap 0.5)
			(thermal_bridge_width 0.5)
			(island_removal_mode 0)
		)
		(polygon
			(pts
				(arc
					(start 39.95166 -11.91768)
					(mid 39.929342 -11.971562)
					(end 39.87546 -11.99388)
				)
				(arc
					(start 38.838886 -11.99388)
					(mid 38.785004 -11.971562)
					(end 38.762686 -11.91768)
				)
				(arc
					(start 38.762686 -10.51814)
					(mid 38.785004 -10.464258)
					(end 38.838886 -10.44194)
				)
				(arc
					(start 39.87546 -10.44194)
					(mid 39.929342 -10.464258)
					(end 39.95166 -10.51814)
				)
			)
		)
	)
	(zone
		(layers "In1.Cu" "In2.Cu")
		(hatch none 0.5)
		(connect_pads
			(clearance 0)
		)
		(min_thickness 0.25)
		(keepout
			(tracks not_allowed)
			(vias allowed)
			(pads allowed)
			(copperpour not_allowed)
			(footprints allowed)
		)
		(placement
			(enabled no)
			(sheetname "")
		)
		(fill yes
			(thermal_gap 0.5)
			(thermal_bridge_width 0.5)
			(island_removal_mode 0)
		)
		(polygon
			(pts
				(arc
					(start 446.974468 -262.785098)
					(mid 446.314068 -262.785098)
					(end 446.974468 -262.785098)
				)
			)
		)
	)
	(zone
		(layers "In1.Cu" "In2.Cu")
		(hatch none 0.5)
		(connect_pads
			(clearance 0)
		)
		(min_thickness 0.25)
		(keepout
			(tracks not_allowed)
			(vias allowed)
			(pads allowed)
			(copperpour not_allowed)
			(footprints allowed)
		)
		(placement
			(enabled no)
			(sheetname "")
		)
		(fill yes
			(thermal_gap 0.5)
			(thermal_bridge_width 0.5)
			(island_removal_mode 0)
		)
		(polygon
			(pts
				(arc
					(start 76.311252 -373.442484)
					(mid 76.331176 -373.45172)
					(end 76.352908 -373.45493)
				)
				(arc
					(start 76.547472 -373.45493)
					(mid 76.601354 -373.432612)
					(end 76.623672 -373.37873)
				)
				(arc
					(start 76.623672 -372.69293)
					(mid 76.601354 -372.639048)
					(end 76.547472 -372.61673)
				)
				(arc
					(start 76.352908 -372.61673)
					(mid 76.331164 -372.619898)
					(end 76.311252 -372.629176)
				)
				(arc
					(start 76.015088 -372.821962)
					(mid 75.973404 -372.834184)
					(end 75.931776 -372.821708)
				)
				(arc
					(start 75.638152 -372.629176)
					(mid 75.618228 -372.61994)
					(end 75.596496 -372.61673)
				)
				(arc
					(start 75.401932 -372.61673)
					(mid 75.34805 -372.639048)
					(end 75.325732 -372.69293)
				)
				(arc
					(start 75.325732 -373.37873)
					(mid 75.34805 -373.432612)
					(end 75.401932 -373.45493)
				)
				(arc
					(start 75.597766 -373.45493)
					(mid 75.61951 -373.451762)
					(end 75.639422 -373.442484)
				)
				(arc
					(start 75.933046 -373.249952)
					(mid 75.974702 -373.23755)
					(end 76.016358 -373.249952)
				)
			)
		)
	)
	(zone
		(layers "In1.Cu" "In2.Cu")
		(hatch none 0.5)
		(connect_pads
			(clearance 0)
		)
		(min_thickness 0.25)
		(keepout
			(tracks not_allowed)
			(vias allowed)
			(pads allowed)
			(copperpour not_allowed)
			(footprints allowed)
		)
		(placement
			(enabled no)
			(sheetname "")
		)
		(fill yes
			(thermal_gap 0.5)
			(thermal_bridge_width 0.5)
			(island_removal_mode 0)
		)
		(polygon
			(pts
				(arc
					(start 172.30217 -232.18521)
					(mid 171.64177 -232.18521)
					(end 172.30217 -232.18521)
				)
			)
		)
	)
	(zone
		(layers "In1.Cu" "In2.Cu")
		(hatch none 0.5)
		(connect_pads
			(clearance 0)
		)
		(min_thickness 0.25)
		(keepout
			(tracks not_allowed)
			(vias allowed)
			(pads allowed)
			(copperpour not_allowed)
			(footprints allowed)
		)
		(placement
			(enabled no)
			(sheetname "")
		)
		(fill yes
			(thermal_gap 0.5)
			(thermal_bridge_width 0.5)
			(island_removal_mode 0)
		)
		(polygon
			(pts
				(arc
					(start 179.846224 -295.9354)
					(mid 179.185824 -295.9354)
					(end 179.846224 -295.9354)
				)
			)
		)
	)
	(zone
		(layers "In1.Cu" "In2.Cu")
		(hatch none 0.5)
		(connect_pads
			(clearance 0)
		)
		(min_thickness 0.25)
		(keepout
			(tracks not_allowed)
			(vias allowed)
			(pads allowed)
			(copperpour not_allowed)
			(footprints allowed)
		)
		(placement
			(enabled no)
			(sheetname "")
		)
		(fill yes
			(thermal_gap 0.5)
			(thermal_bridge_width 0.5)
			(island_removal_mode 0)
		)
		(polygon
			(pts
				(arc
					(start 300.15434 -295.085008)
					(mid 299.49394 -295.085008)
					(end 300.15434 -295.085008)
				)
			)
		)
	)
	(zone
		(layers "In1.Cu" "In2.Cu")
		(hatch none 0.5)
		(connect_pads
			(clearance 0)
		)
		(min_thickness 0.25)
		(keepout
			(tracks not_allowed)
			(vias allowed)
			(pads allowed)
			(copperpour not_allowed)
			(footprints allowed)
		)
		(placement
			(enabled no)
			(sheetname "")
		)
		(fill yes
			(thermal_gap 0.5)
			(thermal_bridge_width 0.5)
			(island_removal_mode 0)
		)
		(polygon
			(pts
				(arc
					(start 22.03831 -285.735268)
					(mid 21.37791 -285.735268)
					(end 22.03831 -285.735268)
				)
			)
		)
	)
	(zone
		(layers "In1.Cu" "In2.Cu")
		(hatch none 0.5)
		(connect_pads
			(clearance 0)
		)
		(min_thickness 0.25)
		(keepout
			(tracks not_allowed)
			(vias allowed)
			(pads allowed)
			(copperpour not_allowed)
			(footprints allowed)
		)
		(placement
			(enabled no)
			(sheetname "")
		)
		(fill yes
			(thermal_gap 0.5)
			(thermal_bridge_width 0.5)
			(island_removal_mode 0)
		)
		(polygon
			(pts
				(arc
					(start 269.978378 -261.085076)
					(mid 269.317978 -261.085076)
					(end 269.978378 -261.085076)
				)
			)
		)
	)
	(zone
		(layers "In1.Cu" "In2.Cu")
		(hatch none 0.5)
		(connect_pads
			(clearance 0)
		)
		(min_thickness 0.25)
		(keepout
			(tracks not_allowed)
			(vias allowed)
			(pads allowed)
			(copperpour not_allowed)
			(footprints allowed)
		)
		(placement
			(enabled no)
			(sheetname "")
		)
		(fill yes
			(thermal_gap 0.5)
			(thermal_bridge_width 0.5)
			(island_removal_mode 0)
		)
		(polygon
			(pts
				(arc
					(start 40.57015 -210.935316)
					(mid 39.90975 -210.935316)
					(end 40.57015 -210.935316)
				)
			)
		)
	)
	(zone
		(layers "In1.Cu" "In2.Cu")
		(hatch none 0.5)
		(connect_pads
			(clearance 0)
		)
		(min_thickness 0.25)
		(keepout
			(tracks not_allowed)
			(vias allowed)
			(pads allowed)
			(copperpour not_allowed)
			(footprints allowed)
		)
		(placement
			(enabled no)
			(sheetname "")
		)
		(fill yes
			(thermal_gap 0.5)
			(thermal_bridge_width 0.5)
			(island_removal_mode 0)
		)
		(polygon
			(pts
				(arc
					(start 194.934332 -267.03528)
					(mid 194.273932 -267.03528)
					(end 194.934332 -267.03528)
				)
			)
		)
	)
	(zone
		(layers "In1.Cu" "In2.Cu")
		(hatch none 0.5)
		(connect_pads
			(clearance 0)
		)
		(min_thickness 0.25)
		(keepout
			(tracks not_allowed)
			(vias allowed)
			(pads allowed)
			(copperpour not_allowed)
			(footprints allowed)
		)
		(placement
			(enabled no)
			(sheetname "")
		)
		(fill yes
			(thermal_gap 0.5)
			(thermal_bridge_width 0.5)
			(island_removal_mode 0)
		)
		(polygon
			(pts
				(arc
					(start 22.03831 -304.435256)
					(mid 21.37791 -304.435256)
					(end 22.03831 -304.435256)
				)
			)
		)
	)
	(zone
		(layers "In1.Cu" "In2.Cu")
		(hatch none 0.5)
		(connect_pads
			(clearance 0)
		)
		(min_thickness 0.25)
		(keepout
			(tracks not_allowed)
			(vias allowed)
			(pads allowed)
			(copperpour not_allowed)
			(footprints allowed)
		)
		(placement
			(enabled no)
			(sheetname "")
		)
		(fill yes
			(thermal_gap 0.5)
			(thermal_bridge_width 0.5)
			(island_removal_mode 0)
		)
		(polygon
			(pts
				(arc
					(start 183.946292 -223.685354)
					(mid 183.285892 -223.685354)
					(end 183.946292 -223.685354)
				)
			)
		)
	)
	(zone
		(layers "In1.Cu" "In2.Cu")
		(hatch none 0.5)
		(connect_pads
			(clearance 0)
		)
		(min_thickness 0.25)
		(keepout
			(tracks not_allowed)
			(vias allowed)
			(pads allowed)
			(copperpour not_allowed)
			(footprints allowed)
		)
		(placement
			(enabled no)
			(sheetname "")
		)
		(fill yes
			(thermal_gap 0.5)
			(thermal_bridge_width 0.5)
			(island_removal_mode 0)
		)
		(polygon
			(pts
				(arc
					(start 40.57015 -204.135228)
					(mid 39.90975 -204.135228)
					(end 40.57015 -204.135228)
				)
			)
		)
	)
	(zone
		(layers "In1.Cu" "In2.Cu")
		(hatch none 0.5)
		(connect_pads
			(clearance 0)
		)
		(min_thickness 0.25)
		(keepout
			(tracks not_allowed)
			(vias allowed)
			(pads allowed)
			(copperpour not_allowed)
			(footprints allowed)
		)
		(placement
			(enabled no)
			(sheetname "")
		)
		(fill yes
			(thermal_gap 0.5)
			(thermal_bridge_width 0.5)
			(island_removal_mode 0)
		)
		(polygon
			(pts
				(arc
					(start 450.4182 -213.484968)
					(mid 449.7578 -213.484968)
					(end 450.4182 -213.484968)
				)
			)
		)
	)
	(zone
		(layers "In1.Cu" "In2.Cu")
		(hatch none 0.5)
		(connect_pads
			(clearance 0)
		)
		(min_thickness 0.25)
		(keepout
			(tracks not_allowed)
			(vias allowed)
			(pads allowed)
			(copperpour not_allowed)
			(footprints allowed)
		)
		(placement
			(enabled no)
			(sheetname "")
		)
		(fill yes
			(thermal_gap 0.5)
			(thermal_bridge_width 0.5)
			(island_removal_mode 0)
		)
		(polygon
			(pts
				(arc
					(start 454.518268 -219.435172)
					(mid 453.857868 -219.435172)
					(end 454.518268 -219.435172)
				)
			)
		)
	)
	(zone
		(layers "In1.Cu" "In2.Cu")
		(hatch none 0.5)
		(connect_pads
			(clearance 0)
		)
		(min_thickness 0.25)
		(keepout
			(tracks not_allowed)
			(vias allowed)
			(pads allowed)
			(copperpour not_allowed)
			(footprints allowed)
		)
		(placement
			(enabled no)
			(sheetname "")
		)
		(fill yes
			(thermal_gap 0.5)
			(thermal_bridge_width 0.5)
			(island_removal_mode 0)
		)
		(polygon
			(pts
				(arc
					(start 300.15434 -283.185108)
					(mid 299.49394 -283.185108)
					(end 300.15434 -283.185108)
				)
			)
		)
	)
	(zone
		(layers "In1.Cu" "In2.Cu")
		(hatch none 0.5)
		(connect_pads
			(clearance 0)
		)
		(min_thickness 0.25)
		(keepout
			(tracks not_allowed)
			(vias allowed)
			(pads allowed)
			(copperpour not_allowed)
			(footprints allowed)
		)
		(placement
			(enabled no)
			(sheetname "")
		)
		(fill yes
			(thermal_gap 0.5)
			(thermal_bridge_width 0.5)
			(island_removal_mode 0)
		)
		(polygon
			(pts
				(arc
					(start 420.242238 -198.185024)
					(mid 419.581838 -198.185024)
					(end 420.242238 -198.185024)
				)
			)
		)
	)
	(zone
		(layers "In1.Cu" "In2.Cu")
		(hatch none 0.5)
		(connect_pads
			(clearance 0)
		)
		(min_thickness 0.25)
		(keepout
			(tracks not_allowed)
			(vias allowed)
			(pads allowed)
			(copperpour not_allowed)
			(footprints allowed)
		)
		(placement
			(enabled no)
			(sheetname "")
		)
		(fill yes
			(thermal_gap 0.5)
			(thermal_bridge_width 0.5)
			(island_removal_mode 0)
		)
		(polygon
			(pts
				(arc
					(start 435.330346 -288.285174)
					(mid 434.669946 -288.285174)
					(end 435.330346 -288.285174)
				)
			)
		)
	)
	(zone
		(layers "In1.Cu" "In2.Cu")
		(hatch none 0.5)
		(connect_pads
			(clearance 0)
		)
		(min_thickness 0.25)
		(keepout
			(tracks not_allowed)
			(vias allowed)
			(pads allowed)
			(copperpour not_allowed)
			(footprints allowed)
		)
		(placement
			(enabled no)
			(sheetname "")
		)
		(fill yes
			(thermal_gap 0.5)
			(thermal_bridge_width 0.5)
			(island_removal_mode 0)
		)
		(polygon
			(pts
				(arc
					(start 420.242238 -227.935028)
					(mid 419.581838 -227.935028)
					(end 420.242238 -227.935028)
				)
			)
		)
	)
	(zone
		(layers "In1.Cu" "In2.Cu")
		(hatch none 0.5)
		(connect_pads
			(clearance 0)
		)
		(min_thickness 0.25)
		(keepout
			(tracks not_allowed)
			(vias allowed)
			(pads allowed)
			(copperpour not_allowed)
			(footprints allowed)
		)
		(placement
			(enabled no)
			(sheetname "")
		)
		(fill yes
			(thermal_gap 0.5)
			(thermal_bridge_width 0.5)
			(island_removal_mode 0)
		)
		(polygon
			(pts
				(arc
					(start 292.610286 -227.085144)
					(mid 291.949886 -227.085144)
					(end 292.610286 -227.085144)
				)
			)
		)
	)
	(zone
		(layers "In1.Cu" "In2.Cu")
		(hatch none 0.5)
		(connect_pads
			(clearance 0)
		)
		(min_thickness 0.25)
		(keepout
			(tracks not_allowed)
			(vias allowed)
			(pads allowed)
			(copperpour not_allowed)
			(footprints allowed)
		)
		(placement
			(enabled no)
			(sheetname "")
		)
		(fill yes
			(thermal_gap 0.5)
			(thermal_bridge_width 0.5)
			(island_removal_mode 0)
		)
		(polygon
			(pts
				(arc
					(start 187.390278 -297.635422)
					(mid 186.729878 -297.635422)
					(end 187.390278 -297.635422)
				)
			)
		)
	)
	(zone
		(layers "In1.Cu" "In2.Cu")
		(hatch none 0.5)
		(connect_pads
			(clearance 0)
		)
		(min_thickness 0.25)
		(keepout
			(tracks not_allowed)
			(vias allowed)
			(pads allowed)
			(copperpour not_allowed)
			(footprints allowed)
		)
		(placement
			(enabled no)
			(sheetname "")
		)
		(fill yes
			(thermal_gap 0.5)
			(thermal_bridge_width 0.5)
			(island_removal_mode 0)
		)
		(polygon
			(pts
				(arc
					(start 312.766456 -417.242244)
					(mid 312.788774 -417.296126)
					(end 312.842656 -417.318444)
				)
				(arc
					(start 313.038236 -417.318444)
					(mid 313.060112 -417.315312)
					(end 313.080146 -417.305998)
				)
				(arc
					(start 313.37377 -417.113466)
					(mid 313.415426 -417.101064)
					(end 313.457082 -417.113466)
				)
				(arc
					(start 313.751976 -417.305998)
					(mid 313.7719 -417.315234)
					(end 313.793632 -417.318444)
				)
				(arc
					(start 313.988196 -417.318444)
					(mid 314.042078 -417.296126)
					(end 314.064396 -417.242244)
				)
				(arc
					(start 314.064396 -416.556444)
					(mid 314.042078 -416.502562)
					(end 313.988196 -416.480244)
				)
				(arc
					(start 313.793632 -416.480244)
					(mid 313.771888 -416.483412)
					(end 313.751976 -416.49269)
				)
				(arc
					(start 313.455812 -416.685476)
					(mid 313.414128 -416.697698)
					(end 313.3725 -416.685222)
				)
				(arc
					(start 313.078876 -416.49269)
					(mid 313.058952 -416.483454)
					(end 313.03722 -416.480244)
				)
				(arc
					(start 312.842656 -416.480244)
					(mid 312.788774 -416.502562)
					(end 312.766456 -416.556444)
				)
			)
		)
	)
	(zone
		(layers "In1.Cu" "In2.Cu")
		(hatch none 0.5)
		(connect_pads
			(clearance 0)
		)
		(min_thickness 0.25)
		(keepout
			(tracks not_allowed)
			(vias allowed)
			(pads allowed)
			(copperpour not_allowed)
			(footprints allowed)
		)
		(placement
			(enabled no)
			(sheetname "")
		)
		(fill yes
			(thermal_gap 0.5)
			(thermal_bridge_width 0.5)
			(island_removal_mode 0)
		)
		(polygon
			(pts
				(arc
					(start 37.126164 -262.785352)
					(mid 36.465764 -262.785352)
					(end 37.126164 -262.785352)
				)
			)
		)
	)
	(zone
		(layers "In1.Cu" "In2.Cu")
		(hatch none 0.5)
		(connect_pads
			(clearance 0)
		)
		(min_thickness 0.25)
		(keepout
			(tracks not_allowed)
			(vias allowed)
			(pads allowed)
			(copperpour not_allowed)
			(footprints allowed)
		)
		(placement
			(enabled no)
			(sheetname "")
		)
		(fill yes
			(thermal_gap 0.5)
			(thermal_bridge_width 0.5)
			(island_removal_mode 0)
		)
		(polygon
			(pts
				(arc
					(start 44.670218 -315.485272)
					(mid 44.009818 -315.485272)
					(end 44.670218 -315.485272)
				)
			)
		)
	)
	(zone
		(layers "In1.Cu" "In2.Cu")
		(hatch none 0.5)
		(connect_pads
			(clearance 0)
		)
		(min_thickness 0.25)
		(keepout
			(tracks not_allowed)
			(vias allowed)
			(pads allowed)
			(copperpour not_allowed)
			(footprints allowed)
		)
		(placement
			(enabled no)
			(sheetname "")
		)
		(fill yes
			(thermal_gap 0.5)
			(thermal_bridge_width 0.5)
			(island_removal_mode 0)
		)
		(polygon
			(pts
				(arc
					(start 273.422364 -265.335004)
					(mid 272.761964 -265.335004)
					(end 273.422364 -265.335004)
				)
			)
		)
	)
	(zone
		(layers "In1.Cu" "In2.Cu")
		(hatch none 0.5)
		(connect_pads
			(clearance 0)
		)
		(min_thickness 0.25)
		(keepout
			(tracks not_allowed)
			(vias allowed)
			(pads allowed)
			(copperpour not_allowed)
			(footprints allowed)
		)
		(placement
			(enabled no)
			(sheetname "")
		)
		(fill yes
			(thermal_gap 0.5)
			(thermal_bridge_width 0.5)
			(island_removal_mode 0)
		)
		(polygon
			(pts
				(arc
					(start 273.422364 -316.335156)
					(mid 272.761964 -316.335156)
					(end 273.422364 -316.335156)
				)
			)
		)
	)
	(zone
		(layers "In1.Cu" "In2.Cu")
		(hatch none 0.5)
		(connect_pads
			(clearance 0)
		)
		(min_thickness 0.25)
		(keepout
			(tracks not_allowed)
			(vias allowed)
			(pads allowed)
			(copperpour not_allowed)
			(footprints allowed)
		)
		(placement
			(enabled no)
			(sheetname "")
		)
		(fill yes
			(thermal_gap 0.5)
			(thermal_bridge_width 0.5)
			(island_removal_mode 0)
		)
		(polygon
			(pts
				(arc
					(start 435.330346 -302.73498)
					(mid 434.669946 -302.73498)
					(end 435.330346 -302.73498)
				)
			)
		)
	)
	(zone
		(layers "In1.Cu" "In2.Cu")
		(hatch none 0.5)
		(connect_pads
			(clearance 0)
		)
		(min_thickness 0.25)
		(keepout
			(tracks not_allowed)
			(vias allowed)
			(pads allowed)
			(copperpour not_allowed)
			(footprints allowed)
		)
		(placement
			(enabled no)
			(sheetname "")
		)
		(fill yes
			(thermal_gap 0.5)
			(thermal_bridge_width 0.5)
			(island_removal_mode 0)
		)
		(polygon
			(pts
				(arc
					(start 44.670218 -219.435426)
					(mid 44.009818 -219.435426)
					(end 44.670218 -219.435426)
				)
			)
		)
	)
	(zone
		(layers "In1.Cu" "In2.Cu")
		(hatch none 0.5)
		(connect_pads
			(clearance 0)
		)
		(min_thickness 0.25)
		(keepout
			(tracks not_allowed)
			(vias allowed)
			(pads allowed)
			(copperpour not_allowed)
			(footprints allowed)
		)
		(placement
			(enabled no)
			(sheetname "")
		)
		(fill yes
			(thermal_gap 0.5)
			(thermal_bridge_width 0.5)
			(island_removal_mode 0)
		)
		(polygon
			(pts
				(arc
					(start 25.482296 -302.735234)
					(mid 24.821896 -302.735234)
					(end 25.482296 -302.735234)
				)
			)
		)
	)
	(zone
		(layers "In1.Cu" "In2.Cu")
		(hatch none 0.5)
		(connect_pads
			(clearance 0)
		)
		(min_thickness 0.25)
		(keepout
			(tracks not_allowed)
			(vias allowed)
			(pads allowed)
			(copperpour not_allowed)
			(footprints allowed)
		)
		(placement
			(enabled no)
			(sheetname "")
		)
		(fill yes
			(thermal_gap 0.5)
			(thermal_bridge_width 0.5)
			(island_removal_mode 0)
		)
		(polygon
			(pts
				(arc
					(start 288.510218 -306.985162)
					(mid 287.849818 -306.985162)
					(end 288.510218 -306.985162)
				)
			)
		)
	)
	(zone
		(layers "In1.Cu" "In2.Cu")
		(hatch none 0.5)
		(connect_pads
			(clearance 0)
		)
		(min_thickness 0.25)
		(keepout
			(tracks not_allowed)
			(vias allowed)
			(pads allowed)
			(copperpour not_allowed)
			(footprints allowed)
		)
		(placement
			(enabled no)
			(sheetname "")
		)
		(fill yes
			(thermal_gap 0.5)
			(thermal_bridge_width 0.5)
			(island_removal_mode 0)
		)
		(polygon
			(pts
				(arc
					(start 277.522432 -227.085144)
					(mid 276.862032 -227.085144)
					(end 277.522432 -227.085144)
				)
			)
		)
	)
	(zone
		(layers "In1.Cu" "In2.Cu")
		(hatch none 0.5)
		(connect_pads
			(clearance 0)
		)
		(min_thickness 0.25)
		(keepout
			(tracks not_allowed)
			(vias allowed)
			(pads allowed)
			(copperpour not_allowed)
			(footprints allowed)
		)
		(placement
			(enabled no)
			(sheetname "")
		)
		(fill yes
			(thermal_gap 0.5)
			(thermal_bridge_width 0.5)
			(island_removal_mode 0)
		)
		(polygon
			(pts
				(arc
					(start 202.478132 -277.235412)
					(mid 201.817732 -277.235412)
					(end 202.478132 -277.235412)
				)
			)
		)
	)
	(zone
		(layers "In1.Cu" "In2.Cu")
		(hatch none 0.5)
		(connect_pads
			(clearance 0)
		)
		(min_thickness 0.25)
		(keepout
			(tracks not_allowed)
			(vias allowed)
			(pads allowed)
			(copperpour not_allowed)
			(footprints allowed)
		)
		(placement
			(enabled no)
			(sheetname "")
		)
		(fill yes
			(thermal_gap 0.5)
			(thermal_bridge_width 0.5)
			(island_removal_mode 0)
		)
		(polygon
			(pts
				(arc
					(start 48.114204 -209.235294)
					(mid 47.453804 -209.235294)
					(end 48.114204 -209.235294)
				)
			)
		)
	)
	(zone
		(layers "In1.Cu" "In2.Cu")
		(hatch none 0.5)
		(connect_pads
			(clearance 0)
		)
		(min_thickness 0.25)
		(keepout
			(tracks not_allowed)
			(vias allowed)
			(pads allowed)
			(copperpour not_allowed)
			(footprints allowed)
		)
		(placement
			(enabled no)
			(sheetname "")
		)
		(fill yes
			(thermal_gap 0.5)
			(thermal_bridge_width 0.5)
			(island_removal_mode 0)
		)
		(polygon
			(pts
				(arc
					(start 199.0344 -279.785318)
					(mid 198.374 -279.785318)
					(end 199.0344 -279.785318)
				)
			)
		)
	)
	(zone
		(layers "In1.Cu" "In2.Cu")
		(hatch none 0.5)
		(connect_pads
			(clearance 0)
		)
		(min_thickness 0.25)
		(keepout
			(tracks not_allowed)
			(vias allowed)
			(pads allowed)
			(copperpour not_allowed)
			(footprints allowed)
		)
		(placement
			(enabled no)
			(sheetname "")
		)
		(fill yes
			(thermal_gap 0.5)
			(thermal_bridge_width 0.5)
			(island_removal_mode 0)
		)
		(polygon
			(pts
				(arc
					(start 296.054272 -263.634982)
					(mid 295.393872 -263.634982)
					(end 296.054272 -263.634982)
				)
			)
		)
	)
	(zone
		(layers "In1.Cu" "In2.Cu")
		(hatch none 0.5)
		(connect_pads
			(clearance 0)
		)
		(min_thickness 0.25)
		(keepout
			(tracks not_allowed)
			(vias allowed)
			(pads allowed)
			(copperpour not_allowed)
			(footprints allowed)
		)
		(placement
			(enabled no)
			(sheetname "")
		)
		(fill yes
			(thermal_gap 0.5)
			(thermal_bridge_width 0.5)
			(island_removal_mode 0)
		)
		(polygon
			(pts
				(arc
					(start 199.0344 -223.685354)
					(mid 198.374 -223.685354)
					(end 199.0344 -223.685354)
				)
			)
		)
	)
	(zone
		(layers "In1.Cu" "In2.Cu")
		(hatch none 0.5)
		(connect_pads
			(clearance 0)
		)
		(min_thickness 0.25)
		(keepout
			(tracks not_allowed)
			(vias allowed)
			(pads allowed)
			(copperpour not_allowed)
			(footprints allowed)
		)
		(placement
			(enabled no)
			(sheetname "")
		)
		(fill yes
			(thermal_gap 0.5)
			(thermal_bridge_width 0.5)
			(island_removal_mode 0)
		)
		(polygon
			(pts
				(arc
					(start 431.88636 -233.035094)
					(mid 431.22596 -233.035094)
					(end 431.88636 -233.035094)
				)
			)
		)
	)
	(zone
		(layers "In1.Cu" "In2.Cu")
		(hatch none 0.5)
		(connect_pads
			(clearance 0)
		)
		(min_thickness 0.25)
		(keepout
			(tracks not_allowed)
			(vias allowed)
			(pads allowed)
			(copperpour not_allowed)
			(footprints allowed)
		)
		(placement
			(enabled no)
			(sheetname "")
		)
		(fill yes
			(thermal_gap 0.5)
			(thermal_bridge_width 0.5)
			(island_removal_mode 0)
		)
		(polygon
			(pts
				(arc
					(start 176.402238 -276.385274)
					(mid 175.741838 -276.385274)
					(end 176.402238 -276.385274)
				)
			)
		)
	)
	(zone
		(layers "In1.Cu" "In2.Cu")
		(hatch none 0.5)
		(connect_pads
			(clearance 0)
		)
		(min_thickness 0.25)
		(keepout
			(tracks not_allowed)
			(vias allowed)
			(pads allowed)
			(copperpour not_allowed)
			(footprints allowed)
		)
		(placement
			(enabled no)
			(sheetname "")
		)
		(fill yes
			(thermal_gap 0.5)
			(thermal_bridge_width 0.5)
			(island_removal_mode 0)
		)
		(polygon
			(pts
				(arc
					(start 172.30217 -261.935214)
					(mid 171.64177 -261.935214)
					(end 172.30217 -261.935214)
				)
			)
		)
	)
	(zone
		(layers "In1.Cu" "In2.Cu")
		(hatch none 0.5)
		(connect_pads
			(clearance 0)
		)
		(min_thickness 0.25)
		(keepout
			(tracks not_allowed)
			(vias allowed)
			(pads allowed)
			(copperpour not_allowed)
			(footprints allowed)
		)
		(placement
			(enabled no)
			(sheetname "")
		)
		(fill yes
			(thermal_gap 0.5)
			(thermal_bridge_width 0.5)
			(island_removal_mode 0)
		)
		(polygon
			(pts
				(arc
					(start 406.579578 -16.443198)
					(mid 406.601896 -16.49708)
					(end 406.655778 -16.519398)
				)
				(arc
					(start 406.851358 -16.519398)
					(mid 406.873234 -16.516266)
					(end 406.893268 -16.506952)
				)
				(arc
					(start 407.186892 -16.31442)
					(mid 407.228548 -16.302018)
					(end 407.270204 -16.31442)
				)
				(arc
					(start 407.565098 -16.506952)
					(mid 407.585022 -16.516188)
					(end 407.606754 -16.519398)
				)
				(arc
					(start 407.801318 -16.519398)
					(mid 407.8552 -16.49708)
					(end 407.877518 -16.443198)
				)
				(arc
					(start 407.877518 -15.757398)
					(mid 407.8552 -15.703516)
					(end 407.801318 -15.681198)
				)
				(arc
					(start 407.606754 -15.681198)
					(mid 407.58501 -15.684366)
					(end 407.565098 -15.693644)
				)
				(arc
					(start 407.268934 -15.88643)
					(mid 407.22725 -15.898652)
					(end 407.185622 -15.886176)
				)
				(arc
					(start 406.891998 -15.693644)
					(mid 406.872074 -15.684408)
					(end 406.850342 -15.681198)
				)
				(arc
					(start 406.655778 -15.681198)
					(mid 406.601896 -15.703516)
					(end 406.579578 -15.757398)
				)
			)
		)
	)
	(zone
		(layers "In1.Cu" "In2.Cu")
		(hatch none 0.5)
		(connect_pads
			(clearance 0)
		)
		(min_thickness 0.25)
		(keepout
			(tracks not_allowed)
			(vias allowed)
			(pads allowed)
			(copperpour not_allowed)
			(footprints allowed)
		)
		(placement
			(enabled no)
			(sheetname "")
		)
		(fill yes
			(thermal_gap 0.5)
			(thermal_bridge_width 0.5)
			(island_removal_mode 0)
		)
		(polygon
			(pts
				(arc
					(start 424.342306 -287.435036)
					(mid 423.681906 -287.435036)
					(end 424.342306 -287.435036)
				)
			)
		)
	)
	(zone
		(layers "In1.Cu" "In2.Cu")
		(hatch none 0.5)
		(connect_pads
			(clearance 0)
		)
		(min_thickness 0.25)
		(keepout
			(tracks not_allowed)
			(vias allowed)
			(pads allowed)
			(copperpour not_allowed)
			(footprints allowed)
		)
		(placement
			(enabled no)
			(sheetname "")
		)
		(fill yes
			(thermal_gap 0.5)
			(thermal_bridge_width 0.5)
			(island_removal_mode 0)
		)
		(polygon
			(pts
				(arc
					(start 29.582364 -312.935366)
					(mid 28.921964 -312.935366)
					(end 29.582364 -312.935366)
				)
			)
		)
	)
	(zone
		(layers "In1.Cu" "In2.Cu")
		(hatch none 0.5)
		(connect_pads
			(clearance 0)
		)
		(min_thickness 0.25)
		(keepout
			(tracks not_allowed)
			(vias allowed)
			(pads allowed)
			(copperpour not_allowed)
			(footprints allowed)
		)
		(placement
			(enabled no)
			(sheetname "")
		)
		(fill yes
			(thermal_gap 0.5)
			(thermal_bridge_width 0.5)
			(island_removal_mode 0)
		)
		(polygon
			(pts
				(arc
					(start 288.510218 -263.634982)
					(mid 287.849818 -263.634982)
					(end 288.510218 -263.634982)
				)
			)
		)
	)
	(zone
		(layers "In1.Cu" "In2.Cu")
		(hatch none 0.5)
		(connect_pads
			(clearance 0)
		)
		(min_thickness 0.25)
		(keepout
			(tracks not_allowed)
			(vias allowed)
			(pads allowed)
			(copperpour not_allowed)
			(footprints allowed)
		)
		(placement
			(enabled no)
			(sheetname "")
		)
		(fill yes
			(thermal_gap 0.5)
			(thermal_bridge_width 0.5)
			(island_removal_mode 0)
		)
		(polygon
			(pts
				(arc
					(start 22.03831 -266.185396)
					(mid 21.37791 -266.185396)
					(end 22.03831 -266.185396)
				)
			)
		)
	)
	(zone
		(layers "In1.Cu" "In2.Cu")
		(hatch none 0.5)
		(connect_pads
			(clearance 0)
		)
		(min_thickness 0.25)
		(keepout
			(tracks not_allowed)
			(vias allowed)
			(pads allowed)
			(copperpour not_allowed)
			(footprints allowed)
		)
		(placement
			(enabled no)
			(sheetname "")
		)
		(fill yes
			(thermal_gap 0.5)
			(thermal_bridge_width 0.5)
			(island_removal_mode 0)
		)
		(polygon
			(pts
				(arc
					(start 285.066232 -254.284988)
					(mid 284.405832 -254.284988)
					(end 285.066232 -254.284988)
				)
			)
		)
	)
	(zone
		(layers "In1.Cu" "In2.Cu")
		(hatch none 0.5)
		(connect_pads
			(clearance 0)
		)
		(min_thickness 0.25)
		(keepout
			(tracks not_allowed)
			(vias allowed)
			(pads allowed)
			(copperpour not_allowed)
			(footprints allowed)
		)
		(placement
			(enabled no)
			(sheetname "")
		)
		(fill yes
			(thermal_gap 0.5)
			(thermal_bridge_width 0.5)
			(island_removal_mode 0)
		)
		(polygon
			(pts
				(arc
					(start 277.522432 -264.48512)
					(mid 276.862032 -264.48512)
					(end 277.522432 -264.48512)
				)
			)
		)
	)
	(zone
		(layers "In1.Cu" "In2.Cu")
		(hatch none 0.5)
		(connect_pads
			(clearance 0)
		)
		(min_thickness 0.25)
		(keepout
			(tracks not_allowed)
			(vias allowed)
			(pads allowed)
			(copperpour not_allowed)
			(footprints allowed)
		)
		(placement
			(enabled no)
			(sheetname "")
		)
		(fill yes
			(thermal_gap 0.5)
			(thermal_bridge_width 0.5)
			(island_removal_mode 0)
		)
		(polygon
			(pts
				(arc
					(start 69.310504 -370.978684)
					(mid 69.330428 -370.98792)
					(end 69.35216 -370.99113)
				)
				(arc
					(start 69.546724 -370.99113)
					(mid 69.600606 -370.968812)
					(end 69.622924 -370.91493)
				)
				(arc
					(start 69.622924 -370.22913)
					(mid 69.600606 -370.175248)
					(end 69.546724 -370.15293)
				)
				(arc
					(start 69.35216 -370.15293)
					(mid 69.330416 -370.156098)
					(end 69.310504 -370.165376)
				)
				(arc
					(start 69.01434 -370.358162)
					(mid 68.972656 -370.370384)
					(end 68.931028 -370.357908)
				)
				(arc
					(start 68.637404 -370.165376)
					(mid 68.61748 -370.15614)
					(end 68.595748 -370.15293)
				)
				(arc
					(start 68.401184 -370.15293)
					(mid 68.347302 -370.175248)
					(end 68.324984 -370.22913)
				)
				(arc
					(start 68.324984 -370.91493)
					(mid 68.347302 -370.968812)
					(end 68.401184 -370.99113)
				)
				(arc
					(start 68.597018 -370.99113)
					(mid 68.618762 -370.987962)
					(end 68.638674 -370.978684)
				)
				(arc
					(start 68.932298 -370.786152)
					(mid 68.973954 -370.77375)
					(end 69.01561 -370.786152)
				)
			)
		)
	)
	(zone
		(layers "In1.Cu" "In2.Cu")
		(hatch none 0.5)
		(connect_pads
			(clearance 0)
		)
		(min_thickness 0.25)
		(keepout
			(tracks not_allowed)
			(vias allowed)
			(pads allowed)
			(copperpour not_allowed)
			(footprints allowed)
		)
		(placement
			(enabled no)
			(sheetname "")
		)
		(fill yes
			(thermal_gap 0.5)
			(thermal_bridge_width 0.5)
			(island_removal_mode 0)
		)
		(polygon
			(pts
				(arc
					(start 296.054272 -253.435104)
					(mid 295.393872 -253.435104)
					(end 296.054272 -253.435104)
				)
			)
		)
	)
	(zone
		(layers "In1.Cu" "In2.Cu")
		(hatch none 0.5)
		(connect_pads
			(clearance 0)
		)
		(min_thickness 0.25)
		(keepout
			(tracks not_allowed)
			(vias allowed)
			(pads allowed)
			(copperpour not_allowed)
			(footprints allowed)
		)
		(placement
			(enabled no)
			(sheetname "")
		)
		(fill yes
			(thermal_gap 0.5)
			(thermal_bridge_width 0.5)
			(island_removal_mode 0)
		)
		(polygon
			(pts
				(arc
					(start 17.938242 -310.385206)
					(mid 17.277842 -310.385206)
					(end 17.938242 -310.385206)
				)
			)
		)
	)
	(zone
		(layers "In1.Cu" "In2.Cu")
		(hatch none 0.5)
		(connect_pads
			(clearance 0)
		)
		(min_thickness 0.25)
		(keepout
			(tracks not_allowed)
			(vias allowed)
			(pads allowed)
			(copperpour not_allowed)
			(footprints allowed)
		)
		(placement
			(enabled no)
			(sheetname "")
		)
		(fill yes
			(thermal_gap 0.5)
			(thermal_bridge_width 0.5)
			(island_removal_mode 0)
		)
		(polygon
			(pts
				(arc
					(start 191.490346 -242.385342)
					(mid 190.829946 -242.385342)
					(end 191.490346 -242.385342)
				)
			)
		)
	)
	(zone
		(layers "In1.Cu" "In2.Cu")
		(hatch none 0.5)
		(connect_pads
			(clearance 0)
		)
		(min_thickness 0.25)
		(keepout
			(tracks not_allowed)
			(vias allowed)
			(pads allowed)
			(copperpour not_allowed)
			(footprints allowed)
		)
		(placement
			(enabled no)
			(sheetname "")
		)
		(fill yes
			(thermal_gap 0.5)
			(thermal_bridge_width 0.5)
			(island_removal_mode 0)
		)
		(polygon
			(pts
				(arc
					(start 285.066232 -227.085144)
					(mid 284.405832 -227.085144)
					(end 285.066232 -227.085144)
				)
			)
		)
	)
	(zone
		(layers "In1.Cu" "In2.Cu")
		(hatch none 0.5)
		(connect_pads
			(clearance 0)
		)
		(min_thickness 0.25)
		(keepout
			(tracks not_allowed)
			(vias allowed)
			(pads allowed)
			(copperpour not_allowed)
			(footprints allowed)
		)
		(placement
			(enabled no)
			(sheetname "")
		)
		(fill yes
			(thermal_gap 0.5)
			(thermal_bridge_width 0.5)
			(island_removal_mode 0)
		)
		(polygon
			(pts
				(arc
					(start 126.199646 -370.978684)
					(mid 126.21957 -370.98792)
					(end 126.241302 -370.99113)
				)
				(arc
					(start 126.435866 -370.99113)
					(mid 126.489748 -370.968812)
					(end 126.512066 -370.91493)
				)
				(arc
					(start 126.512066 -370.22913)
					(mid 126.489748 -370.175248)
					(end 126.435866 -370.15293)
				)
				(arc
					(start 126.241302 -370.15293)
					(mid 126.219558 -370.156098)
					(end 126.199646 -370.165376)
				)
				(arc
					(start 125.903482 -370.358162)
					(mid 125.861798 -370.370384)
					(end 125.82017 -370.357908)
				)
				(arc
					(start 125.526546 -370.165376)
					(mid 125.506622 -370.15614)
					(end 125.48489 -370.15293)
				)
				(arc
					(start 125.290326 -370.15293)
					(mid 125.236444 -370.175248)
					(end 125.214126 -370.22913)
				)
				(arc
					(start 125.214126 -370.91493)
					(mid 125.236444 -370.968812)
					(end 125.290326 -370.99113)
				)
				(arc
					(start 125.48616 -370.99113)
					(mid 125.507904 -370.987962)
					(end 125.527816 -370.978684)
				)
				(arc
					(start 125.82144 -370.786152)
					(mid 125.863096 -370.77375)
					(end 125.904752 -370.786152)
				)
			)
		)
	)
	(zone
		(layers "In1.Cu" "In2.Cu")
		(hatch none 0.5)
		(connect_pads
			(clearance 0)
		)
		(min_thickness 0.25)
		(keepout
			(tracks not_allowed)
			(vias allowed)
			(pads allowed)
			(copperpour not_allowed)
			(footprints allowed)
		)
		(placement
			(enabled no)
			(sheetname "")
		)
		(fill yes
			(thermal_gap 0.5)
			(thermal_bridge_width 0.5)
			(island_removal_mode 0)
		)
		(polygon
			(pts
				(arc
					(start 280.966164 -250.03506)
					(mid 280.305764 -250.03506)
					(end 280.966164 -250.03506)
				)
			)
		)
	)
	(zone
		(layers "In1.Cu" "In2.Cu")
		(hatch none 0.5)
		(connect_pads
			(clearance 0)
		)
		(min_thickness 0.25)
		(keepout
			(tracks not_allowed)
			(vias allowed)
			(pads allowed)
			(copperpour not_allowed)
			(footprints allowed)
		)
		(placement
			(enabled no)
			(sheetname "")
		)
		(fill yes
			(thermal_gap 0.5)
			(thermal_bridge_width 0.5)
			(island_removal_mode 0)
		)
		(polygon
			(pts
				(arc
					(start 296.054272 -302.73498)
					(mid 295.393872 -302.73498)
					(end 296.054272 -302.73498)
				)
			)
		)
	)
	(zone
		(layers "In1.Cu" "In2.Cu")
		(hatch none 0.5)
		(connect_pads
			(clearance 0)
		)
		(min_thickness 0.25)
		(keepout
			(tracks not_allowed)
			(vias allowed)
			(pads allowed)
			(copperpour not_allowed)
			(footprints allowed)
		)
		(placement
			(enabled no)
			(sheetname "")
		)
		(fill yes
			(thermal_gap 0.5)
			(thermal_bridge_width 0.5)
			(island_removal_mode 0)
		)
		(polygon
			(pts
				(arc
					(start 17.938242 -313.78525)
					(mid 17.277842 -313.78525)
					(end 17.938242 -313.78525)
				)
			)
		)
	)
	(zone
		(layers "In1.Cu" "In2.Cu")
		(hatch none 0.5)
		(connect_pads
			(clearance 0)
		)
		(min_thickness 0.25)
		(keepout
			(tracks not_allowed)
			(vias allowed)
			(pads allowed)
			(copperpour not_allowed)
			(footprints allowed)
		)
		(placement
			(enabled no)
			(sheetname "")
		)
		(fill yes
			(thermal_gap 0.5)
			(thermal_bridge_width 0.5)
			(island_removal_mode 0)
		)
		(polygon
			(pts
				(arc
					(start 202.478132 -301.035212)
					(mid 201.817732 -301.035212)
					(end 202.478132 -301.035212)
				)
			)
		)
	)
	(zone
		(layers "In1.Cu" "In2.Cu")
		(hatch none 0.5)
		(connect_pads
			(clearance 0)
		)
		(min_thickness 0.25)
		(keepout
			(tracks not_allowed)
			(vias allowed)
			(pads allowed)
			(copperpour not_allowed)
			(footprints allowed)
		)
		(placement
			(enabled no)
			(sheetname "")
		)
		(fill yes
			(thermal_gap 0.5)
			(thermal_bridge_width 0.5)
			(island_removal_mode 0)
		)
		(polygon
			(pts
				(arc
					(start 424.342306 -240.685066)
					(mid 423.681906 -240.685066)
					(end 424.342306 -240.685066)
				)
			)
		)
	)
	(zone
		(layers "In1.Cu" "In2.Cu")
		(hatch none 0.5)
		(connect_pads
			(clearance 0)
		)
		(min_thickness 0.25)
		(keepout
			(tracks not_allowed)
			(vias allowed)
			(pads allowed)
			(copperpour not_allowed)
			(footprints allowed)
		)
		(placement
			(enabled no)
			(sheetname "")
		)
		(fill yes
			(thermal_gap 0.5)
			(thermal_bridge_width 0.5)
			(island_removal_mode 0)
		)
		(polygon
			(pts
				(arc
					(start 172.30217 -267.03528)
					(mid 171.64177 -267.03528)
					(end 172.30217 -267.03528)
				)
			)
		)
	)
	(zone
		(layers "In1.Cu" "In2.Cu")
		(hatch none 0.5)
		(connect_pads
			(clearance 0)
		)
		(min_thickness 0.25)
		(keepout
			(tracks not_allowed)
			(vias allowed)
			(pads allowed)
			(copperpour not_allowed)
			(footprints allowed)
		)
		(placement
			(enabled no)
			(sheetname "")
		)
		(fill yes
			(thermal_gap 0.5)
			(thermal_bridge_width 0.5)
			(island_removal_mode 0)
		)
		(polygon
			(pts
				(arc
					(start 202.478132 -314.635388)
					(mid 201.817732 -314.635388)
					(end 202.478132 -314.635388)
				)
			)
		)
	)
	(zone
		(layers "In1.Cu" "In2.Cu")
		(hatch none 0.5)
		(connect_pads
			(clearance 0)
		)
		(min_thickness 0.25)
		(keepout
			(tracks not_allowed)
			(vias allowed)
			(pads allowed)
			(copperpour not_allowed)
			(footprints allowed)
		)
		(placement
			(enabled no)
			(sheetname "")
		)
		(fill yes
			(thermal_gap 0.5)
			(thermal_bridge_width 0.5)
			(island_removal_mode 0)
		)
		(polygon
			(pts
				(arc
					(start 446.974468 -304.435002)
					(mid 446.314068 -304.435002)
					(end 446.974468 -304.435002)
				)
			)
		)
	)
	(zone
		(layers "In1.Cu" "In2.Cu")
		(hatch none 0.5)
		(connect_pads
			(clearance 0)
		)
		(min_thickness 0.25)
		(keepout
			(tracks not_allowed)
			(vias allowed)
			(pads allowed)
			(copperpour not_allowed)
			(footprints allowed)
		)
		(placement
			(enabled no)
			(sheetname "")
		)
		(fill yes
			(thermal_gap 0.5)
			(thermal_bridge_width 0.5)
			(island_removal_mode 0)
		)
		(polygon
			(pts
				(arc
					(start 194.934332 -226.23526)
					(mid 194.273932 -226.23526)
					(end 194.934332 -226.23526)
				)
			)
		)
	)
	(zone
		(layers "In1.Cu" "In2.Cu")
		(hatch none 0.5)
		(connect_pads
			(clearance 0)
		)
		(min_thickness 0.25)
		(keepout
			(tracks not_allowed)
			(vias allowed)
			(pads allowed)
			(copperpour not_allowed)
			(footprints allowed)
		)
		(placement
			(enabled no)
			(sheetname "")
		)
		(fill yes
			(thermal_gap 0.5)
			(thermal_bridge_width 0.5)
			(island_removal_mode 0)
		)
		(polygon
			(pts
				(arc
					(start 454.518268 -294.235124)
					(mid 453.857868 -294.235124)
					(end 454.518268 -294.235124)
				)
			)
		)
	)
	(zone
		(layers "In1.Cu" "In2.Cu")
		(hatch none 0.5)
		(connect_pads
			(clearance 0)
		)
		(min_thickness 0.25)
		(keepout
			(tracks not_allowed)
			(vias allowed)
			(pads allowed)
			(copperpour not_allowed)
			(footprints allowed)
		)
		(placement
			(enabled no)
			(sheetname "")
		)
		(fill yes
			(thermal_gap 0.5)
			(thermal_bridge_width 0.5)
			(island_removal_mode 0)
		)
		(polygon
			(pts
				(arc
					(start 133.056376 -408.860244)
					(mid 133.078694 -408.914126)
					(end 133.132576 -408.936444)
				)
				(arc
					(start 133.328156 -408.936444)
					(mid 133.350032 -408.933312)
					(end 133.370066 -408.923998)
				)
				(arc
					(start 133.66369 -408.731466)
					(mid 133.705346 -408.719064)
					(end 133.747002 -408.731466)
				)
				(arc
					(start 134.041896 -408.923998)
					(mid 134.06182 -408.933234)
					(end 134.083552 -408.936444)
				)
				(arc
					(start 134.278116 -408.936444)
					(mid 134.331998 -408.914126)
					(end 134.354316 -408.860244)
				)
				(arc
					(start 134.354316 -408.174444)
					(mid 134.331998 -408.120562)
					(end 134.278116 -408.098244)
				)
				(arc
					(start 134.083552 -408.098244)
					(mid 134.061808 -408.101412)
					(end 134.041896 -408.11069)
				)
				(arc
					(start 133.745732 -408.303476)
					(mid 133.704048 -408.315698)
					(end 133.66242 -408.303222)
				)
				(arc
					(start 133.368796 -408.11069)
					(mid 133.348872 -408.101454)
					(end 133.32714 -408.098244)
				)
				(arc
					(start 133.132576 -408.098244)
					(mid 133.078694 -408.120562)
					(end 133.056376 -408.174444)
				)
			)
		)
	)
	(zone
		(layers "In1.Cu" "In2.Cu")
		(hatch none 0.5)
		(connect_pads
			(clearance 0)
		)
		(min_thickness 0.25)
		(keepout
			(tracks not_allowed)
			(vias allowed)
			(pads allowed)
			(copperpour not_allowed)
			(footprints allowed)
		)
		(placement
			(enabled no)
			(sheetname "")
		)
		(fill yes
			(thermal_gap 0.5)
			(thermal_bridge_width 0.5)
			(island_removal_mode 0)
		)
		(polygon
			(pts
				(arc
					(start 25.482296 -239.835436)
					(mid 24.821896 -239.835436)
					(end 25.482296 -239.835436)
				)
			)
		)
	)
	(zone
		(layers "In1.Cu" "In2.Cu")
		(hatch none 0.5)
		(connect_pads
			(clearance 0)
		)
		(min_thickness 0.25)
		(keepout
			(tracks not_allowed)
			(vias allowed)
			(pads allowed)
			(copperpour not_allowed)
			(footprints allowed)
		)
		(placement
			(enabled no)
			(sheetname "")
		)
		(fill yes
			(thermal_gap 0.5)
			(thermal_bridge_width 0.5)
			(island_removal_mode 0)
		)
		(polygon
			(pts
				(arc
					(start 427.786292 -263.634982)
					(mid 427.125892 -263.634982)
					(end 427.786292 -263.634982)
				)
			)
		)
	)
	(zone
		(layers "In1.Cu" "In2.Cu")
		(hatch none 0.5)
		(connect_pads
			(clearance 0)
		)
		(min_thickness 0.25)
		(keepout
			(tracks not_allowed)
			(vias allowed)
			(pads allowed)
			(copperpour not_allowed)
			(footprints allowed)
		)
		(placement
			(enabled no)
			(sheetname "")
		)
		(fill yes
			(thermal_gap 0.5)
			(thermal_bridge_width 0.5)
			(island_removal_mode 0)
		)
		(polygon
			(pts
				(arc
					(start 179.846224 -302.735234)
					(mid 179.185824 -302.735234)
					(end 179.846224 -302.735234)
				)
			)
		)
	)
	(zone
		(layers "In1.Cu" "In2.Cu")
		(hatch none 0.5)
		(connect_pads
			(clearance 0)
		)
		(min_thickness 0.25)
		(keepout
			(tracks not_allowed)
			(vias allowed)
			(pads allowed)
			(copperpour not_allowed)
			(footprints allowed)
		)
		(placement
			(enabled no)
			(sheetname "")
		)
		(fill yes
			(thermal_gap 0.5)
			(thermal_bridge_width 0.5)
			(island_removal_mode 0)
		)
		(polygon
			(pts
				(arc
					(start 179.846224 -316.33541)
					(mid 179.185824 -316.33541)
					(end 179.846224 -316.33541)
				)
			)
		)
	)
	(zone
		(layers "In1.Cu" "In2.Cu")
		(hatch none 0.5)
		(connect_pads
			(clearance 0)
		)
		(min_thickness 0.25)
		(keepout
			(tracks not_allowed)
			(vias allowed)
			(pads allowed)
			(copperpour not_allowed)
			(footprints allowed)
		)
		(placement
			(enabled no)
			(sheetname "")
		)
		(fill yes
			(thermal_gap 0.5)
			(thermal_bridge_width 0.5)
			(island_removal_mode 0)
		)
		(polygon
			(pts
				(arc
					(start 454.518268 -304.435002)
					(mid 453.857868 -304.435002)
					(end 454.518268 -304.435002)
				)
			)
		)
	)
	(zone
		(layers "In1.Cu" "In2.Cu")
		(hatch none 0.5)
		(connect_pads
			(clearance 0)
		)
		(min_thickness 0.25)
		(keepout
			(tracks not_allowed)
			(vias allowed)
			(pads allowed)
			(copperpour not_allowed)
			(footprints allowed)
		)
		(placement
			(enabled no)
			(sheetname "")
		)
		(fill yes
			(thermal_gap 0.5)
			(thermal_bridge_width 0.5)
			(island_removal_mode 0)
		)
		(polygon
			(pts
				(arc
					(start 280.966164 -274.684998)
					(mid 280.305764 -274.684998)
					(end 280.966164 -274.684998)
				)
			)
		)
	)
	(zone
		(layers "In1.Cu" "In2.Cu")
		(hatch none 0.5)
		(connect_pads
			(clearance 0)
		)
		(min_thickness 0.25)
		(keepout
			(tracks not_allowed)
			(vias allowed)
			(pads allowed)
			(copperpour not_allowed)
			(footprints allowed)
		)
		(placement
			(enabled no)
			(sheetname "")
		)
		(fill yes
			(thermal_gap 0.5)
			(thermal_bridge_width 0.5)
			(island_removal_mode 0)
		)
		(polygon
			(pts
				(arc
					(start 366.883442 -381.824484)
					(mid 366.903366 -381.83372)
					(end 366.925098 -381.83693)
				)
				(arc
					(start 367.119662 -381.83693)
					(mid 367.173544 -381.814612)
					(end 367.195862 -381.76073)
				)
				(arc
					(start 367.195862 -381.07493)
					(mid 367.173544 -381.021048)
					(end 367.119662 -380.99873)
				)
				(arc
					(start 366.925098 -380.99873)
					(mid 366.903354 -381.001898)
					(end 366.883442 -381.011176)
				)
				(arc
					(start 366.587278 -381.203962)
					(mid 366.545594 -381.216184)
					(end 366.503966 -381.203708)
				)
				(arc
					(start 366.210342 -381.011176)
					(mid 366.190418 -381.00194)
					(end 366.168686 -380.99873)
				)
				(arc
					(start 365.974122 -380.99873)
					(mid 365.92024 -381.021048)
					(end 365.897922 -381.07493)
				)
				(arc
					(start 365.897922 -381.76073)
					(mid 365.92024 -381.814612)
					(end 365.974122 -381.83693)
				)
				(arc
					(start 366.169956 -381.83693)
					(mid 366.1917 -381.833762)
					(end 366.211612 -381.824484)
				)
				(arc
					(start 366.505236 -381.631952)
					(mid 366.546892 -381.61955)
					(end 366.588548 -381.631952)
				)
			)
		)
	)
	(zone
		(layers "In1.Cu" "In2.Cu")
		(hatch none 0.5)
		(connect_pads
			(clearance 0)
		)
		(min_thickness 0.25)
		(keepout
			(tracks not_allowed)
			(vias allowed)
			(pads allowed)
			(copperpour not_allowed)
			(footprints allowed)
		)
		(placement
			(enabled no)
			(sheetname "")
		)
		(fill yes
			(thermal_gap 0.5)
			(thermal_bridge_width 0.5)
			(island_removal_mode 0)
		)
		(polygon
			(pts
				(arc
					(start 446.974468 -240.685066)
					(mid 446.314068 -240.685066)
					(end 446.974468 -240.685066)
				)
			)
		)
	)
	(zone
		(layers "In1.Cu" "In2.Cu")
		(hatch none 0.5)
		(connect_pads
			(clearance 0)
		)
		(min_thickness 0.25)
		(keepout
			(tracks not_allowed)
			(vias allowed)
			(pads allowed)
			(copperpour not_allowed)
			(footprints allowed)
		)
		(placement
			(enabled no)
			(sheetname "")
		)
		(fill yes
			(thermal_gap 0.5)
			(thermal_bridge_width 0.5)
			(island_removal_mode 0)
		)
		(polygon
			(pts
				(arc
					(start 439.430414 -279.785064)
					(mid 438.770014 -279.785064)
					(end 439.430414 -279.785064)
				)
			)
		)
	)
	(zone
		(layers "In1.Cu" "In2.Cu")
		(hatch none 0.5)
		(connect_pads
			(clearance 0)
		)
		(min_thickness 0.25)
		(keepout
			(tracks not_allowed)
			(vias allowed)
			(pads allowed)
			(copperpour not_allowed)
			(footprints allowed)
		)
		(placement
			(enabled no)
			(sheetname "")
		)
		(fill yes
			(thermal_gap 0.5)
			(thermal_bridge_width 0.5)
			(island_removal_mode 0)
		)
		(polygon
			(pts
				(arc
					(start 280.966164 -211.784946)
					(mid 280.305764 -211.784946)
					(end 280.966164 -211.784946)
				)
			)
		)
	)
	(zone
		(layers "In1.Cu" "In2.Cu")
		(hatch none 0.5)
		(connect_pads
			(clearance 0)
		)
		(min_thickness 0.25)
		(keepout
			(tracks not_allowed)
			(vias allowed)
			(pads allowed)
			(copperpour not_allowed)
			(footprints allowed)
		)
		(placement
			(enabled no)
			(sheetname "")
		)
		(fill yes
			(thermal_gap 0.5)
			(thermal_bridge_width 0.5)
			(island_removal_mode 0)
		)
		(polygon
			(pts
				(arc
					(start 179.846224 -265.335258)
					(mid 179.185824 -265.335258)
					(end 179.846224 -265.335258)
				)
			)
		)
	)
	(zone
		(layers "In1.Cu" "In2.Cu")
		(hatch none 0.5)
		(connect_pads
			(clearance 0)
		)
		(min_thickness 0.25)
		(keepout
			(tracks not_allowed)
			(vias allowed)
			(pads allowed)
			(copperpour not_allowed)
			(footprints allowed)
		)
		(placement
			(enabled no)
			(sheetname "")
		)
		(fill yes
			(thermal_gap 0.5)
			(thermal_bridge_width 0.5)
			(island_removal_mode 0)
		)
		(polygon
			(pts
				(arc
					(start 44.670218 -244.085364)
					(mid 44.009818 -244.085364)
					(end 44.670218 -244.085364)
				)
			)
		)
	)
	(zone
		(layers "In1.Cu" "In2.Cu")
		(hatch none 0.5)
		(connect_pads
			(clearance 0)
		)
		(min_thickness 0.25)
		(keepout
			(tracks not_allowed)
			(vias allowed)
			(pads allowed)
			(copperpour not_allowed)
			(footprints allowed)
		)
		(placement
			(enabled no)
			(sheetname "")
		)
		(fill yes
			(thermal_gap 0.5)
			(thermal_bridge_width 0.5)
			(island_removal_mode 0)
		)
		(polygon
			(pts
				(arc
					(start 176.402238 -294.235378)
					(mid 175.741838 -294.235378)
					(end 176.402238 -294.235378)
				)
			)
		)
	)
	(zone
		(layers "In1.Cu" "In2.Cu")
		(hatch none 0.5)
		(connect_pads
			(clearance 0)
		)
		(min_thickness 0.25)
		(keepout
			(tracks not_allowed)
			(vias allowed)
			(pads allowed)
			(copperpour not_allowed)
			(footprints allowed)
		)
		(placement
			(enabled no)
			(sheetname "")
		)
		(fill yes
			(thermal_gap 0.5)
			(thermal_bridge_width 0.5)
			(island_removal_mode 0)
		)
		(polygon
			(pts
				(arc
					(start 431.88636 -266.185142)
					(mid 431.22596 -266.185142)
					(end 431.88636 -266.185142)
				)
			)
		)
	)
	(zone
		(layers "In1.Cu" "In2.Cu")
		(hatch none 0.5)
		(connect_pads
			(clearance 0)
		)
		(min_thickness 0.25)
		(keepout
			(tracks not_allowed)
			(vias allowed)
			(pads allowed)
			(copperpour not_allowed)
			(footprints allowed)
		)
		(placement
			(enabled no)
			(sheetname "")
		)
		(fill yes
			(thermal_gap 0.5)
			(thermal_bridge_width 0.5)
			(island_removal_mode 0)
		)
		(polygon
			(pts
				(arc
					(start 292.610286 -296.78503)
					(mid 291.949886 -296.78503)
					(end 292.610286 -296.78503)
				)
			)
		)
	)
	(zone
		(layers "In1.Cu" "In2.Cu")
		(hatch none 0.5)
		(connect_pads
			(clearance 0)
		)
		(min_thickness 0.25)
		(keepout
			(tracks not_allowed)
			(vias allowed)
			(pads allowed)
			(copperpour not_allowed)
			(footprints allowed)
		)
		(placement
			(enabled no)
			(sheetname "")
		)
		(fill yes
			(thermal_gap 0.5)
			(thermal_bridge_width 0.5)
			(island_removal_mode 0)
		)
		(polygon
			(pts
				(arc
					(start 44.670218 -300.185328)
					(mid 44.009818 -300.185328)
					(end 44.670218 -300.185328)
				)
			)
		)
	)
	(zone
		(layers "In1.Cu" "In2.Cu")
		(hatch none 0.5)
		(connect_pads
			(clearance 0)
		)
		(min_thickness 0.25)
		(keepout
			(tracks not_allowed)
			(vias allowed)
			(pads allowed)
			(copperpour not_allowed)
			(footprints allowed)
		)
		(placement
			(enabled no)
			(sheetname "")
		)
		(fill yes
			(thermal_gap 0.5)
			(thermal_bridge_width 0.5)
			(island_removal_mode 0)
		)
		(polygon
			(pts
				(arc
					(start 172.30217 -229.635304)
					(mid 171.64177 -229.635304)
					(end 172.30217 -229.635304)
				)
			)
		)
	)
	(zone
		(layers "In1.Cu" "In2.Cu")
		(hatch none 0.5)
		(connect_pads
			(clearance 0)
		)
		(min_thickness 0.25)
		(keepout
			(tracks not_allowed)
			(vias allowed)
			(pads allowed)
			(copperpour not_allowed)
			(footprints allowed)
		)
		(placement
			(enabled no)
			(sheetname "")
		)
		(fill yes
			(thermal_gap 0.5)
			(thermal_bridge_width 0.5)
			(island_removal_mode 0)
		)
		(polygon
			(pts
				(arc
					(start 296.054272 -202.434952)
					(mid 295.393872 -202.434952)
					(end 296.054272 -202.434952)
				)
			)
		)
	)
	(zone
		(layers "In1.Cu" "In2.Cu")
		(hatch none 0.5)
		(connect_pads
			(clearance 0)
		)
		(min_thickness 0.25)
		(keepout
			(tracks not_allowed)
			(vias allowed)
			(pads allowed)
			(copperpour not_allowed)
			(footprints allowed)
		)
		(placement
			(enabled no)
			(sheetname "")
		)
		(fill yes
			(thermal_gap 0.5)
			(thermal_bridge_width 0.5)
			(island_removal_mode 0)
		)
		(polygon
			(pts
				(arc
					(start 420.242238 -280.634948)
					(mid 419.581838 -280.634948)
					(end 420.242238 -280.634948)
				)
			)
		)
	)
	(zone
		(layers "In1.Cu" "In2.Cu")
		(hatch none 0.5)
		(connect_pads
			(clearance 0)
		)
		(min_thickness 0.25)
		(keepout
			(tracks not_allowed)
			(vias allowed)
			(pads allowed)
			(copperpour not_allowed)
			(footprints allowed)
		)
		(placement
			(enabled no)
			(sheetname "")
		)
		(fill yes
			(thermal_gap 0.5)
			(thermal_bridge_width 0.5)
			(island_removal_mode 0)
		)
		(polygon
			(pts
				(arc
					(start 69.019674 -408.860244)
					(mid 69.041992 -408.914126)
					(end 69.095874 -408.936444)
				)
				(arc
					(start 69.291454 -408.936444)
					(mid 69.31333 -408.933312)
					(end 69.333364 -408.923998)
				)
				(arc
					(start 69.626988 -408.731466)
					(mid 69.668644 -408.719064)
					(end 69.7103 -408.731466)
				)
				(arc
					(start 70.005194 -408.923998)
					(mid 70.025118 -408.933234)
					(end 70.04685 -408.936444)
				)
				(arc
					(start 70.241414 -408.936444)
					(mid 70.295296 -408.914126)
					(end 70.317614 -408.860244)
				)
				(arc
					(start 70.317614 -408.174444)
					(mid 70.295296 -408.120562)
					(end 70.241414 -408.098244)
				)
				(arc
					(start 70.04685 -408.098244)
					(mid 70.025106 -408.101412)
					(end 70.005194 -408.11069)
				)
				(arc
					(start 69.70903 -408.303476)
					(mid 69.667346 -408.315698)
					(end 69.625718 -408.303222)
				)
				(arc
					(start 69.332094 -408.11069)
					(mid 69.31217 -408.101454)
					(end 69.290438 -408.098244)
				)
				(arc
					(start 69.095874 -408.098244)
					(mid 69.041992 -408.120562)
					(end 69.019674 -408.174444)
				)
			)
		)
	)
	(zone
		(layers "In1.Cu" "In2.Cu")
		(hatch none 0.5)
		(connect_pads
			(clearance 0)
		)
		(min_thickness 0.25)
		(keepout
			(tracks not_allowed)
			(vias allowed)
			(pads allowed)
			(copperpour not_allowed)
			(footprints allowed)
		)
		(placement
			(enabled no)
			(sheetname "")
		)
		(fill yes
			(thermal_gap 0.5)
			(thermal_bridge_width 0.5)
			(island_removal_mode 0)
		)
		(polygon
			(pts
				(arc
					(start 273.422364 -246.635016)
					(mid 272.761964 -246.635016)
					(end 273.422364 -246.635016)
				)
			)
		)
	)
	(zone
		(layers "In1.Cu" "In2.Cu")
		(hatch none 0.5)
		(connect_pads
			(clearance 0)
		)
		(min_thickness 0.25)
		(keepout
			(tracks not_allowed)
			(vias allowed)
			(pads allowed)
			(copperpour not_allowed)
			(footprints allowed)
		)
		(placement
			(enabled no)
			(sheetname "")
		)
		(fill yes
			(thermal_gap 0.5)
			(thermal_bridge_width 0.5)
			(island_removal_mode 0)
		)
		(polygon
			(pts
				(arc
					(start 277.522432 -306.135024)
					(mid 276.862032 -306.135024)
					(end 277.522432 -306.135024)
				)
			)
		)
	)
	(zone
		(layers "In1.Cu" "In2.Cu")
		(hatch none 0.5)
		(connect_pads
			(clearance 0)
		)
		(min_thickness 0.25)
		(keepout
			(tracks not_allowed)
			(vias allowed)
			(pads allowed)
			(copperpour not_allowed)
			(footprints allowed)
		)
		(placement
			(enabled no)
			(sheetname "")
		)
		(fill yes
			(thermal_gap 0.5)
			(thermal_bridge_width 0.5)
			(island_removal_mode 0)
		)
		(polygon
			(pts
				(arc
					(start 450.4182 -238.985044)
					(mid 449.7578 -238.985044)
					(end 450.4182 -238.985044)
				)
			)
		)
	)
	(zone
		(layers "In1.Cu" "In2.Cu")
		(hatch none 0.5)
		(connect_pads
			(clearance 0)
		)
		(min_thickness 0.25)
		(keepout
			(tracks not_allowed)
			(vias allowed)
			(pads allowed)
			(copperpour not_allowed)
			(footprints allowed)
		)
		(placement
			(enabled no)
			(sheetname "")
		)
		(fill yes
			(thermal_gap 0.5)
			(thermal_bridge_width 0.5)
			(island_removal_mode 0)
		)
		(polygon
			(pts
				(arc
					(start 420.242238 -207.535018)
					(mid 419.581838 -207.535018)
					(end 420.242238 -207.535018)
				)
			)
		)
	)
	(zone
		(layers "In1.Cu" "In2.Cu")
		(hatch none 0.5)
		(connect_pads
			(clearance 0)
		)
		(min_thickness 0.25)
		(keepout
			(tracks not_allowed)
			(vias allowed)
			(pads allowed)
			(copperpour not_allowed)
			(footprints allowed)
		)
		(placement
			(enabled no)
			(sheetname "")
		)
		(fill yes
			(thermal_gap 0.5)
			(thermal_bridge_width 0.5)
			(island_removal_mode 0)
		)
		(polygon
			(pts
				(arc
					(start 37.126164 -201.585322)
					(mid 36.465764 -201.585322)
					(end 37.126164 -201.585322)
				)
			)
		)
	)
	(zone
		(layers "In1.Cu" "In2.Cu")
		(hatch none 0.5)
		(connect_pads
			(clearance 0)
		)
		(min_thickness 0.25)
		(keepout
			(tracks not_allowed)
			(vias allowed)
			(pads allowed)
			(copperpour not_allowed)
			(footprints allowed)
		)
		(placement
			(enabled no)
			(sheetname "")
		)
		(fill yes
			(thermal_gap 0.5)
			(thermal_bridge_width 0.5)
			(island_removal_mode 0)
		)
		(polygon
			(pts
				(arc
					(start 420.242238 -201.585068)
					(mid 419.581838 -201.585068)
					(end 420.242238 -201.585068)
				)
			)
		)
	)
	(zone
		(layers "In1.Cu" "In2.Cu")
		(hatch none 0.5)
		(connect_pads
			(clearance 0)
		)
		(min_thickness 0.25)
		(keepout
			(tracks not_allowed)
			(vias allowed)
			(pads allowed)
			(copperpour not_allowed)
			(footprints allowed)
		)
		(placement
			(enabled no)
			(sheetname "")
		)
		(fill yes
			(thermal_gap 0.5)
			(thermal_bridge_width 0.5)
			(island_removal_mode 0)
		)
		(polygon
			(pts
				(arc
					(start 48.114204 -251.735336)
					(mid 47.453804 -251.735336)
					(end 48.114204 -251.735336)
				)
			)
		)
	)
	(zone
		(layers "In1.Cu" "In2.Cu")
		(hatch none 0.5)
		(connect_pads
			(clearance 0)
		)
		(min_thickness 0.25)
		(keepout
			(tracks not_allowed)
			(vias allowed)
			(pads allowed)
			(copperpour not_allowed)
			(footprints allowed)
		)
		(placement
			(enabled no)
			(sheetname "")
		)
		(fill yes
			(thermal_gap 0.5)
			(thermal_bridge_width 0.5)
			(island_removal_mode 0)
		)
		(polygon
			(pts
				(arc
					(start 292.610286 -300.185074)
					(mid 291.949886 -300.185074)
					(end 292.610286 -300.185074)
				)
			)
		)
	)
	(zone
		(layers "In1.Cu" "In2.Cu")
		(hatch none 0.5)
		(connect_pads
			(clearance 0)
		)
		(min_thickness 0.25)
		(keepout
			(tracks not_allowed)
			(vias allowed)
			(pads allowed)
			(copperpour not_allowed)
			(footprints allowed)
		)
		(placement
			(enabled no)
			(sheetname "")
		)
		(fill yes
			(thermal_gap 0.5)
			(thermal_bridge_width 0.5)
			(island_removal_mode 0)
		)
		(polygon
			(pts
				(arc
					(start 300.15434 -303.585118)
					(mid 299.49394 -303.585118)
					(end 300.15434 -303.585118)
				)
			)
		)
	)
	(zone
		(layers "In1.Cu" "In2.Cu")
		(hatch none 0.5)
		(connect_pads
			(clearance 0)
		)
		(min_thickness 0.25)
		(keepout
			(tracks not_allowed)
			(vias allowed)
			(pads allowed)
			(copperpour not_allowed)
			(footprints allowed)
		)
		(placement
			(enabled no)
			(sheetname "")
		)
		(fill yes
			(thermal_gap 0.5)
			(thermal_bridge_width 0.5)
			(island_removal_mode 0)
		)
		(polygon
			(pts
				(arc
					(start 194.934332 -308.685438)
					(mid 194.273932 -308.685438)
					(end 194.934332 -308.685438)
				)
			)
		)
	)
	(zone
		(layers "In1.Cu" "In2.Cu")
		(hatch none 0.5)
		(connect_pads
			(clearance 0)
		)
		(min_thickness 0.25)
		(keepout
			(tracks not_allowed)
			(vias allowed)
			(pads allowed)
			(copperpour not_allowed)
			(footprints allowed)
		)
		(placement
			(enabled no)
			(sheetname "")
		)
		(fill yes
			(thermal_gap 0.5)
			(thermal_bridge_width 0.5)
			(island_removal_mode 0)
		)
		(polygon
			(pts
				(arc
					(start 435.330346 -227.935028)
					(mid 434.669946 -227.935028)
					(end 435.330346 -227.935028)
				)
			)
		)
	)
	(zone
		(layers "In1.Cu" "In2.Cu")
		(hatch none 0.5)
		(connect_pads
			(clearance 0)
		)
		(min_thickness 0.25)
		(keepout
			(tracks not_allowed)
			(vias allowed)
			(pads allowed)
			(copperpour not_allowed)
			(footprints allowed)
		)
		(placement
			(enabled no)
			(sheetname "")
		)
		(fill yes
			(thermal_gap 0.5)
			(thermal_bridge_width 0.5)
			(island_removal_mode 0)
		)
		(polygon
			(pts
				(arc
					(start 176.402238 -229.635304)
					(mid 175.741838 -229.635304)
					(end 176.402238 -229.635304)
				)
			)
		)
	)
	(zone
		(layers "In1.Cu" "In2.Cu")
		(hatch none 0.5)
		(connect_pads
			(clearance 0)
		)
		(min_thickness 0.25)
		(keepout
			(tracks not_allowed)
			(vias allowed)
			(pads allowed)
			(copperpour not_allowed)
			(footprints allowed)
		)
		(placement
			(enabled no)
			(sheetname "")
		)
		(fill yes
			(thermal_gap 0.5)
			(thermal_bridge_width 0.5)
			(island_removal_mode 0)
		)
		(polygon
			(pts
				(arc
					(start 48.114204 -295.9354)
					(mid 47.453804 -295.9354)
					(end 48.114204 -295.9354)
				)
			)
		)
	)
	(zone
		(layers "In1.Cu" "In2.Cu")
		(hatch none 0.5)
		(connect_pads
			(clearance 0)
		)
		(min_thickness 0.25)
		(keepout
			(tracks not_allowed)
			(vias allowed)
			(pads allowed)
			(copperpour not_allowed)
			(footprints allowed)
		)
		(placement
			(enabled no)
			(sheetname "")
		)
		(fill yes
			(thermal_gap 0.5)
			(thermal_bridge_width 0.5)
			(island_removal_mode 0)
		)
		(polygon
			(pts
				(arc
					(start 280.966164 -301.034958)
					(mid 280.305764 -301.034958)
					(end 280.966164 -301.034958)
				)
			)
		)
	)
	(zone
		(layers "In1.Cu" "In2.Cu")
		(hatch none 0.5)
		(connect_pads
			(clearance 0)
		)
		(min_thickness 0.25)
		(keepout
			(tracks not_allowed)
			(vias allowed)
			(pads allowed)
			(copperpour not_allowed)
			(footprints allowed)
		)
		(placement
			(enabled no)
			(sheetname "")
		)
		(fill yes
			(thermal_gap 0.5)
			(thermal_bridge_width 0.5)
			(island_removal_mode 0)
		)
		(polygon
			(pts
				(arc
					(start 292.610286 -236.435138)
					(mid 291.949886 -236.435138)
					(end 292.610286 -236.435138)
				)
			)
		)
	)
	(zone
		(layers "In1.Cu" "In2.Cu")
		(hatch none 0.5)
		(connect_pads
			(clearance 0)
		)
		(min_thickness 0.25)
		(keepout
			(tracks not_allowed)
			(vias allowed)
			(pads allowed)
			(copperpour not_allowed)
			(footprints allowed)
		)
		(placement
			(enabled no)
			(sheetname "")
		)
		(fill yes
			(thermal_gap 0.5)
			(thermal_bridge_width 0.5)
			(island_removal_mode 0)
		)
		(polygon
			(pts
				(arc
					(start 285.066232 -247.485154)
					(mid 284.405832 -247.485154)
					(end 285.066232 -247.485154)
				)
			)
		)
	)
	(zone
		(layers "In1.Cu" "In2.Cu")
		(hatch none 0.5)
		(connect_pads
			(clearance 0)
		)
		(min_thickness 0.25)
		(keepout
			(tracks not_allowed)
			(vias allowed)
			(pads allowed)
			(copperpour not_allowed)
			(footprints allowed)
		)
		(placement
			(enabled no)
			(sheetname "")
		)
		(fill yes
			(thermal_gap 0.5)
			(thermal_bridge_width 0.5)
			(island_removal_mode 0)
		)
		(polygon
			(pts
				(arc
					(start 446.974468 -294.235124)
					(mid 446.314068 -294.235124)
					(end 446.974468 -294.235124)
				)
			)
		)
	)
	(zone
		(layers "In1.Cu" "In2.Cu")
		(hatch none 0.5)
		(connect_pads
			(clearance 0)
		)
		(min_thickness 0.25)
		(keepout
			(tracks not_allowed)
			(vias allowed)
			(pads allowed)
			(copperpour not_allowed)
			(footprints allowed)
		)
		(placement
			(enabled no)
			(sheetname "")
		)
		(fill yes
			(thermal_gap 0.5)
			(thermal_bridge_width 0.5)
			(island_removal_mode 0)
		)
		(polygon
			(pts
				(arc
					(start 296.054272 -244.934994)
					(mid 295.393872 -244.934994)
					(end 296.054272 -244.934994)
				)
			)
		)
	)
	(zone
		(layers "In1.Cu" "In2.Cu")
		(hatch none 0.5)
		(connect_pads
			(clearance 0)
		)
		(min_thickness 0.25)
		(keepout
			(tracks not_allowed)
			(vias allowed)
			(pads allowed)
			(copperpour not_allowed)
			(footprints allowed)
		)
		(placement
			(enabled no)
			(sheetname "")
		)
		(fill yes
			(thermal_gap 0.5)
			(thermal_bridge_width 0.5)
			(island_removal_mode 0)
		)
		(polygon
			(pts
				(arc
					(start 365.660686 -390.65581)
					(mid 365.65145 -390.675734)
					(end 365.64824 -390.697466)
				)
				(arc
					(start 365.64824 -390.89203)
					(mid 365.670558 -390.945912)
					(end 365.72444 -390.96823)
				)
				(arc
					(start 366.41024 -390.96823)
					(mid 366.464122 -390.945912)
					(end 366.48644 -390.89203)
				)
				(arc
					(start 366.48644 -390.697466)
					(mid 366.483272 -390.675722)
					(end 366.473994 -390.65581)
				)
				(arc
					(start 366.281208 -390.359646)
					(mid 366.268986 -390.317962)
					(end 366.281462 -390.276334)
				)
				(arc
					(start 366.473994 -389.98271)
					(mid 366.48323 -389.962786)
					(end 366.48644 -389.941054)
				)
				(arc
					(start 366.48644 -389.74649)
					(mid 366.464122 -389.692608)
					(end 366.41024 -389.67029)
				)
				(arc
					(start 365.72444 -389.67029)
					(mid 365.670558 -389.692608)
					(end 365.64824 -389.74649)
				)
				(arc
					(start 365.64824 -389.942324)
					(mid 365.651408 -389.964068)
					(end 365.660686 -389.98398)
				)
				(arc
					(start 365.853218 -390.277604)
					(mid 365.86562 -390.31926)
					(end 365.853218 -390.360916)
				)
			)
		)
	)
	(zone
		(layers "In1.Cu" "In2.Cu")
		(hatch none 0.5)
		(connect_pads
			(clearance 0)
		)
		(min_thickness 0.25)
		(keepout
			(tracks not_allowed)
			(vias allowed)
			(pads allowed)
			(copperpour not_allowed)
			(footprints allowed)
		)
		(placement
			(enabled no)
			(sheetname "")
		)
		(fill yes
			(thermal_gap 0.5)
			(thermal_bridge_width 0.5)
			(island_removal_mode 0)
		)
		(polygon
			(pts
				(arc
					(start 351.561146 -292.41115)
					(mid 351.256346 -292.71595)
					(end 351.561146 -293.02075)
				)
				(arc
					(start 352.5012 -293.02075)
					(mid 352.806 -292.71595)
					(end 352.5012 -292.41115)
				)
			)
		)
	)
	(zone
		(layers "In1.Cu" "In2.Cu")
		(hatch none 0.5)
		(connect_pads
			(clearance 0)
		)
		(min_thickness 0.25)
		(keepout
			(tracks not_allowed)
			(vias allowed)
			(pads allowed)
			(copperpour not_allowed)
			(footprints allowed)
		)
		(placement
			(enabled no)
			(sheetname "")
		)
		(fill yes
			(thermal_gap 0.5)
			(thermal_bridge_width 0.5)
			(island_removal_mode 0)
		)
		(polygon
			(pts
				(arc
					(start 187.390278 -268.735302)
					(mid 186.729878 -268.735302)
					(end 187.390278 -268.735302)
				)
			)
		)
	)
	(zone
		(layers "In1.Cu" "In2.Cu")
		(hatch none 0.5)
		(connect_pads
			(clearance 0)
		)
		(min_thickness 0.25)
		(keepout
			(tracks not_allowed)
			(vias allowed)
			(pads allowed)
			(copperpour not_allowed)
			(footprints allowed)
		)
		(placement
			(enabled no)
			(sheetname "")
		)
		(fill yes
			(thermal_gap 0.5)
			(thermal_bridge_width 0.5)
			(island_removal_mode 0)
		)
		(polygon
			(pts
				(arc
					(start 187.390278 -226.23526)
					(mid 186.729878 -226.23526)
					(end 187.390278 -226.23526)
				)
			)
		)
	)
	(zone
		(layers "In1.Cu" "In2.Cu")
		(hatch none 0.5)
		(connect_pads
			(clearance 0)
		)
		(min_thickness 0.25)
		(keepout
			(tracks not_allowed)
			(vias allowed)
			(pads allowed)
			(copperpour not_allowed)
			(footprints allowed)
		)
		(placement
			(enabled no)
			(sheetname "")
		)
		(fill yes
			(thermal_gap 0.5)
			(thermal_bridge_width 0.5)
			(island_removal_mode 0)
		)
		(polygon
			(pts
				(arc
					(start 17.938242 -308.685438)
					(mid 17.277842 -308.685438)
					(end 17.938242 -308.685438)
				)
			)
		)
	)
	(zone
		(layers "In1.Cu" "In2.Cu")
		(hatch none 0.5)
		(connect_pads
			(clearance 0)
		)
		(min_thickness 0.25)
		(keepout
			(tracks not_allowed)
			(vias allowed)
			(pads allowed)
			(copperpour not_allowed)
			(footprints allowed)
		)
		(placement
			(enabled no)
			(sheetname "")
		)
		(fill yes
			(thermal_gap 0.5)
			(thermal_bridge_width 0.5)
			(island_removal_mode 0)
		)
		(polygon
			(pts
				(arc
					(start 187.390278 -248.335292)
					(mid 186.729878 -248.335292)
					(end 187.390278 -248.335292)
				)
			)
		)
	)
	(zone
		(layers "In1.Cu" "In2.Cu")
		(hatch none 0.5)
		(connect_pads
			(clearance 0)
		)
		(min_thickness 0.25)
		(keepout
			(tracks not_allowed)
			(vias allowed)
			(pads allowed)
			(copperpour not_allowed)
			(footprints allowed)
		)
		(placement
			(enabled no)
			(sheetname "")
		)
		(fill yes
			(thermal_gap 0.5)
			(thermal_bridge_width 0.5)
			(island_removal_mode 0)
		)
		(polygon
			(pts
				(arc
					(start 348.741238 -292.41115)
					(mid 348.436438 -292.71595)
					(end 348.741238 -293.02075)
				)
				(arc
					(start 349.681292 -293.02075)
					(mid 349.986092 -292.71595)
					(end 349.681292 -292.41115)
				)
			)
		)
	)
	(zone
		(layers "In1.Cu" "In2.Cu")
		(hatch none 0.5)
		(connect_pads
			(clearance 0)
		)
		(min_thickness 0.25)
		(keepout
			(tracks not_allowed)
			(vias allowed)
			(pads allowed)
			(copperpour not_allowed)
			(footprints allowed)
		)
		(placement
			(enabled no)
			(sheetname "")
		)
		(fill yes
			(thermal_gap 0.5)
			(thermal_bridge_width 0.5)
			(island_removal_mode 0)
		)
		(polygon
			(pts
				(arc
					(start 292.610286 -252.584966)
					(mid 291.949886 -252.584966)
					(end 292.610286 -252.584966)
				)
			)
		)
	)
	(zone
		(layers "In1.Cu" "In2.Cu")
		(hatch none 0.5)
		(connect_pads
			(clearance 0)
		)
		(min_thickness 0.25)
		(keepout
			(tracks not_allowed)
			(vias allowed)
			(pads allowed)
			(copperpour not_allowed)
			(footprints allowed)
		)
		(placement
			(enabled no)
			(sheetname "")
		)
		(fill yes
			(thermal_gap 0.5)
			(thermal_bridge_width 0.5)
			(island_removal_mode 0)
		)
		(polygon
			(pts
				(arc
					(start 183.946292 -216.035382)
					(mid 183.285892 -216.035382)
					(end 183.946292 -216.035382)
				)
			)
		)
	)
	(zone
		(layers "In1.Cu" "In2.Cu")
		(hatch none 0.5)
		(connect_pads
			(clearance 0)
		)
		(min_thickness 0.25)
		(keepout
			(tracks not_allowed)
			(vias allowed)
			(pads allowed)
			(copperpour not_allowed)
			(footprints allowed)
		)
		(placement
			(enabled no)
			(sheetname "")
		)
		(fill yes
			(thermal_gap 0.5)
			(thermal_bridge_width 0.5)
			(island_removal_mode 0)
		)
		(polygon
			(pts
				(arc
					(start 40.57015 -286.585406)
					(mid 39.90975 -286.585406)
					(end 40.57015 -286.585406)
				)
			)
		)
	)
	(zone
		(layers "In1.Cu" "In2.Cu")
		(hatch none 0.5)
		(connect_pads
			(clearance 0)
		)
		(min_thickness 0.25)
		(keepout
			(tracks not_allowed)
			(vias allowed)
			(pads allowed)
			(copperpour not_allowed)
			(footprints allowed)
		)
		(placement
			(enabled no)
			(sheetname "")
		)
		(fill yes
			(thermal_gap 0.5)
			(thermal_bridge_width 0.5)
			(island_removal_mode 0)
		)
		(polygon
			(pts
				(arc
					(start 269.978378 -210.935062)
					(mid 269.317978 -210.935062)
					(end 269.978378 -210.935062)
				)
			)
		)
	)
	(zone
		(layers "In1.Cu" "In2.Cu")
		(hatch none 0.5)
		(connect_pads
			(clearance 0)
		)
		(min_thickness 0.25)
		(keepout
			(tracks not_allowed)
			(vias allowed)
			(pads allowed)
			(copperpour not_allowed)
			(footprints allowed)
		)
		(placement
			(enabled no)
			(sheetname "")
		)
		(fill yes
			(thermal_gap 0.5)
			(thermal_bridge_width 0.5)
			(island_removal_mode 0)
		)
		(polygon
			(pts
				(arc
					(start 52.214272 -238.985298)
					(mid 51.553872 -238.985298)
					(end 52.214272 -238.985298)
				)
			)
		)
	)
	(zone
		(layers "In1.Cu" "In2.Cu")
		(hatch none 0.5)
		(connect_pads
			(clearance 0)
		)
		(min_thickness 0.25)
		(keepout
			(tracks not_allowed)
			(vias allowed)
			(pads allowed)
			(copperpour not_allowed)
			(footprints allowed)
		)
		(placement
			(enabled no)
			(sheetname "")
		)
		(fill yes
			(thermal_gap 0.5)
			(thermal_bridge_width 0.5)
			(island_removal_mode 0)
		)
		(polygon
			(pts
				(arc
					(start 450.4182 -305.28514)
					(mid 449.7578 -305.28514)
					(end 450.4182 -305.28514)
				)
			)
		)
	)
	(zone
		(layers "In1.Cu" "In2.Cu")
		(hatch none 0.5)
		(connect_pads
			(clearance 0)
		)
		(min_thickness 0.25)
		(keepout
			(tracks not_allowed)
			(vias allowed)
			(pads allowed)
			(copperpour not_allowed)
			(footprints allowed)
		)
		(placement
			(enabled no)
			(sheetname "")
		)
		(fill yes
			(thermal_gap 0.5)
			(thermal_bridge_width 0.5)
			(island_removal_mode 0)
		)
		(polygon
			(pts
				(arc
					(start 48.114204 -306.985416)
					(mid 47.453804 -306.985416)
					(end 48.114204 -306.985416)
				)
			)
		)
	)
	(zone
		(layers "In1.Cu" "In2.Cu")
		(hatch none 0.5)
		(connect_pads
			(clearance 0)
		)
		(min_thickness 0.25)
		(keepout
			(tracks not_allowed)
			(vias allowed)
			(pads allowed)
			(copperpour not_allowed)
			(footprints allowed)
		)
		(placement
			(enabled no)
			(sheetname "")
		)
		(fill yes
			(thermal_gap 0.5)
			(thermal_bridge_width 0.5)
			(island_removal_mode 0)
		)
		(polygon
			(pts
				(arc
					(start 44.670218 -217.735404)
					(mid 44.009818 -217.735404)
					(end 44.670218 -217.735404)
				)
			)
		)
	)
	(zone
		(layers "In1.Cu" "In2.Cu")
		(hatch none 0.5)
		(connect_pads
			(clearance 0)
		)
		(min_thickness 0.25)
		(keepout
			(tracks not_allowed)
			(vias allowed)
			(pads allowed)
			(copperpour not_allowed)
			(footprints allowed)
		)
		(placement
			(enabled no)
			(sheetname "")
		)
		(fill yes
			(thermal_gap 0.5)
			(thermal_bridge_width 0.5)
			(island_removal_mode 0)
		)
		(polygon
			(pts
				(arc
					(start 33.026096 -202.435206)
					(mid 32.365696 -202.435206)
					(end 33.026096 -202.435206)
				)
			)
		)
	)
	(zone
		(layers "In1.Cu" "In2.Cu")
		(hatch none 0.5)
		(connect_pads
			(clearance 0)
		)
		(min_thickness 0.25)
		(keepout
			(tracks not_allowed)
			(vias allowed)
			(pads allowed)
			(copperpour not_allowed)
			(footprints allowed)
		)
		(placement
			(enabled no)
			(sheetname "")
		)
		(fill yes
			(thermal_gap 0.5)
			(thermal_bridge_width 0.5)
			(island_removal_mode 0)
		)
		(polygon
			(pts
				(arc
					(start 37.126164 -210.085432)
					(mid 36.465764 -210.085432)
					(end 37.126164 -210.085432)
				)
			)
		)
	)
	(zone
		(layers "In1.Cu" "In2.Cu")
		(hatch none 0.5)
		(connect_pads
			(clearance 0)
		)
		(min_thickness 0.25)
		(keepout
			(tracks not_allowed)
			(vias allowed)
			(pads allowed)
			(copperpour not_allowed)
			(footprints allowed)
		)
		(placement
			(enabled no)
			(sheetname "")
		)
		(fill yes
			(thermal_gap 0.5)
			(thermal_bridge_width 0.5)
			(island_removal_mode 0)
		)
		(polygon
			(pts
				(arc
					(start 296.054272 -304.435002)
					(mid 295.393872 -304.435002)
					(end 296.054272 -304.435002)
				)
			)
		)
	)
	(zone
		(layers "In1.Cu" "In2.Cu")
		(hatch none 0.5)
		(connect_pads
			(clearance 0)
		)
		(min_thickness 0.25)
		(keepout
			(tracks not_allowed)
			(vias allowed)
			(pads allowed)
			(copperpour not_allowed)
			(footprints allowed)
		)
		(placement
			(enabled no)
			(sheetname "")
		)
		(fill yes
			(thermal_gap 0.5)
			(thermal_bridge_width 0.5)
			(island_removal_mode 0)
		)
		(polygon
			(pts
				(arc
					(start 300.15434 -233.035094)
					(mid 299.49394 -233.035094)
					(end 300.15434 -233.035094)
				)
			)
		)
	)
	(zone
		(layers "In1.Cu" "In2.Cu")
		(hatch none 0.5)
		(connect_pads
			(clearance 0)
		)
		(min_thickness 0.25)
		(keepout
			(tracks not_allowed)
			(vias allowed)
			(pads allowed)
			(copperpour not_allowed)
			(footprints allowed)
		)
		(placement
			(enabled no)
			(sheetname "")
		)
		(fill yes
			(thermal_gap 0.5)
			(thermal_bridge_width 0.5)
			(island_removal_mode 0)
		)
		(polygon
			(pts
				(arc
					(start 273.422364 -202.434952)
					(mid 272.761964 -202.434952)
					(end 273.422364 -202.434952)
				)
			)
		)
	)
	(zone
		(layers "In1.Cu" "In2.Cu")
		(hatch none 0.5)
		(connect_pads
			(clearance 0)
		)
		(min_thickness 0.25)
		(keepout
			(tracks not_allowed)
			(vias allowed)
			(pads allowed)
			(copperpour not_allowed)
			(footprints allowed)
		)
		(placement
			(enabled no)
			(sheetname "")
		)
		(fill yes
			(thermal_gap 0.5)
			(thermal_bridge_width 0.5)
			(island_removal_mode 0)
		)
		(polygon
			(pts
				(arc
					(start 25.482296 -202.435206)
					(mid 24.821896 -202.435206)
					(end 25.482296 -202.435206)
				)
			)
		)
	)
	(zone
		(layers "In1.Cu" "In2.Cu")
		(hatch none 0.5)
		(connect_pads
			(clearance 0)
		)
		(min_thickness 0.25)
		(keepout
			(tracks not_allowed)
			(vias allowed)
			(pads allowed)
			(copperpour not_allowed)
			(footprints allowed)
		)
		(placement
			(enabled no)
			(sheetname "")
		)
		(fill yes
			(thermal_gap 0.5)
			(thermal_bridge_width 0.5)
			(island_removal_mode 0)
		)
		(polygon
			(pts
				(arc
					(start 427.786292 -316.335156)
					(mid 427.125892 -316.335156)
					(end 427.786292 -316.335156)
				)
			)
		)
	)
	(zone
		(layers "In1.Cu" "In2.Cu")
		(hatch none 0.5)
		(connect_pads
			(clearance 0)
		)
		(min_thickness 0.25)
		(keepout
			(tracks not_allowed)
			(vias allowed)
			(pads allowed)
			(copperpour not_allowed)
			(footprints allowed)
		)
		(placement
			(enabled no)
			(sheetname "")
		)
		(fill yes
			(thermal_gap 0.5)
			(thermal_bridge_width 0.5)
			(island_removal_mode 0)
		)
		(polygon
			(pts
				(arc
					(start 427.786292 -233.884978)
					(mid 427.125892 -233.884978)
					(end 427.786292 -233.884978)
				)
			)
		)
	)
	(zone
		(layers "In1.Cu" "In2.Cu")
		(hatch none 0.5)
		(connect_pads
			(clearance 0)
		)
		(min_thickness 0.25)
		(keepout
			(tracks not_allowed)
			(vias allowed)
			(pads allowed)
			(copperpour not_allowed)
			(footprints allowed)
		)
		(placement
			(enabled no)
			(sheetname "")
		)
		(fill yes
			(thermal_gap 0.5)
			(thermal_bridge_width 0.5)
			(island_removal_mode 0)
		)
		(polygon
			(pts
				(arc
					(start 442.8744 -268.735048)
					(mid 442.214 -268.735048)
					(end 442.8744 -268.735048)
				)
			)
		)
	)
	(zone
		(layers "In1.Cu" "In2.Cu")
		(hatch none 0.5)
		(connect_pads
			(clearance 0)
		)
		(min_thickness 0.25)
		(keepout
			(tracks not_allowed)
			(vias allowed)
			(pads allowed)
			(copperpour not_allowed)
			(footprints allowed)
		)
		(placement
			(enabled no)
			(sheetname "")
		)
		(fill yes
			(thermal_gap 0.5)
			(thermal_bridge_width 0.5)
			(island_removal_mode 0)
		)
		(polygon
			(pts
				(arc
					(start 191.490346 -231.335326)
					(mid 190.829946 -231.335326)
					(end 191.490346 -231.335326)
				)
			)
		)
	)
	(zone
		(layers "In1.Cu" "In2.Cu")
		(hatch none 0.5)
		(connect_pads
			(clearance 0)
		)
		(min_thickness 0.25)
		(keepout
			(tracks not_allowed)
			(vias allowed)
			(pads allowed)
			(copperpour not_allowed)
			(footprints allowed)
		)
		(placement
			(enabled no)
			(sheetname "")
		)
		(fill yes
			(thermal_gap 0.5)
			(thermal_bridge_width 0.5)
			(island_removal_mode 0)
		)
		(polygon
			(pts
				(arc
					(start 172.30217 -218.585288)
					(mid 171.64177 -218.585288)
					(end 172.30217 -218.585288)
				)
			)
		)
	)
	(zone
		(layers "In1.Cu" "In2.Cu")
		(hatch none 0.5)
		(connect_pads
			(clearance 0)
		)
		(min_thickness 0.25)
		(keepout
			(tracks not_allowed)
			(vias allowed)
			(pads allowed)
			(copperpour not_allowed)
			(footprints allowed)
		)
		(placement
			(enabled no)
			(sheetname "")
		)
		(fill yes
			(thermal_gap 0.5)
			(thermal_bridge_width 0.5)
			(island_removal_mode 0)
		)
		(polygon
			(pts
				(arc
					(start 191.490346 -217.735404)
					(mid 190.829946 -217.735404)
					(end 191.490346 -217.735404)
				)
			)
		)
	)
	(zone
		(layers "In1.Cu" "In2.Cu")
		(hatch none 0.5)
		(connect_pads
			(clearance 0)
		)
		(min_thickness 0.25)
		(keepout
			(tracks not_allowed)
			(vias allowed)
			(pads allowed)
			(copperpour not_allowed)
			(footprints allowed)
		)
		(placement
			(enabled no)
			(sheetname "")
		)
		(fill yes
			(thermal_gap 0.5)
			(thermal_bridge_width 0.5)
			(island_removal_mode 0)
		)
		(polygon
			(pts
				(arc
					(start 273.422364 -293.384986)
					(mid 272.761964 -293.384986)
					(end 273.422364 -293.384986)
				)
			)
		)
	)
	(zone
		(layers "In1.Cu" "In2.Cu")
		(hatch none 0.5)
		(connect_pads
			(clearance 0)
		)
		(min_thickness 0.25)
		(keepout
			(tracks not_allowed)
			(vias allowed)
			(pads allowed)
			(copperpour not_allowed)
			(footprints allowed)
		)
		(placement
			(enabled no)
			(sheetname "")
		)
		(fill yes
			(thermal_gap 0.5)
			(thermal_bridge_width 0.5)
			(island_removal_mode 0)
		)
		(polygon
			(pts
				(arc
					(start 450.4182 -299.33519)
					(mid 449.7578 -299.33519)
					(end 450.4182 -299.33519)
				)
			)
		)
	)
	(zone
		(layers "In1.Cu" "In2.Cu")
		(hatch none 0.5)
		(connect_pads
			(clearance 0)
		)
		(min_thickness 0.25)
		(keepout
			(tracks not_allowed)
			(vias allowed)
			(pads allowed)
			(copperpour not_allowed)
			(footprints allowed)
		)
		(placement
			(enabled no)
			(sheetname "")
		)
		(fill yes
			(thermal_gap 0.5)
			(thermal_bridge_width 0.5)
			(island_removal_mode 0)
		)
		(polygon
			(pts
				(arc
					(start 29.582364 -227.085398)
					(mid 28.921964 -227.085398)
					(end 29.582364 -227.085398)
				)
			)
		)
	)
	(zone
		(layers "In1.Cu" "In2.Cu")
		(hatch none 0.5)
		(connect_pads
			(clearance 0)
		)
		(min_thickness 0.25)
		(keepout
			(tracks not_allowed)
			(vias allowed)
			(pads allowed)
			(copperpour not_allowed)
			(footprints allowed)
		)
		(placement
			(enabled no)
			(sheetname "")
		)
		(fill yes
			(thermal_gap 0.5)
			(thermal_bridge_width 0.5)
			(island_removal_mode 0)
		)
		(polygon
			(pts
				(arc
					(start 427.786292 -293.384986)
					(mid 427.125892 -293.384986)
					(end 427.786292 -293.384986)
				)
			)
		)
	)
	(zone
		(layers "In1.Cu" "In2.Cu")
		(hatch none 0.5)
		(connect_pads
			(clearance 0)
		)
		(min_thickness 0.25)
		(keepout
			(tracks not_allowed)
			(vias allowed)
			(pads allowed)
			(copperpour not_allowed)
			(footprints allowed)
		)
		(placement
			(enabled no)
			(sheetname "")
		)
		(fill yes
			(thermal_gap 0.5)
			(thermal_bridge_width 0.5)
			(island_removal_mode 0)
		)
		(polygon
			(pts
				(arc
					(start 296.054272 -207.535018)
					(mid 295.393872 -207.535018)
					(end 296.054272 -207.535018)
				)
			)
		)
	)
	(zone
		(layers "In1.Cu" "In2.Cu")
		(hatch none 0.5)
		(connect_pads
			(clearance 0)
		)
		(min_thickness 0.25)
		(keepout
			(tracks not_allowed)
			(vias allowed)
			(pads allowed)
			(copperpour not_allowed)
			(footprints allowed)
		)
		(placement
			(enabled no)
			(sheetname "")
		)
		(fill yes
			(thermal_gap 0.5)
			(thermal_bridge_width 0.5)
			(island_removal_mode 0)
		)
		(polygon
			(pts
				(arc
					(start 29.582364 -242.385342)
					(mid 28.921964 -242.385342)
					(end 29.582364 -242.385342)
				)
			)
		)
	)
	(zone
		(layers "In1.Cu" "In2.Cu")
		(hatch none 0.5)
		(connect_pads
			(clearance 0)
		)
		(min_thickness 0.25)
		(keepout
			(tracks not_allowed)
			(vias allowed)
			(pads allowed)
			(copperpour not_allowed)
			(footprints allowed)
		)
		(placement
			(enabled no)
			(sheetname "")
		)
		(fill yes
			(thermal_gap 0.5)
			(thermal_bridge_width 0.5)
			(island_removal_mode 0)
		)
		(polygon
			(pts
				(arc
					(start 424.342306 -285.735014)
					(mid 423.681906 -285.735014)
					(end 424.342306 -285.735014)
				)
			)
		)
	)
	(zone
		(layers "In1.Cu" "In2.Cu")
		(hatch none 0.5)
		(connect_pads
			(clearance 0)
		)
		(min_thickness 0.25)
		(keepout
			(tracks not_allowed)
			(vias allowed)
			(pads allowed)
			(copperpour not_allowed)
			(footprints allowed)
		)
		(placement
			(enabled no)
			(sheetname "")
		)
		(fill yes
			(thermal_gap 0.5)
			(thermal_bridge_width 0.5)
			(island_removal_mode 0)
		)
		(polygon
			(pts
				(arc
					(start 44.670218 -284.885384)
					(mid 44.009818 -284.885384)
					(end 44.670218 -284.885384)
				)
			)
		)
	)
	(zone
		(layers "In1.Cu" "In2.Cu")
		(hatch none 0.5)
		(connect_pads
			(clearance 0)
		)
		(min_thickness 0.25)
		(keepout
			(tracks not_allowed)
			(vias allowed)
			(pads allowed)
			(copperpour not_allowed)
			(footprints allowed)
		)
		(placement
			(enabled no)
			(sheetname "")
		)
		(fill yes
			(thermal_gap 0.5)
			(thermal_bridge_width 0.5)
			(island_removal_mode 0)
		)
		(polygon
			(pts
				(arc
					(start 420.242238 -267.035026)
					(mid 419.581838 -267.035026)
					(end 420.242238 -267.035026)
				)
			)
		)
	)
	(zone
		(layers "In1.Cu" "In2.Cu")
		(hatch none 0.5)
		(connect_pads
			(clearance 0)
		)
		(min_thickness 0.25)
		(keepout
			(tracks not_allowed)
			(vias allowed)
			(pads allowed)
			(copperpour not_allowed)
			(footprints allowed)
		)
		(placement
			(enabled no)
			(sheetname "")
		)
		(fill yes
			(thermal_gap 0.5)
			(thermal_bridge_width 0.5)
			(island_removal_mode 0)
		)
		(polygon
			(pts
				(arc
					(start 48.114204 -318.035432)
					(mid 47.453804 -318.035432)
					(end 48.114204 -318.035432)
				)
			)
		)
	)
	(zone
		(layers "In1.Cu" "In2.Cu")
		(hatch none 0.5)
		(connect_pads
			(clearance 0)
		)
		(min_thickness 0.25)
		(keepout
			(tracks not_allowed)
			(vias allowed)
			(pads allowed)
			(copperpour not_allowed)
			(footprints allowed)
		)
		(placement
			(enabled no)
			(sheetname "")
		)
		(fill yes
			(thermal_gap 0.5)
			(thermal_bridge_width 0.5)
			(island_removal_mode 0)
		)
		(polygon
			(pts
				(arc
					(start 420.242238 -204.134974)
					(mid 419.581838 -204.134974)
					(end 420.242238 -204.134974)
				)
			)
		)
	)
	(zone
		(layers "In1.Cu" "In2.Cu")
		(hatch none 0.5)
		(connect_pads
			(clearance 0)
		)
		(min_thickness 0.25)
		(keepout
			(tracks not_allowed)
			(vias allowed)
			(pads allowed)
			(copperpour not_allowed)
			(footprints allowed)
		)
		(placement
			(enabled no)
			(sheetname "")
		)
		(fill yes
			(thermal_gap 0.5)
			(thermal_bridge_width 0.5)
			(island_removal_mode 0)
		)
		(polygon
			(pts
				(arc
					(start 288.510218 -253.435104)
					(mid 287.849818 -253.435104)
					(end 288.510218 -253.435104)
				)
			)
		)
	)
	(zone
		(layers "In1.Cu" "In2.Cu")
		(hatch none 0.5)
		(connect_pads
			(clearance 0)
		)
		(min_thickness 0.25)
		(keepout
			(tracks not_allowed)
			(vias allowed)
			(pads allowed)
			(copperpour not_allowed)
			(footprints allowed)
		)
		(placement
			(enabled no)
			(sheetname "")
		)
		(fill yes
			(thermal_gap 0.5)
			(thermal_bridge_width 0.5)
			(island_removal_mode 0)
		)
		(polygon
			(pts
				(arc
					(start 427.786292 -302.73498)
					(mid 427.125892 -302.73498)
					(end 427.786292 -302.73498)
				)
			)
		)
	)
	(zone
		(layers "In1.Cu" "In2.Cu")
		(hatch none 0.5)
		(connect_pads
			(clearance 0)
		)
		(min_thickness 0.25)
		(keepout
			(tracks not_allowed)
			(vias allowed)
			(pads allowed)
			(copperpour not_allowed)
			(footprints allowed)
		)
		(placement
			(enabled no)
			(sheetname "")
		)
		(fill yes
			(thermal_gap 0.5)
			(thermal_bridge_width 0.5)
			(island_removal_mode 0)
		)
		(polygon
			(pts
				(arc
					(start 37.126164 -225.385376)
					(mid 36.465764 -225.385376)
					(end 37.126164 -225.385376)
				)
			)
		)
	)
	(zone
		(layers "In1.Cu" "In2.Cu")
		(hatch none 0.5)
		(connect_pads
			(clearance 0)
		)
		(min_thickness 0.25)
		(keepout
			(tracks not_allowed)
			(vias allowed)
			(pads allowed)
			(copperpour not_allowed)
			(footprints allowed)
		)
		(placement
			(enabled no)
			(sheetname "")
		)
		(fill yes
			(thermal_gap 0.5)
			(thermal_bridge_width 0.5)
			(island_removal_mode 0)
		)
		(polygon
			(pts
				(arc
					(start 285.066232 -285.735014)
					(mid 284.405832 -285.735014)
					(end 285.066232 -285.735014)
				)
			)
		)
	)
	(zone
		(layers "In1.Cu" "In2.Cu")
		(hatch none 0.5)
		(connect_pads
			(clearance 0)
		)
		(min_thickness 0.25)
		(keepout
			(tracks not_allowed)
			(vias allowed)
			(pads allowed)
			(copperpour not_allowed)
			(footprints allowed)
		)
		(placement
			(enabled no)
			(sheetname "")
		)
		(fill yes
			(thermal_gap 0.5)
			(thermal_bridge_width 0.5)
			(island_removal_mode 0)
		)
		(polygon
			(pts
				(arc
					(start 172.30217 -226.23526)
					(mid 171.64177 -226.23526)
					(end 172.30217 -226.23526)
				)
			)
		)
	)
	(zone
		(layers "In1.Cu" "In2.Cu")
		(hatch none 0.5)
		(connect_pads
			(clearance 0)
		)
		(min_thickness 0.25)
		(keepout
			(tracks not_allowed)
			(vias allowed)
			(pads allowed)
			(copperpour not_allowed)
			(footprints allowed)
		)
		(placement
			(enabled no)
			(sheetname "")
		)
		(fill yes
			(thermal_gap 0.5)
			(thermal_bridge_width 0.5)
			(island_removal_mode 0)
		)
		(polygon
			(pts
				(arc
					(start 321.956176 -417.242244)
					(mid 321.978494 -417.296126)
					(end 322.032376 -417.318444)
				)
				(arc
					(start 322.227956 -417.318444)
					(mid 322.249832 -417.315312)
					(end 322.269866 -417.305998)
				)
				(arc
					(start 322.56349 -417.113466)
					(mid 322.605146 -417.101064)
					(end 322.646802 -417.113466)
				)
				(arc
					(start 322.941696 -417.305998)
					(mid 322.96162 -417.315234)
					(end 322.983352 -417.318444)
				)
				(arc
					(start 323.177916 -417.318444)
					(mid 323.231798 -417.296126)
					(end 323.254116 -417.242244)
				)
				(arc
					(start 323.254116 -416.556444)
					(mid 323.231798 -416.502562)
					(end 323.177916 -416.480244)
				)
				(arc
					(start 322.983352 -416.480244)
					(mid 322.961608 -416.483412)
					(end 322.941696 -416.49269)
				)
				(arc
					(start 322.645532 -416.685476)
					(mid 322.603848 -416.697698)
					(end 322.56222 -416.685222)
				)
				(arc
					(start 322.268596 -416.49269)
					(mid 322.248672 -416.483454)
					(end 322.22694 -416.480244)
				)
				(arc
					(start 322.032376 -416.480244)
					(mid 321.978494 -416.502562)
					(end 321.956176 -416.556444)
				)
			)
		)
	)
	(zone
		(layers "In1.Cu" "In2.Cu")
		(hatch none 0.5)
		(connect_pads
			(clearance 0)
		)
		(min_thickness 0.25)
		(keepout
			(tracks not_allowed)
			(vias allowed)
			(pads allowed)
			(copperpour not_allowed)
			(footprints allowed)
		)
		(placement
			(enabled no)
			(sheetname "")
		)
		(fill yes
			(thermal_gap 0.5)
			(thermal_bridge_width 0.5)
			(island_removal_mode 0)
		)
		(polygon
			(pts
				(arc
					(start 398.246092 -417.242244)
					(mid 398.26841 -417.296126)
					(end 398.322292 -417.318444)
				)
				(arc
					(start 398.517872 -417.318444)
					(mid 398.539748 -417.315312)
					(end 398.559782 -417.305998)
				)
				(arc
					(start 398.853406 -417.113466)
					(mid 398.895062 -417.101064)
					(end 398.936718 -417.113466)
				)
				(arc
					(start 399.231612 -417.305998)
					(mid 399.251536 -417.315234)
					(end 399.273268 -417.318444)
				)
				(arc
					(start 399.467832 -417.318444)
					(mid 399.521714 -417.296126)
					(end 399.544032 -417.242244)
				)
				(arc
					(start 399.544032 -416.556444)
					(mid 399.521714 -416.502562)
					(end 399.467832 -416.480244)
				)
				(arc
					(start 399.273268 -416.480244)
					(mid 399.251524 -416.483412)
					(end 399.231612 -416.49269)
				)
				(arc
					(start 398.935448 -416.685476)
					(mid 398.893764 -416.697698)
					(end 398.852136 -416.685222)
				)
				(arc
					(start 398.558512 -416.49269)
					(mid 398.538588 -416.483454)
					(end 398.516856 -416.480244)
				)
				(arc
					(start 398.322292 -416.480244)
					(mid 398.26841 -416.502562)
					(end 398.246092 -416.556444)
				)
			)
		)
	)
	(zone
		(layers "In1.Cu" "In2.Cu")
		(hatch none 0.5)
		(connect_pads
			(clearance 0)
		)
		(min_thickness 0.25)
		(keepout
			(tracks not_allowed)
			(vias allowed)
			(pads allowed)
			(copperpour not_allowed)
			(footprints allowed)
		)
		(placement
			(enabled no)
			(sheetname "")
		)
		(fill yes
			(thermal_gap 0.5)
			(thermal_bridge_width 0.5)
			(island_removal_mode 0)
		)
		(polygon
			(pts
				(arc
					(start 431.88636 -300.185074)
					(mid 431.22596 -300.185074)
					(end 431.88636 -300.185074)
				)
			)
		)
	)
	(zone
		(layers "In1.Cu" "In2.Cu")
		(hatch none 0.5)
		(connect_pads
			(clearance 0)
		)
		(min_thickness 0.25)
		(keepout
			(tracks not_allowed)
			(vias allowed)
			(pads allowed)
			(copperpour not_allowed)
			(footprints allowed)
		)
		(placement
			(enabled no)
			(sheetname "")
		)
		(fill yes
			(thermal_gap 0.5)
			(thermal_bridge_width 0.5)
			(island_removal_mode 0)
		)
		(polygon
			(pts
				(arc
					(start 52.214272 -227.085398)
					(mid 51.553872 -227.085398)
					(end 52.214272 -227.085398)
				)
			)
		)
	)
	(zone
		(layers "In1.Cu" "In2.Cu")
		(hatch none 0.5)
		(connect_pads
			(clearance 0)
		)
		(min_thickness 0.25)
		(keepout
			(tracks not_allowed)
			(vias allowed)
			(pads allowed)
			(copperpour not_allowed)
			(footprints allowed)
		)
		(placement
			(enabled no)
			(sheetname "")
		)
		(fill yes
			(thermal_gap 0.5)
			(thermal_bridge_width 0.5)
			(island_removal_mode 0)
		)
		(polygon
			(pts
				(arc
					(start 187.390278 -267.03528)
					(mid 186.729878 -267.03528)
					(end 187.390278 -267.03528)
				)
			)
		)
	)
	(zone
		(layers "In1.Cu" "In2.Cu")
		(hatch none 0.5)
		(connect_pads
			(clearance 0)
		)
		(min_thickness 0.25)
		(keepout
			(tracks not_allowed)
			(vias allowed)
			(pads allowed)
			(copperpour not_allowed)
			(footprints allowed)
		)
		(placement
			(enabled no)
			(sheetname "")
		)
		(fill yes
			(thermal_gap 0.5)
			(thermal_bridge_width 0.5)
			(island_removal_mode 0)
		)
		(polygon
			(pts
				(arc
					(start 391.66673 -7.67461)
					(mid 391.689048 -7.620728)
					(end 391.74293 -7.59841)
				)
				(arc
					(start 392.55827 -7.59841)
					(mid 392.612152 -7.620728)
					(end 392.63447 -7.67461)
				)
				(arc
					(start 392.63447 -8.98017)
					(mid 392.612152 -9.034052)
					(end 392.55827 -9.05637)
				)
				(arc
					(start 391.74293 -9.05637)
					(mid 391.689048 -9.034052)
					(end 391.66673 -8.98017)
				)
			)
		)
	)
	(zone
		(layers "In1.Cu" "In2.Cu")
		(hatch none 0.5)
		(connect_pads
			(clearance 0)
		)
		(min_thickness 0.25)
		(keepout
			(tracks not_allowed)
			(vias allowed)
			(pads allowed)
			(copperpour not_allowed)
			(footprints allowed)
		)
		(placement
			(enabled no)
			(sheetname "")
		)
		(fill yes
			(thermal_gap 0.5)
			(thermal_bridge_width 0.5)
			(island_removal_mode 0)
		)
		(polygon
			(pts
				(arc
					(start 40.57015 -299.335444)
					(mid 39.90975 -299.335444)
					(end 40.57015 -299.335444)
				)
			)
		)
	)
	(zone
		(layers "In1.Cu" "In2.Cu")
		(hatch none 0.5)
		(connect_pads
			(clearance 0)
		)
		(min_thickness 0.25)
		(keepout
			(tracks not_allowed)
			(vias allowed)
			(pads allowed)
			(copperpour not_allowed)
			(footprints allowed)
		)
		(placement
			(enabled no)
			(sheetname "")
		)
		(fill yes
			(thermal_gap 0.5)
			(thermal_bridge_width 0.5)
			(island_removal_mode 0)
		)
		(polygon
			(pts
				(arc
					(start 172.30217 -211.7852)
					(mid 171.64177 -211.7852)
					(end 172.30217 -211.7852)
				)
			)
		)
	)
	(zone
		(layers "In1.Cu" "In2.Cu")
		(hatch none 0.5)
		(connect_pads
			(clearance 0)
		)
		(min_thickness 0.25)
		(keepout
			(tracks not_allowed)
			(vias allowed)
			(pads allowed)
			(copperpour not_allowed)
			(footprints allowed)
		)
		(placement
			(enabled no)
			(sheetname "")
		)
		(fill yes
			(thermal_gap 0.5)
			(thermal_bridge_width 0.5)
			(island_removal_mode 0)
		)
		(polygon
			(pts
				(arc
					(start 176.402238 -261.08533)
					(mid 175.741838 -261.08533)
					(end 176.402238 -261.08533)
				)
			)
		)
	)
	(zone
		(layers "In1.Cu" "In2.Cu")
		(hatch none 0.5)
		(connect_pads
			(clearance 0)
		)
		(min_thickness 0.25)
		(keepout
			(tracks not_allowed)
			(vias allowed)
			(pads allowed)
			(copperpour not_allowed)
			(footprints allowed)
		)
		(placement
			(enabled no)
			(sheetname "")
		)
		(fill yes
			(thermal_gap 0.5)
			(thermal_bridge_width 0.5)
			(island_removal_mode 0)
		)
		(polygon
			(pts
				(arc
					(start 399.941542 -11.91768)
					(mid 399.919224 -11.971562)
					(end 399.865342 -11.99388)
				)
				(arc
					(start 398.828768 -11.99388)
					(mid 398.774886 -11.971562)
					(end 398.752568 -11.91768)
				)
				(arc
					(start 398.752568 -10.51814)
					(mid 398.774886 -10.464258)
					(end 398.828768 -10.44194)
				)
				(arc
					(start 399.865342 -10.44194)
					(mid 399.919224 -10.464258)
					(end 399.941542 -10.51814)
				)
			)
		)
	)
	(zone
		(layers "In1.Cu" "In2.Cu")
		(hatch none 0.5)
		(connect_pads
			(clearance 0)
		)
		(min_thickness 0.25)
		(keepout
			(tracks not_allowed)
			(vias allowed)
			(pads allowed)
			(copperpour not_allowed)
			(footprints allowed)
		)
		(placement
			(enabled no)
			(sheetname "")
		)
		(fill yes
			(thermal_gap 0.5)
			(thermal_bridge_width 0.5)
			(island_removal_mode 0)
		)
		(polygon
			(pts
				(arc
					(start 454.518268 -238.13516)
					(mid 453.857868 -238.13516)
					(end 454.518268 -238.13516)
				)
			)
		)
	)
	(zone
		(layers "In1.Cu" "In2.Cu")
		(hatch none 0.5)
		(connect_pads
			(clearance 0)
		)
		(min_thickness 0.25)
		(keepout
			(tracks not_allowed)
			(vias allowed)
			(pads allowed)
			(copperpour not_allowed)
			(footprints allowed)
		)
		(placement
			(enabled no)
			(sheetname "")
		)
		(fill yes
			(thermal_gap 0.5)
			(thermal_bridge_width 0.5)
			(island_removal_mode 0)
		)
		(polygon
			(pts
				(arc
					(start 37.126164 -284.885384)
					(mid 36.465764 -284.885384)
					(end 37.126164 -284.885384)
				)
			)
		)
	)
	(zone
		(layers "In1.Cu" "In2.Cu")
		(hatch none 0.5)
		(connect_pads
			(clearance 0)
		)
		(min_thickness 0.25)
		(keepout
			(tracks not_allowed)
			(vias allowed)
			(pads allowed)
			(copperpour not_allowed)
			(footprints allowed)
		)
		(placement
			(enabled no)
			(sheetname "")
		)
		(fill yes
			(thermal_gap 0.5)
			(thermal_bridge_width 0.5)
			(island_removal_mode 0)
		)
		(polygon
			(pts
				(arc
					(start 296.054272 -210.935062)
					(mid 295.393872 -210.935062)
					(end 296.054272 -210.935062)
				)
			)
		)
	)
	(zone
		(layers "In1.Cu" "In2.Cu")
		(hatch none 0.5)
		(connect_pads
			(clearance 0)
		)
		(min_thickness 0.25)
		(keepout
			(tracks not_allowed)
			(vias allowed)
			(pads allowed)
			(copperpour not_allowed)
			(footprints allowed)
		)
		(placement
			(enabled no)
			(sheetname "")
		)
		(fill yes
			(thermal_gap 0.5)
			(thermal_bridge_width 0.5)
			(island_removal_mode 0)
		)
		(polygon
			(pts
				(arc
					(start 420.242238 -230.485188)
					(mid 419.581838 -230.485188)
					(end 420.242238 -230.485188)
				)
			)
		)
	)
	(zone
		(layers "In1.Cu" "In2.Cu")
		(hatch none 0.5)
		(connect_pads
			(clearance 0)
		)
		(min_thickness 0.25)
		(keepout
			(tracks not_allowed)
			(vias allowed)
			(pads allowed)
			(copperpour not_allowed)
			(footprints allowed)
		)
		(placement
			(enabled no)
			(sheetname "")
		)
		(fill yes
			(thermal_gap 0.5)
			(thermal_bridge_width 0.5)
			(island_removal_mode 0)
		)
		(polygon
			(pts
				(arc
					(start 273.422364 -285.735014)
					(mid 272.761964 -285.735014)
					(end 273.422364 -285.735014)
				)
			)
		)
	)
	(zone
		(layers "In1.Cu" "In2.Cu")
		(hatch none 0.5)
		(connect_pads
			(clearance 0)
		)
		(min_thickness 0.25)
		(keepout
			(tracks not_allowed)
			(vias allowed)
			(pads allowed)
			(copperpour not_allowed)
			(footprints allowed)
		)
		(placement
			(enabled no)
			(sheetname "")
		)
		(fill yes
			(thermal_gap 0.5)
			(thermal_bridge_width 0.5)
			(island_removal_mode 0)
		)
		(polygon
			(pts
				(arc
					(start 442.8744 -246.635016)
					(mid 442.214 -246.635016)
					(end 442.8744 -246.635016)
				)
			)
		)
	)
	(zone
		(layers "In1.Cu" "In2.Cu")
		(hatch none 0.5)
		(connect_pads
			(clearance 0)
		)
		(min_thickness 0.25)
		(keepout
			(tracks not_allowed)
			(vias allowed)
			(pads allowed)
			(copperpour not_allowed)
			(footprints allowed)
		)
		(placement
			(enabled no)
			(sheetname "")
		)
		(fill yes
			(thermal_gap 0.5)
			(thermal_bridge_width 0.5)
			(island_removal_mode 0)
		)
		(polygon
			(pts
				(arc
					(start 431.88636 -240.685066)
					(mid 431.22596 -240.685066)
					(end 431.88636 -240.685066)
				)
			)
		)
	)
	(zone
		(layers "In1.Cu" "In2.Cu")
		(hatch none 0.5)
		(connect_pads
			(clearance 0)
		)
		(min_thickness 0.25)
		(keepout
			(tracks not_allowed)
			(vias allowed)
			(pads allowed)
			(copperpour not_allowed)
			(footprints allowed)
		)
		(placement
			(enabled no)
			(sheetname "")
		)
		(fill yes
			(thermal_gap 0.5)
			(thermal_bridge_width 0.5)
			(island_removal_mode 0)
		)
		(polygon
			(pts
				(arc
					(start 277.522432 -294.235124)
					(mid 276.862032 -294.235124)
					(end 277.522432 -294.235124)
				)
			)
		)
	)
	(zone
		(layers "In1.Cu" "In2.Cu")
		(hatch none 0.5)
		(connect_pads
			(clearance 0)
		)
		(min_thickness 0.25)
		(keepout
			(tracks not_allowed)
			(vias allowed)
			(pads allowed)
			(copperpour not_allowed)
			(footprints allowed)
		)
		(placement
			(enabled no)
			(sheetname "")
		)
		(fill yes
			(thermal_gap 0.5)
			(thermal_bridge_width 0.5)
			(island_removal_mode 0)
		)
		(polygon
			(pts
				(arc
					(start 172.30217 -299.335444)
					(mid 171.64177 -299.335444)
					(end 172.30217 -299.335444)
				)
			)
		)
	)
	(zone
		(layers "In1.Cu" "In2.Cu")
		(hatch none 0.5)
		(connect_pads
			(clearance 0)
		)
		(min_thickness 0.25)
		(keepout
			(tracks not_allowed)
			(vias allowed)
			(pads allowed)
			(copperpour not_allowed)
			(footprints allowed)
		)
		(placement
			(enabled no)
			(sheetname "")
		)
		(fill yes
			(thermal_gap 0.5)
			(thermal_bridge_width 0.5)
			(island_removal_mode 0)
		)
		(polygon
			(pts
				(arc
					(start 401.309332 -417.242244)
					(mid 401.33165 -417.296126)
					(end 401.385532 -417.318444)
				)
				(arc
					(start 401.581112 -417.318444)
					(mid 401.602988 -417.315312)
					(end 401.623022 -417.305998)
				)
				(arc
					(start 401.916646 -417.113466)
					(mid 401.958302 -417.101064)
					(end 401.999958 -417.113466)
				)
				(arc
					(start 402.294852 -417.305998)
					(mid 402.314776 -417.315234)
					(end 402.336508 -417.318444)
				)
				(arc
					(start 402.531072 -417.318444)
					(mid 402.584954 -417.296126)
					(end 402.607272 -417.242244)
				)
				(arc
					(start 402.607272 -416.556444)
					(mid 402.584954 -416.502562)
					(end 402.531072 -416.480244)
				)
				(arc
					(start 402.336508 -416.480244)
					(mid 402.314764 -416.483412)
					(end 402.294852 -416.49269)
				)
				(arc
					(start 401.998688 -416.685476)
					(mid 401.957004 -416.697698)
					(end 401.915376 -416.685222)
				)
				(arc
					(start 401.621752 -416.49269)
					(mid 401.601828 -416.483454)
					(end 401.580096 -416.480244)
				)
				(arc
					(start 401.385532 -416.480244)
					(mid 401.33165 -416.502562)
					(end 401.309332 -416.556444)
				)
			)
		)
	)
	(zone
		(layers "In1.Cu" "In2.Cu")
		(hatch none 0.5)
		(connect_pads
			(clearance 0)
		)
		(min_thickness 0.25)
		(keepout
			(tracks not_allowed)
			(vias allowed)
			(pads allowed)
			(copperpour not_allowed)
			(footprints allowed)
		)
		(placement
			(enabled no)
			(sheetname "")
		)
		(fill yes
			(thermal_gap 0.5)
			(thermal_bridge_width 0.5)
			(island_removal_mode 0)
		)
		(polygon
			(pts
				(arc
					(start 424.342306 -296.78503)
					(mid 423.681906 -296.78503)
					(end 424.342306 -296.78503)
				)
			)
		)
	)
	(zone
		(layers "In1.Cu" "In2.Cu")
		(hatch none 0.5)
		(connect_pads
			(clearance 0)
		)
		(min_thickness 0.25)
		(keepout
			(tracks not_allowed)
			(vias allowed)
			(pads allowed)
			(copperpour not_allowed)
			(footprints allowed)
		)
		(placement
			(enabled no)
			(sheetname "")
		)
		(fill yes
			(thermal_gap 0.5)
			(thermal_bridge_width 0.5)
			(island_removal_mode 0)
		)
		(polygon
			(pts
				(arc
					(start 187.390278 -202.435206)
					(mid 186.729878 -202.435206)
					(end 187.390278 -202.435206)
				)
			)
		)
	)
	(zone
		(layers "In1.Cu" "In2.Cu")
		(hatch none 0.5)
		(connect_pads
			(clearance 0)
		)
		(min_thickness 0.25)
		(keepout
			(tracks not_allowed)
			(vias allowed)
			(pads allowed)
			(copperpour not_allowed)
			(footprints allowed)
		)
		(placement
			(enabled no)
			(sheetname "")
		)
		(fill yes
			(thermal_gap 0.5)
			(thermal_bridge_width 0.5)
			(island_removal_mode 0)
		)
		(polygon
			(pts
				(arc
					(start 442.8744 -288.285174)
					(mid 442.214 -288.285174)
					(end 442.8744 -288.285174)
				)
			)
		)
	)
	(zone
		(layers "In1.Cu" "In2.Cu")
		(hatch none 0.5)
		(connect_pads
			(clearance 0)
		)
		(min_thickness 0.25)
		(keepout
			(tracks not_allowed)
			(vias allowed)
			(pads allowed)
			(copperpour not_allowed)
			(footprints allowed)
		)
		(placement
			(enabled no)
			(sheetname "")
		)
		(fill yes
			(thermal_gap 0.5)
			(thermal_bridge_width 0.5)
			(island_removal_mode 0)
		)
		(polygon
			(pts
				(arc
					(start 292.610286 -206.685134)
					(mid 291.949886 -206.685134)
					(end 292.610286 -206.685134)
				)
			)
		)
	)
	(zone
		(layers "In1.Cu" "In2.Cu")
		(hatch none 0.5)
		(connect_pads
			(clearance 0)
		)
		(min_thickness 0.25)
		(keepout
			(tracks not_allowed)
			(vias allowed)
			(pads allowed)
			(copperpour not_allowed)
			(footprints allowed)
		)
		(placement
			(enabled no)
			(sheetname "")
		)
		(fill yes
			(thermal_gap 0.5)
			(thermal_bridge_width 0.5)
			(island_removal_mode 0)
		)
		(polygon
			(pts
				(arc
					(start 300.15434 -313.784996)
					(mid 299.49394 -313.784996)
					(end 300.15434 -313.784996)
				)
			)
		)
	)
	(zone
		(layers "In1.Cu" "In2.Cu")
		(hatch none 0.5)
		(connect_pads
			(clearance 0)
		)
		(min_thickness 0.25)
		(keepout
			(tracks not_allowed)
			(vias allowed)
			(pads allowed)
			(copperpour not_allowed)
			(footprints allowed)
		)
		(placement
			(enabled no)
			(sheetname "")
		)
		(fill yes
			(thermal_gap 0.5)
			(thermal_bridge_width 0.5)
			(island_removal_mode 0)
		)
		(polygon
			(pts
				(arc
					(start 288.510218 -226.235006)
					(mid 287.849818 -226.235006)
					(end 288.510218 -226.235006)
				)
			)
		)
	)
	(zone
		(layers "In1.Cu" "In2.Cu")
		(hatch none 0.5)
		(connect_pads
			(clearance 0)
		)
		(min_thickness 0.25)
		(keepout
			(tracks not_allowed)
			(vias allowed)
			(pads allowed)
			(copperpour not_allowed)
			(footprints allowed)
		)
		(placement
			(enabled no)
			(sheetname "")
		)
		(fill yes
			(thermal_gap 0.5)
			(thermal_bridge_width 0.5)
			(island_removal_mode 0)
		)
		(polygon
			(pts
				(arc
					(start 395.182852 -417.242244)
					(mid 395.20517 -417.296126)
					(end 395.259052 -417.318444)
				)
				(arc
					(start 395.454632 -417.318444)
					(mid 395.476508 -417.315312)
					(end 395.496542 -417.305998)
				)
				(arc
					(start 395.790166 -417.113466)
					(mid 395.831822 -417.101064)
					(end 395.873478 -417.113466)
				)
				(arc
					(start 396.168372 -417.305998)
					(mid 396.188296 -417.315234)
					(end 396.210028 -417.318444)
				)
				(arc
					(start 396.404592 -417.318444)
					(mid 396.458474 -417.296126)
					(end 396.480792 -417.242244)
				)
				(arc
					(start 396.480792 -416.556444)
					(mid 396.458474 -416.502562)
					(end 396.404592 -416.480244)
				)
				(arc
					(start 396.210028 -416.480244)
					(mid 396.188284 -416.483412)
					(end 396.168372 -416.49269)
				)
				(arc
					(start 395.872208 -416.685476)
					(mid 395.830524 -416.697698)
					(end 395.788896 -416.685222)
				)
				(arc
					(start 395.495272 -416.49269)
					(mid 395.475348 -416.483454)
					(end 395.453616 -416.480244)
				)
				(arc
					(start 395.259052 -416.480244)
					(mid 395.20517 -416.502562)
					(end 395.182852 -416.556444)
				)
			)
		)
	)
	(zone
		(layers "In1.Cu" "In2.Cu")
		(hatch none 0.5)
		(connect_pads
			(clearance 0)
		)
		(min_thickness 0.25)
		(keepout
			(tracks not_allowed)
			(vias allowed)
			(pads allowed)
			(copperpour not_allowed)
			(footprints allowed)
		)
		(placement
			(enabled no)
			(sheetname "")
		)
		(fill yes
			(thermal_gap 0.5)
			(thermal_bridge_width 0.5)
			(island_removal_mode 0)
		)
		(polygon
			(pts
				(arc
					(start 296.054272 -286.585152)
					(mid 295.393872 -286.585152)
					(end 296.054272 -286.585152)
				)
			)
		)
	)
	(zone
		(layers "In1.Cu" "In2.Cu")
		(hatch none 0.5)
		(connect_pads
			(clearance 0)
		)
		(min_thickness 0.25)
		(keepout
			(tracks not_allowed)
			(vias allowed)
			(pads allowed)
			(copperpour not_allowed)
			(footprints allowed)
		)
		(placement
			(enabled no)
			(sheetname "")
		)
		(fill yes
			(thermal_gap 0.5)
			(thermal_bridge_width 0.5)
			(island_removal_mode 0)
		)
		(polygon
			(pts
				(arc
					(start 420.242238 -235.585)
					(mid 419.581838 -235.585)
					(end 420.242238 -235.585)
				)
			)
		)
	)
	(zone
		(layers "In1.Cu" "In2.Cu")
		(hatch none 0.5)
		(connect_pads
			(clearance 0)
		)
		(min_thickness 0.25)
		(keepout
			(tracks not_allowed)
			(vias allowed)
			(pads allowed)
			(copperpour not_allowed)
			(footprints allowed)
		)
		(placement
			(enabled no)
			(sheetname "")
		)
		(fill yes
			(thermal_gap 0.5)
			(thermal_bridge_width 0.5)
			(island_removal_mode 0)
		)
		(polygon
			(pts
				(arc
					(start 420.242238 -229.63505)
					(mid 419.581838 -229.63505)
					(end 420.242238 -229.63505)
				)
			)
		)
	)
	(zone
		(layers "In1.Cu" "In2.Cu")
		(hatch none 0.5)
		(connect_pads
			(clearance 0)
		)
		(min_thickness 0.25)
		(keepout
			(tracks not_allowed)
			(vias allowed)
			(pads allowed)
			(copperpour not_allowed)
			(footprints allowed)
		)
		(placement
			(enabled no)
			(sheetname "")
		)
		(fill yes
			(thermal_gap 0.5)
			(thermal_bridge_width 0.5)
			(island_removal_mode 0)
		)
		(polygon
			(pts
				(arc
					(start 29.582364 -206.685388)
					(mid 28.921964 -206.685388)
					(end 29.582364 -206.685388)
				)
			)
		)
	)
	(zone
		(layers "In1.Cu" "In2.Cu")
		(hatch none 0.5)
		(connect_pads
			(clearance 0)
		)
		(min_thickness 0.25)
		(keepout
			(tracks not_allowed)
			(vias allowed)
			(pads allowed)
			(copperpour not_allowed)
			(footprints allowed)
		)
		(placement
			(enabled no)
			(sheetname "")
		)
		(fill yes
			(thermal_gap 0.5)
			(thermal_bridge_width 0.5)
			(island_removal_mode 0)
		)
		(polygon
			(pts
				(arc
					(start 176.402238 -292.535356)
					(mid 175.741838 -292.535356)
					(end 176.402238 -292.535356)
				)
			)
		)
	)
	(zone
		(layers "In1.Cu" "In2.Cu")
		(hatch none 0.5)
		(connect_pads
			(clearance 0)
		)
		(min_thickness 0.25)
		(keepout
			(tracks not_allowed)
			(vias allowed)
			(pads allowed)
			(copperpour not_allowed)
			(footprints allowed)
		)
		(placement
			(enabled no)
			(sheetname "")
		)
		(fill yes
			(thermal_gap 0.5)
			(thermal_bridge_width 0.5)
			(island_removal_mode 0)
		)
		(polygon
			(pts
				(arc
					(start 37.126164 -244.085364)
					(mid 36.465764 -244.085364)
					(end 37.126164 -244.085364)
				)
			)
		)
	)
	(zone
		(layers "In1.Cu" "In2.Cu")
		(hatch none 0.5)
		(connect_pads
			(clearance 0)
		)
		(min_thickness 0.25)
		(keepout
			(tracks not_allowed)
			(vias allowed)
			(pads allowed)
			(copperpour not_allowed)
			(footprints allowed)
		)
		(placement
			(enabled no)
			(sheetname "")
		)
		(fill yes
			(thermal_gap 0.5)
			(thermal_bridge_width 0.5)
			(island_removal_mode 0)
		)
		(polygon
			(pts
				(arc
					(start 179.846224 -218.585288)
					(mid 179.185824 -218.585288)
					(end 179.846224 -218.585288)
				)
			)
		)
	)
	(zone
		(layers "In1.Cu" "In2.Cu")
		(hatch none 0.5)
		(connect_pads
			(clearance 0)
		)
		(min_thickness 0.25)
		(keepout
			(tracks not_allowed)
			(vias allowed)
			(pads allowed)
			(copperpour not_allowed)
			(footprints allowed)
		)
		(placement
			(enabled no)
			(sheetname "")
		)
		(fill yes
			(thermal_gap 0.5)
			(thermal_bridge_width 0.5)
			(island_removal_mode 0)
		)
		(polygon
			(pts
				(arc
					(start 446.974468 -254.284988)
					(mid 446.314068 -254.284988)
					(end 446.974468 -254.284988)
				)
			)
		)
	)
	(zone
		(layers "In1.Cu" "In2.Cu")
		(hatch none 0.5)
		(connect_pads
			(clearance 0)
		)
		(min_thickness 0.25)
		(keepout
			(tracks not_allowed)
			(vias allowed)
			(pads allowed)
			(copperpour not_allowed)
			(footprints allowed)
		)
		(placement
			(enabled no)
			(sheetname "")
		)
		(fill yes
			(thermal_gap 0.5)
			(thermal_bridge_width 0.5)
			(island_removal_mode 0)
		)
		(polygon
			(pts
				(arc
					(start 180.121814 -47.932848)
					(mid 180.112578 -47.952772)
					(end 180.109368 -47.974504)
				)
				(arc
					(start 180.109368 -48.169068)
					(mid 180.131686 -48.22295)
					(end 180.185568 -48.245268)
				)
				(arc
					(start 180.871368 -48.245268)
					(mid 180.92525 -48.22295)
					(end 180.947568 -48.169068)
				)
				(arc
					(start 180.947568 -47.974504)
					(mid 180.9444 -47.95276)
					(end 180.935122 -47.932848)
				)
				(arc
					(start 180.742336 -47.636684)
					(mid 180.730114 -47.595)
					(end 180.74259 -47.553372)
				)
				(arc
					(start 180.935122 -47.259748)
					(mid 180.944358 -47.239824)
					(end 180.947568 -47.218092)
				)
				(arc
					(start 180.947568 -47.023528)
					(mid 180.92525 -46.969646)
					(end 180.871368 -46.947328)
				)
				(arc
					(start 180.185568 -46.947328)
					(mid 180.131686 -46.969646)
					(end 180.109368 -47.023528)
				)
				(arc
					(start 180.109368 -47.219362)
					(mid 180.112536 -47.241106)
					(end 180.121814 -47.261018)
				)
				(arc
					(start 180.314346 -47.554642)
					(mid 180.326748 -47.596298)
					(end 180.314346 -47.637954)
				)
			)
		)
	)
	(zone
		(layers "In1.Cu" "In2.Cu")
		(hatch none 0.5)
		(connect_pads
			(clearance 0)
		)
		(min_thickness 0.25)
		(keepout
			(tracks not_allowed)
			(vias allowed)
			(pads allowed)
			(copperpour not_allowed)
			(footprints allowed)
		)
		(placement
			(enabled no)
			(sheetname "")
		)
		(fill yes
			(thermal_gap 0.5)
			(thermal_bridge_width 0.5)
			(island_removal_mode 0)
		)
		(polygon
			(pts
				(arc
					(start 280.966164 -313.784996)
					(mid 280.305764 -313.784996)
					(end 280.966164 -313.784996)
				)
			)
		)
	)
	(zone
		(layers "In1.Cu" "In2.Cu")
		(hatch none 0.5)
		(connect_pads
			(clearance 0)
		)
		(min_thickness 0.25)
		(keepout
			(tracks not_allowed)
			(vias allowed)
			(pads allowed)
			(copperpour not_allowed)
			(footprints allowed)
		)
		(placement
			(enabled no)
			(sheetname "")
		)
		(fill yes
			(thermal_gap 0.5)
			(thermal_bridge_width 0.5)
			(island_removal_mode 0)
		)
		(polygon
			(pts
				(arc
					(start 23.641558 -11.91768)
					(mid 23.61924 -11.971562)
					(end 23.565358 -11.99388)
				)
				(arc
					(start 22.528784 -11.99388)
					(mid 22.474902 -11.971562)
					(end 22.452584 -11.91768)
				)
				(arc
					(start 22.452584 -10.51814)
					(mid 22.474902 -10.464258)
					(end 22.528784 -10.44194)
				)
				(arc
					(start 23.565358 -10.44194)
					(mid 23.61924 -10.464258)
					(end 23.641558 -10.51814)
				)
			)
		)
	)
	(zone
		(layers "In1.Cu" "In2.Cu")
		(hatch none 0.5)
		(connect_pads
			(clearance 0)
		)
		(min_thickness 0.25)
		(keepout
			(tracks not_allowed)
			(vias allowed)
			(pads allowed)
			(copperpour not_allowed)
			(footprints allowed)
		)
		(placement
			(enabled no)
			(sheetname "")
		)
		(fill yes
			(thermal_gap 0.5)
			(thermal_bridge_width 0.5)
			(island_removal_mode 0)
		)
		(polygon
			(pts
				(arc
					(start 420.242238 -224.534984)
					(mid 419.581838 -224.534984)
					(end 420.242238 -224.534984)
				)
			)
		)
	)
	(zone
		(layers "In1.Cu" "In2.Cu")
		(hatch none 0.5)
		(connect_pads
			(clearance 0)
		)
		(min_thickness 0.25)
		(keepout
			(tracks not_allowed)
			(vias allowed)
			(pads allowed)
			(copperpour not_allowed)
			(footprints allowed)
		)
		(placement
			(enabled no)
			(sheetname "")
		)
		(fill yes
			(thermal_gap 0.5)
			(thermal_bridge_width 0.5)
			(island_removal_mode 0)
		)
		(polygon
			(pts
				(arc
					(start 22.03831 -223.685354)
					(mid 21.37791 -223.685354)
					(end 22.03831 -223.685354)
				)
			)
		)
	)
	(zone
		(layers "In1.Cu" "In2.Cu")
		(hatch none 0.5)
		(connect_pads
			(clearance 0)
		)
		(min_thickness 0.25)
		(keepout
			(tracks not_allowed)
			(vias allowed)
			(pads allowed)
			(copperpour not_allowed)
			(footprints allowed)
		)
		(placement
			(enabled no)
			(sheetname "")
		)
		(fill yes
			(thermal_gap 0.5)
			(thermal_bridge_width 0.5)
			(island_removal_mode 0)
		)
		(polygon
			(pts
				(arc
					(start 98.434652 -370.978684)
					(mid 98.454576 -370.98792)
					(end 98.476308 -370.99113)
				)
				(arc
					(start 98.670872 -370.99113)
					(mid 98.724754 -370.968812)
					(end 98.747072 -370.91493)
				)
				(arc
					(start 98.747072 -370.22913)
					(mid 98.724754 -370.175248)
					(end 98.670872 -370.15293)
				)
				(arc
					(start 98.476308 -370.15293)
					(mid 98.454564 -370.156098)
					(end 98.434652 -370.165376)
				)
				(arc
					(start 98.138488 -370.358162)
					(mid 98.096804 -370.370384)
					(end 98.055176 -370.357908)
				)
				(arc
					(start 97.761552 -370.165376)
					(mid 97.741628 -370.15614)
					(end 97.719896 -370.15293)
				)
				(arc
					(start 97.525332 -370.15293)
					(mid 97.47145 -370.175248)
					(end 97.449132 -370.22913)
				)
				(arc
					(start 97.449132 -370.91493)
					(mid 97.47145 -370.968812)
					(end 97.525332 -370.99113)
				)
				(arc
					(start 97.721166 -370.99113)
					(mid 97.74291 -370.987962)
					(end 97.762822 -370.978684)
				)
				(arc
					(start 98.056446 -370.786152)
					(mid 98.098102 -370.77375)
					(end 98.139758 -370.786152)
				)
			)
		)
	)
	(zone
		(layers "In1.Cu" "In2.Cu")
		(hatch none 0.5)
		(connect_pads
			(clearance 0)
		)
		(min_thickness 0.25)
		(keepout
			(tracks not_allowed)
			(vias allowed)
			(pads allowed)
			(copperpour not_allowed)
			(footprints allowed)
		)
		(placement
			(enabled no)
			(sheetname "")
		)
		(fill yes
			(thermal_gap 0.5)
			(thermal_bridge_width 0.5)
			(island_removal_mode 0)
		)
		(polygon
			(pts
				(arc
					(start 191.490346 -315.485272)
					(mid 190.829946 -315.485272)
					(end 191.490346 -315.485272)
				)
			)
		)
	)
	(zone
		(layers "In1.Cu" "In2.Cu")
		(hatch none 0.5)
		(connect_pads
			(clearance 0)
		)
		(min_thickness 0.25)
		(keepout
			(tracks not_allowed)
			(vias allowed)
			(pads allowed)
			(copperpour not_allowed)
			(footprints allowed)
		)
		(placement
			(enabled no)
			(sheetname "")
		)
		(fill yes
			(thermal_gap 0.5)
			(thermal_bridge_width 0.5)
			(island_removal_mode 0)
		)
		(polygon
			(pts
				(arc
					(start 285.066232 -200.735184)
					(mid 284.405832 -200.735184)
					(end 285.066232 -200.735184)
				)
			)
		)
	)
	(zone
		(layers "In1.Cu" "In2.Cu")
		(hatch none 0.5)
		(connect_pads
			(clearance 0)
		)
		(min_thickness 0.25)
		(keepout
			(tracks not_allowed)
			(vias allowed)
			(pads allowed)
			(copperpour not_allowed)
			(footprints allowed)
		)
		(placement
			(enabled no)
			(sheetname "")
		)
		(fill yes
			(thermal_gap 0.5)
			(thermal_bridge_width 0.5)
			(island_removal_mode 0)
		)
		(polygon
			(pts
				(arc
					(start 280.966164 -233.884978)
					(mid 280.305764 -233.884978)
					(end 280.966164 -233.884978)
				)
			)
		)
	)
	(zone
		(layers "In1.Cu" "In2.Cu")
		(hatch none 0.5)
		(connect_pads
			(clearance 0)
		)
		(min_thickness 0.25)
		(keepout
			(tracks not_allowed)
			(vias allowed)
			(pads allowed)
			(copperpour not_allowed)
			(footprints allowed)
		)
		(placement
			(enabled no)
			(sheetname "")
		)
		(fill yes
			(thermal_gap 0.5)
			(thermal_bridge_width 0.5)
			(island_removal_mode 0)
		)
		(polygon
			(pts
				(arc
					(start 292.610286 -238.985044)
					(mid 291.949886 -238.985044)
					(end 292.610286 -238.985044)
				)
			)
		)
	)
	(zone
		(layers "In1.Cu" "In2.Cu")
		(hatch none 0.5)
		(connect_pads
			(clearance 0)
		)
		(min_thickness 0.25)
		(keepout
			(tracks not_allowed)
			(vias allowed)
			(pads allowed)
			(copperpour not_allowed)
			(footprints allowed)
		)
		(placement
			(enabled no)
			(sheetname "")
		)
		(fill yes
			(thermal_gap 0.5)
			(thermal_bridge_width 0.5)
			(island_removal_mode 0)
		)
		(polygon
			(pts
				(arc
					(start 176.402238 -212.635338)
					(mid 175.741838 -212.635338)
					(end 176.402238 -212.635338)
				)
			)
		)
	)
	(zone
		(layers "In1.Cu" "In2.Cu")
		(hatch none 0.5)
		(connect_pads
			(clearance 0)
		)
		(min_thickness 0.25)
		(keepout
			(tracks not_allowed)
			(vias allowed)
			(pads allowed)
			(copperpour not_allowed)
			(footprints allowed)
		)
		(placement
			(enabled no)
			(sheetname "")
		)
		(fill yes
			(thermal_gap 0.5)
			(thermal_bridge_width 0.5)
			(island_removal_mode 0)
		)
		(polygon
			(pts
				(arc
					(start 269.978378 -289.135058)
					(mid 269.317978 -289.135058)
					(end 269.978378 -289.135058)
				)
			)
		)
	)
	(zone
		(layers "In1.Cu" "In2.Cu")
		(hatch none 0.5)
		(connect_pads
			(clearance 0)
		)
		(min_thickness 0.25)
		(keepout
			(tracks not_allowed)
			(vias allowed)
			(pads allowed)
			(copperpour not_allowed)
			(footprints allowed)
		)
		(placement
			(enabled no)
			(sheetname "")
		)
		(fill yes
			(thermal_gap 0.5)
			(thermal_bridge_width 0.5)
			(island_removal_mode 0)
		)
		(polygon
			(pts
				(arc
					(start 183.946292 -298.485306)
					(mid 183.285892 -298.485306)
					(end 183.946292 -298.485306)
				)
			)
		)
	)
	(zone
		(layers "In1.Cu" "In2.Cu")
		(hatch none 0.5)
		(connect_pads
			(clearance 0)
		)
		(min_thickness 0.25)
		(keepout
			(tracks not_allowed)
			(vias allowed)
			(pads allowed)
			(copperpour not_allowed)
			(footprints allowed)
		)
		(placement
			(enabled no)
			(sheetname "")
		)
		(fill yes
			(thermal_gap 0.5)
			(thermal_bridge_width 0.5)
			(island_removal_mode 0)
		)
		(polygon
			(pts
				(arc
					(start 176.402238 -223.685354)
					(mid 175.741838 -223.685354)
					(end 176.402238 -223.685354)
				)
			)
		)
	)
	(zone
		(layers "In1.Cu" "In2.Cu")
		(hatch none 0.5)
		(connect_pads
			(clearance 0)
		)
		(min_thickness 0.25)
		(keepout
			(tracks not_allowed)
			(vias allowed)
			(pads allowed)
			(copperpour not_allowed)
			(footprints allowed)
		)
		(placement
			(enabled no)
			(sheetname "")
		)
		(fill yes
			(thermal_gap 0.5)
			(thermal_bridge_width 0.5)
			(island_removal_mode 0)
		)
		(polygon
			(pts
				(arc
					(start 176.402238 -250.885198)
					(mid 175.741838 -250.885198)
					(end 176.402238 -250.885198)
				)
			)
		)
	)
	(zone
		(layers "In1.Cu" "In2.Cu")
		(hatch none 0.5)
		(connect_pads
			(clearance 0)
		)
		(min_thickness 0.25)
		(keepout
			(tracks not_allowed)
			(vias allowed)
			(pads allowed)
			(copperpour not_allowed)
			(footprints allowed)
		)
		(placement
			(enabled no)
			(sheetname "")
		)
		(fill yes
			(thermal_gap 0.5)
			(thermal_bridge_width 0.5)
			(island_removal_mode 0)
		)
		(polygon
			(pts
				(arc
					(start 44.670218 -279.785318)
					(mid 44.009818 -279.785318)
					(end 44.670218 -279.785318)
				)
			)
		)
	)
	(zone
		(layers "In1.Cu" "In2.Cu")
		(hatch none 0.5)
		(connect_pads
			(clearance 0)
		)
		(min_thickness 0.25)
		(keepout
			(tracks not_allowed)
			(vias allowed)
			(pads allowed)
			(copperpour not_allowed)
			(footprints allowed)
		)
		(placement
			(enabled no)
			(sheetname "")
		)
		(fill yes
			(thermal_gap 0.5)
			(thermal_bridge_width 0.5)
			(island_removal_mode 0)
		)
		(polygon
			(pts
				(arc
					(start 199.0344 -227.085398)
					(mid 198.374 -227.085398)
					(end 199.0344 -227.085398)
				)
			)
		)
	)
	(zone
		(layers "In1.Cu" "In2.Cu")
		(hatch none 0.5)
		(connect_pads
			(clearance 0)
		)
		(min_thickness 0.25)
		(keepout
			(tracks not_allowed)
			(vias allowed)
			(pads allowed)
			(copperpour not_allowed)
			(footprints allowed)
		)
		(placement
			(enabled no)
			(sheetname "")
		)
		(fill yes
			(thermal_gap 0.5)
			(thermal_bridge_width 0.5)
			(island_removal_mode 0)
		)
		(polygon
			(pts
				(arc
					(start 431.88636 -313.784996)
					(mid 431.22596 -313.784996)
					(end 431.88636 -313.784996)
				)
			)
		)
	)
	(zone
		(layers "In1.Cu" "In2.Cu")
		(hatch none 0.5)
		(connect_pads
			(clearance 0)
		)
		(min_thickness 0.25)
		(keepout
			(tracks not_allowed)
			(vias allowed)
			(pads allowed)
			(copperpour not_allowed)
			(footprints allowed)
		)
		(placement
			(enabled no)
			(sheetname "")
		)
		(fill yes
			(thermal_gap 0.5)
			(thermal_bridge_width 0.5)
			(island_removal_mode 0)
		)
		(polygon
			(pts
				(arc
					(start 37.126164 -283.185362)
					(mid 36.465764 -283.185362)
					(end 37.126164 -283.185362)
				)
			)
		)
	)
	(zone
		(layers "In1.Cu" "In2.Cu")
		(hatch none 0.5)
		(connect_pads
			(clearance 0)
		)
		(min_thickness 0.25)
		(keepout
			(tracks not_allowed)
			(vias allowed)
			(pads allowed)
			(copperpour not_allowed)
			(footprints allowed)
		)
		(placement
			(enabled no)
			(sheetname "")
		)
		(fill yes
			(thermal_gap 0.5)
			(thermal_bridge_width 0.5)
			(island_removal_mode 0)
		)
		(polygon
			(pts
				(arc
					(start 273.422364 -227.935028)
					(mid 272.761964 -227.935028)
					(end 273.422364 -227.935028)
				)
			)
		)
	)
	(zone
		(layers "In1.Cu" "In2.Cu")
		(hatch none 0.5)
		(connect_pads
			(clearance 0)
		)
		(min_thickness 0.25)
		(keepout
			(tracks not_allowed)
			(vias allowed)
			(pads allowed)
			(copperpour not_allowed)
			(footprints allowed)
		)
		(placement
			(enabled no)
			(sheetname "")
		)
		(fill yes
			(thermal_gap 0.5)
			(thermal_bridge_width 0.5)
			(island_removal_mode 0)
		)
		(polygon
			(pts
				(arc
					(start 273.422364 -251.735082)
					(mid 272.761964 -251.735082)
					(end 273.422364 -251.735082)
				)
			)
		)
	)
	(zone
		(layers "In1.Cu" "In2.Cu")
		(hatch none 0.5)
		(connect_pads
			(clearance 0)
		)
		(min_thickness 0.25)
		(keepout
			(tracks not_allowed)
			(vias allowed)
			(pads allowed)
			(copperpour not_allowed)
			(footprints allowed)
		)
		(placement
			(enabled no)
			(sheetname "")
		)
		(fill yes
			(thermal_gap 0.5)
			(thermal_bridge_width 0.5)
			(island_removal_mode 0)
		)
		(polygon
			(pts
				(arc
					(start 40.57015 -276.385274)
					(mid 39.90975 -276.385274)
					(end 40.57015 -276.385274)
				)
			)
		)
	)
	(zone
		(layers "In1.Cu" "In2.Cu")
		(hatch none 0.5)
		(connect_pads
			(clearance 0)
		)
		(min_thickness 0.25)
		(keepout
			(tracks not_allowed)
			(vias allowed)
			(pads allowed)
			(copperpour not_allowed)
			(footprints allowed)
		)
		(placement
			(enabled no)
			(sheetname "")
		)
		(fill yes
			(thermal_gap 0.5)
			(thermal_bridge_width 0.5)
			(island_removal_mode 0)
		)
		(polygon
			(pts
				(arc
					(start 48.114204 -201.585322)
					(mid 47.453804 -201.585322)
					(end 48.114204 -201.585322)
				)
			)
		)
	)
	(zone
		(layers "In1.Cu" "In2.Cu")
		(hatch none 0.5)
		(connect_pads
			(clearance 0)
		)
		(min_thickness 0.25)
		(keepout
			(tracks not_allowed)
			(vias allowed)
			(pads allowed)
			(copperpour not_allowed)
			(footprints allowed)
		)
		(placement
			(enabled no)
			(sheetname "")
		)
		(fill yes
			(thermal_gap 0.5)
			(thermal_bridge_width 0.5)
			(island_removal_mode 0)
		)
		(polygon
			(pts
				(arc
					(start 29.582364 -229.635304)
					(mid 28.921964 -229.635304)
					(end 29.582364 -229.635304)
				)
			)
		)
	)
	(zone
		(layers "In1.Cu" "In2.Cu")
		(hatch none 0.5)
		(connect_pads
			(clearance 0)
		)
		(min_thickness 0.25)
		(keepout
			(tracks not_allowed)
			(vias allowed)
			(pads allowed)
			(copperpour not_allowed)
			(footprints allowed)
		)
		(placement
			(enabled no)
			(sheetname "")
		)
		(fill yes
			(thermal_gap 0.5)
			(thermal_bridge_width 0.5)
			(island_removal_mode 0)
		)
		(polygon
			(pts
				(arc
					(start 435.330346 -253.435104)
					(mid 434.669946 -253.435104)
					(end 435.330346 -253.435104)
				)
			)
		)
	)
	(zone
		(layers "In1.Cu" "In2.Cu")
		(hatch none 0.5)
		(connect_pads
			(clearance 0)
		)
		(min_thickness 0.25)
		(keepout
			(tracks not_allowed)
			(vias allowed)
			(pads allowed)
			(copperpour not_allowed)
			(footprints allowed)
		)
		(placement
			(enabled no)
			(sheetname "")
		)
		(fill yes
			(thermal_gap 0.5)
			(thermal_bridge_width 0.5)
			(island_removal_mode 0)
		)
		(polygon
			(pts
				(arc
					(start 450.4182 -202.434952)
					(mid 449.7578 -202.434952)
					(end 450.4182 -202.434952)
				)
			)
		)
	)
	(zone
		(layers "In1.Cu" "In2.Cu")
		(hatch none 0.5)
		(connect_pads
			(clearance 0)
		)
		(min_thickness 0.25)
		(keepout
			(tracks not_allowed)
			(vias allowed)
			(pads allowed)
			(copperpour not_allowed)
			(footprints allowed)
		)
		(placement
			(enabled no)
			(sheetname "")
		)
		(fill yes
			(thermal_gap 0.5)
			(thermal_bridge_width 0.5)
			(island_removal_mode 0)
		)
		(polygon
			(pts
				(arc
					(start 22.03831 -264.485374)
					(mid 21.37791 -264.485374)
					(end 22.03831 -264.485374)
				)
			)
		)
	)
	(zone
		(layers "In1.Cu" "In2.Cu")
		(hatch none 0.5)
		(connect_pads
			(clearance 0)
		)
		(min_thickness 0.25)
		(keepout
			(tracks not_allowed)
			(vias allowed)
			(pads allowed)
			(copperpour not_allowed)
			(footprints allowed)
		)
		(placement
			(enabled no)
			(sheetname "")
		)
		(fill yes
			(thermal_gap 0.5)
			(thermal_bridge_width 0.5)
			(island_removal_mode 0)
		)
		(polygon
			(pts
				(arc
					(start 273.422364 -210.935062)
					(mid 272.761964 -210.935062)
					(end 273.422364 -210.935062)
				)
			)
		)
	)
	(zone
		(layers "In1.Cu" "In2.Cu")
		(hatch none 0.5)
		(connect_pads
			(clearance 0)
		)
		(min_thickness 0.25)
		(keepout
			(tracks not_allowed)
			(vias allowed)
			(pads allowed)
			(copperpour not_allowed)
			(footprints allowed)
		)
		(placement
			(enabled no)
			(sheetname "")
		)
		(fill yes
			(thermal_gap 0.5)
			(thermal_bridge_width 0.5)
			(island_removal_mode 0)
		)
		(polygon
			(pts
				(arc
					(start 273.422364 -254.284988)
					(mid 272.761964 -254.284988)
					(end 273.422364 -254.284988)
				)
			)
		)
	)
	(zone
		(layers "In1.Cu" "In2.Cu")
		(hatch none 0.5)
		(connect_pads
			(clearance 0)
		)
		(min_thickness 0.25)
		(keepout
			(tracks not_allowed)
			(vias allowed)
			(pads allowed)
			(copperpour not_allowed)
			(footprints allowed)
		)
		(placement
			(enabled no)
			(sheetname "")
		)
		(fill yes
			(thermal_gap 0.5)
			(thermal_bridge_width 0.5)
			(island_removal_mode 0)
		)
		(polygon
			(pts
				(arc
					(start 48.114204 -263.635236)
					(mid 47.453804 -263.635236)
					(end 48.114204 -263.635236)
				)
			)
		)
	)
	(zone
		(layers "In1.Cu" "In2.Cu")
		(hatch none 0.5)
		(connect_pads
			(clearance 0)
		)
		(min_thickness 0.25)
		(keepout
			(tracks not_allowed)
			(vias allowed)
			(pads allowed)
			(copperpour not_allowed)
			(footprints allowed)
		)
		(placement
			(enabled no)
			(sheetname "")
		)
		(fill yes
			(thermal_gap 0.5)
			(thermal_bridge_width 0.5)
			(island_removal_mode 0)
		)
		(polygon
			(pts
				(arc
					(start 454.518268 -269.585186)
					(mid 453.857868 -269.585186)
					(end 454.518268 -269.585186)
				)
			)
		)
	)
	(zone
		(layers "In1.Cu" "In2.Cu")
		(hatch none 0.5)
		(connect_pads
			(clearance 0)
		)
		(min_thickness 0.25)
		(keepout
			(tracks not_allowed)
			(vias allowed)
			(pads allowed)
			(copperpour not_allowed)
			(footprints allowed)
		)
		(placement
			(enabled no)
			(sheetname "")
		)
		(fill yes
			(thermal_gap 0.5)
			(thermal_bridge_width 0.5)
			(island_removal_mode 0)
		)
		(polygon
			(pts
				(arc
					(start 439.430414 -283.185108)
					(mid 438.770014 -283.185108)
					(end 439.430414 -283.185108)
				)
			)
		)
	)
	(zone
		(layers "In1.Cu" "In2.Cu")
		(hatch none 0.5)
		(connect_pads
			(clearance 0)
		)
		(min_thickness 0.25)
		(keepout
			(tracks not_allowed)
			(vias allowed)
			(pads allowed)
			(copperpour not_allowed)
			(footprints allowed)
		)
		(placement
			(enabled no)
			(sheetname "")
		)
		(fill yes
			(thermal_gap 0.5)
			(thermal_bridge_width 0.5)
			(island_removal_mode 0)
		)
		(polygon
			(pts
				(arc
					(start 277.522432 -276.38502)
					(mid 276.862032 -276.38502)
					(end 277.522432 -276.38502)
				)
			)
		)
	)
	(zone
		(layers "In1.Cu" "In2.Cu")
		(hatch none 0.5)
		(connect_pads
			(clearance 0)
		)
		(min_thickness 0.25)
		(keepout
			(tracks not_allowed)
			(vias allowed)
			(pads allowed)
			(copperpour not_allowed)
			(footprints allowed)
		)
		(placement
			(enabled no)
			(sheetname "")
		)
		(fill yes
			(thermal_gap 0.5)
			(thermal_bridge_width 0.5)
			(island_removal_mode 0)
		)
		(polygon
			(pts
				(arc
					(start 37.126164 -244.08511)
					(mid 36.465764 -244.08511)
					(end 37.126164 -244.08511)
				)
			)
		)
	)
	(zone
		(layers "In1.Cu" "In2.Cu")
		(hatch none 0.5)
		(connect_pads
			(clearance 0)
		)
		(min_thickness 0.25)
		(keepout
			(tracks not_allowed)
			(vias allowed)
			(pads allowed)
			(copperpour not_allowed)
			(footprints allowed)
		)
		(placement
			(enabled no)
			(sheetname "")
		)
		(fill yes
			(thermal_gap 0.5)
			(thermal_bridge_width 0.5)
			(island_removal_mode 0)
		)
		(polygon
			(pts
				(arc
					(start 427.786292 -243.234972)
					(mid 427.125892 -243.234972)
					(end 427.786292 -243.234972)
				)
			)
		)
	)
	(zone
		(layers "In1.Cu" "In2.Cu")
		(hatch none 0.5)
		(connect_pads
			(clearance 0)
		)
		(min_thickness 0.25)
		(keepout
			(tracks not_allowed)
			(vias allowed)
			(pads allowed)
			(copperpour not_allowed)
			(footprints allowed)
		)
		(placement
			(enabled no)
			(sheetname "")
		)
		(fill yes
			(thermal_gap 0.5)
			(thermal_bridge_width 0.5)
			(island_removal_mode 0)
		)
		(polygon
			(pts
				(arc
					(start 199.0344 -250.885198)
					(mid 198.374 -250.885198)
					(end 199.0344 -250.885198)
				)
			)
		)
	)
	(zone
		(layers "In1.Cu" "In2.Cu")
		(hatch none 0.5)
		(connect_pads
			(clearance 0)
		)
		(min_thickness 0.25)
		(keepout
			(tracks not_allowed)
			(vias allowed)
			(pads allowed)
			(copperpour not_allowed)
			(footprints allowed)
		)
		(placement
			(enabled no)
			(sheetname "")
		)
		(fill yes
			(thermal_gap 0.5)
			(thermal_bridge_width 0.5)
			(island_removal_mode 0)
		)
		(polygon
			(pts
				(arc
					(start 424.342306 -289.135058)
					(mid 423.681906 -289.135058)
					(end 424.342306 -289.135058)
				)
			)
		)
	)
	(zone
		(layers "In1.Cu" "In2.Cu")
		(hatch none 0.5)
		(connect_pads
			(clearance 0)
		)
		(min_thickness 0.25)
		(keepout
			(tracks not_allowed)
			(vias allowed)
			(pads allowed)
			(copperpour not_allowed)
			(footprints allowed)
		)
		(placement
			(enabled no)
			(sheetname "")
		)
		(fill yes
			(thermal_gap 0.5)
			(thermal_bridge_width 0.5)
			(island_removal_mode 0)
		)
		(polygon
			(pts
				(arc
					(start 420.242238 -211.784946)
					(mid 419.581838 -211.784946)
					(end 420.242238 -211.784946)
				)
			)
		)
	)
	(zone
		(layers "In1.Cu" "In2.Cu")
		(hatch none 0.5)
		(connect_pads
			(clearance 0)
		)
		(min_thickness 0.25)
		(keepout
			(tracks not_allowed)
			(vias allowed)
			(pads allowed)
			(copperpour not_allowed)
			(footprints allowed)
		)
		(placement
			(enabled no)
			(sheetname "")
		)
		(fill yes
			(thermal_gap 0.5)
			(thermal_bridge_width 0.5)
			(island_removal_mode 0)
		)
		(polygon
			(pts
				(arc
					(start 450.4182 -278.93518)
					(mid 449.7578 -278.93518)
					(end 450.4182 -278.93518)
				)
			)
		)
	)
	(zone
		(layers "In1.Cu" "In2.Cu")
		(hatch none 0.5)
		(connect_pads
			(clearance 0)
		)
		(min_thickness 0.25)
		(keepout
			(tracks not_allowed)
			(vias allowed)
			(pads allowed)
			(copperpour not_allowed)
			(footprints allowed)
		)
		(placement
			(enabled no)
			(sheetname "")
		)
		(fill yes
			(thermal_gap 0.5)
			(thermal_bridge_width 0.5)
			(island_removal_mode 0)
		)
		(polygon
			(pts
				(arc
					(start 52.214272 -269.58544)
					(mid 51.553872 -269.58544)
					(end 52.214272 -269.58544)
				)
			)
		)
	)
	(zone
		(layers "In1.Cu" "In2.Cu")
		(hatch none 0.5)
		(connect_pads
			(clearance 0)
		)
		(min_thickness 0.25)
		(keepout
			(tracks not_allowed)
			(vias allowed)
			(pads allowed)
			(copperpour not_allowed)
			(footprints allowed)
		)
		(placement
			(enabled no)
			(sheetname "")
		)
		(fill yes
			(thermal_gap 0.5)
			(thermal_bridge_width 0.5)
			(island_removal_mode 0)
		)
		(polygon
			(pts
				(arc
					(start 300.15434 -304.435002)
					(mid 299.49394 -304.435002)
					(end 300.15434 -304.435002)
				)
			)
		)
	)
	(zone
		(layers "In1.Cu" "In2.Cu")
		(hatch none 0.5)
		(connect_pads
			(clearance 0)
		)
		(min_thickness 0.25)
		(keepout
			(tracks not_allowed)
			(vias allowed)
			(pads allowed)
			(copperpour not_allowed)
			(footprints allowed)
		)
		(placement
			(enabled no)
			(sheetname "")
		)
		(fill yes
			(thermal_gap 0.5)
			(thermal_bridge_width 0.5)
			(island_removal_mode 0)
		)
		(polygon
			(pts
				(arc
					(start 292.610286 -231.335072)
					(mid 291.949886 -231.335072)
					(end 292.610286 -231.335072)
				)
			)
		)
	)
	(zone
		(layers "In1.Cu" "In2.Cu")
		(hatch none 0.5)
		(connect_pads
			(clearance 0)
		)
		(min_thickness 0.25)
		(keepout
			(tracks not_allowed)
			(vias allowed)
			(pads allowed)
			(copperpour not_allowed)
			(footprints allowed)
		)
		(placement
			(enabled no)
			(sheetname "")
		)
		(fill yes
			(thermal_gap 0.5)
			(thermal_bridge_width 0.5)
			(island_removal_mode 0)
		)
		(polygon
			(pts
				(arc
					(start 300.15434 -317.18504)
					(mid 299.49394 -317.18504)
					(end 300.15434 -317.18504)
				)
			)
		)
	)
	(zone
		(layers "In1.Cu" "In2.Cu")
		(hatch none 0.5)
		(connect_pads
			(clearance 0)
		)
		(min_thickness 0.25)
		(keepout
			(tracks not_allowed)
			(vias allowed)
			(pads allowed)
			(copperpour not_allowed)
			(footprints allowed)
		)
		(placement
			(enabled no)
			(sheetname "")
		)
		(fill yes
			(thermal_gap 0.5)
			(thermal_bridge_width 0.5)
			(island_removal_mode 0)
		)
		(polygon
			(pts
				(arc
					(start 40.57015 -222.835216)
					(mid 39.90975 -222.835216)
					(end 40.57015 -222.835216)
				)
			)
		)
	)
	(zone
		(layers "In1.Cu" "In2.Cu")
		(hatch none 0.5)
		(connect_pads
			(clearance 0)
		)
		(min_thickness 0.25)
		(keepout
			(tracks not_allowed)
			(vias allowed)
			(pads allowed)
			(copperpour not_allowed)
			(footprints allowed)
		)
		(placement
			(enabled no)
			(sheetname "")
		)
		(fill yes
			(thermal_gap 0.5)
			(thermal_bridge_width 0.5)
			(island_removal_mode 0)
		)
		(polygon
			(pts
				(arc
					(start 183.946292 -242.385342)
					(mid 183.285892 -242.385342)
					(end 183.946292 -242.385342)
				)
			)
		)
	)
	(zone
		(layers "In1.Cu" "In2.Cu")
		(hatch none 0.5)
		(connect_pads
			(clearance 0)
		)
		(min_thickness 0.25)
		(keepout
			(tracks not_allowed)
			(vias allowed)
			(pads allowed)
			(copperpour not_allowed)
			(footprints allowed)
		)
		(placement
			(enabled no)
			(sheetname "")
		)
		(fill yes
			(thermal_gap 0.5)
			(thermal_bridge_width 0.5)
			(island_removal_mode 0)
		)
		(polygon
			(pts
				(arc
					(start 427.786292 -274.684998)
					(mid 427.125892 -274.684998)
					(end 427.786292 -274.684998)
				)
			)
		)
	)
	(zone
		(layers "In1.Cu" "In2.Cu")
		(hatch none 0.5)
		(connect_pads
			(clearance 0)
		)
		(min_thickness 0.25)
		(keepout
			(tracks not_allowed)
			(vias allowed)
			(pads allowed)
			(copperpour not_allowed)
			(footprints allowed)
		)
		(placement
			(enabled no)
			(sheetname "")
		)
		(fill yes
			(thermal_gap 0.5)
			(thermal_bridge_width 0.5)
			(island_removal_mode 0)
		)
		(polygon
			(pts
				(arc
					(start 288.510218 -295.935146)
					(mid 287.849818 -295.935146)
					(end 288.510218 -295.935146)
				)
			)
		)
	)
	(zone
		(layers "In1.Cu" "In2.Cu")
		(hatch none 0.5)
		(connect_pads
			(clearance 0)
		)
		(min_thickness 0.25)
		(keepout
			(tracks not_allowed)
			(vias allowed)
			(pads allowed)
			(copperpour not_allowed)
			(footprints allowed)
		)
		(placement
			(enabled no)
			(sheetname "")
		)
		(fill yes
			(thermal_gap 0.5)
			(thermal_bridge_width 0.5)
			(island_removal_mode 0)
		)
		(polygon
			(pts
				(arc
					(start 44.670218 -234.73537)
					(mid 44.009818 -234.73537)
					(end 44.670218 -234.73537)
				)
			)
		)
	)
	(zone
		(layers "In1.Cu" "In2.Cu")
		(hatch none 0.5)
		(connect_pads
			(clearance 0)
		)
		(min_thickness 0.25)
		(keepout
			(tracks not_allowed)
			(vias allowed)
			(pads allowed)
			(copperpour not_allowed)
			(footprints allowed)
		)
		(placement
			(enabled no)
			(sheetname "")
		)
		(fill yes
			(thermal_gap 0.5)
			(thermal_bridge_width 0.5)
			(island_removal_mode 0)
		)
		(polygon
			(pts
				(arc
					(start 17.938242 -202.435206)
					(mid 17.277842 -202.435206)
					(end 17.938242 -202.435206)
				)
			)
		)
	)
	(zone
		(layers "In1.Cu" "In2.Cu")
		(hatch none 0.5)
		(connect_pads
			(clearance 0)
		)
		(min_thickness 0.25)
		(keepout
			(tracks not_allowed)
			(vias allowed)
			(pads allowed)
			(copperpour not_allowed)
			(footprints allowed)
		)
		(placement
			(enabled no)
			(sheetname "")
		)
		(fill yes
			(thermal_gap 0.5)
			(thermal_bridge_width 0.5)
			(island_removal_mode 0)
		)
		(polygon
			(pts
				(arc
					(start 48.114204 -205.83525)
					(mid 47.453804 -205.83525)
					(end 48.114204 -205.83525)
				)
			)
		)
	)
	(zone
		(layers "In1.Cu" "In2.Cu")
		(hatch none 0.5)
		(connect_pads
			(clearance 0)
		)
		(min_thickness 0.25)
		(keepout
			(tracks not_allowed)
			(vias allowed)
			(pads allowed)
			(copperpour not_allowed)
			(footprints allowed)
		)
		(placement
			(enabled no)
			(sheetname "")
		)
		(fill yes
			(thermal_gap 0.5)
			(thermal_bridge_width 0.5)
			(island_removal_mode 0)
		)
		(polygon
			(pts
				(arc
					(start 401.11299 -379.360684)
					(mid 401.132914 -379.36992)
					(end 401.154646 -379.37313)
				)
				(arc
					(start 401.34921 -379.37313)
					(mid 401.403092 -379.350812)
					(end 401.42541 -379.29693)
				)
				(arc
					(start 401.42541 -378.61113)
					(mid 401.403092 -378.557248)
					(end 401.34921 -378.53493)
				)
				(arc
					(start 401.154646 -378.53493)
					(mid 401.132902 -378.538098)
					(end 401.11299 -378.547376)
				)
				(arc
					(start 400.816826 -378.740162)
					(mid 400.775142 -378.752384)
					(end 400.733514 -378.739908)
				)
				(arc
					(start 400.43989 -378.547376)
					(mid 400.419966 -378.53814)
					(end 400.398234 -378.53493)
				)
				(arc
					(start 400.20367 -378.53493)
					(mid 400.149788 -378.557248)
					(end 400.12747 -378.61113)
				)
				(arc
					(start 400.12747 -379.29693)
					(mid 400.149788 -379.350812)
					(end 400.20367 -379.37313)
				)
				(arc
					(start 400.399504 -379.37313)
					(mid 400.421248 -379.369962)
					(end 400.44116 -379.360684)
				)
				(arc
					(start 400.734784 -379.168152)
					(mid 400.77644 -379.15575)
					(end 400.818096 -379.168152)
				)
			)
		)
	)
	(zone
		(layers "In1.Cu" "In2.Cu")
		(hatch none 0.5)
		(connect_pads
			(clearance 0)
		)
		(min_thickness 0.25)
		(keepout
			(tracks not_allowed)
			(vias allowed)
			(pads allowed)
			(copperpour not_allowed)
			(footprints allowed)
		)
		(placement
			(enabled no)
			(sheetname "")
		)
		(fill yes
			(thermal_gap 0.5)
			(thermal_bridge_width 0.5)
			(island_removal_mode 0)
		)
		(polygon
			(pts
				(arc
					(start 429.27143 -16.443198)
					(mid 429.293748 -16.49708)
					(end 429.34763 -16.519398)
				)
				(arc
					(start 429.54321 -16.519398)
					(mid 429.565086 -16.516266)
					(end 429.58512 -16.506952)
				)
				(arc
					(start 429.878744 -16.31442)
					(mid 429.9204 -16.302018)
					(end 429.962056 -16.31442)
				)
				(arc
					(start 430.25695 -16.506952)
					(mid 430.276874 -16.516188)
					(end 430.298606 -16.519398)
				)
				(arc
					(start 430.49317 -16.519398)
					(mid 430.547052 -16.49708)
					(end 430.56937 -16.443198)
				)
				(arc
					(start 430.56937 -15.757398)
					(mid 430.547052 -15.703516)
					(end 430.49317 -15.681198)
				)
				(arc
					(start 430.298606 -15.681198)
					(mid 430.276862 -15.684366)
					(end 430.25695 -15.693644)
				)
				(arc
					(start 429.960786 -15.88643)
					(mid 429.919102 -15.898652)
					(end 429.877474 -15.886176)
				)
				(arc
					(start 429.58385 -15.693644)
					(mid 429.563926 -15.684408)
					(end 429.542194 -15.681198)
				)
				(arc
					(start 429.34763 -15.681198)
					(mid 429.293748 -15.703516)
					(end 429.27143 -15.757398)
				)
			)
		)
	)
	(zone
		(layers "In1.Cu" "In2.Cu")
		(hatch none 0.5)
		(connect_pads
			(clearance 0)
		)
		(min_thickness 0.25)
		(keepout
			(tracks not_allowed)
			(vias allowed)
			(pads allowed)
			(copperpour not_allowed)
			(footprints allowed)
		)
		(placement
			(enabled no)
			(sheetname "")
		)
		(fill yes
			(thermal_gap 0.5)
			(thermal_bridge_width 0.5)
			(island_removal_mode 0)
		)
		(polygon
			(pts
				(arc
					(start 176.402238 -245.785386)
					(mid 175.741838 -245.785386)
					(end 176.402238 -245.785386)
				)
			)
		)
	)
	(zone
		(layers "In1.Cu" "In2.Cu")
		(hatch none 0.5)
		(connect_pads
			(clearance 0)
		)
		(min_thickness 0.25)
		(keepout
			(tracks not_allowed)
			(vias allowed)
			(pads allowed)
			(copperpour not_allowed)
			(footprints allowed)
		)
		(placement
			(enabled no)
			(sheetname "")
		)
		(fill yes
			(thermal_gap 0.5)
			(thermal_bridge_width 0.5)
			(island_removal_mode 0)
		)
		(polygon
			(pts
				(arc
					(start 33.026096 -241.535204)
					(mid 32.365696 -241.535204)
					(end 33.026096 -241.535204)
				)
			)
		)
	)
	(zone
		(layers "In1.Cu" "In2.Cu")
		(hatch none 0.5)
		(connect_pads
			(clearance 0)
		)
		(min_thickness 0.25)
		(keepout
			(tracks not_allowed)
			(vias allowed)
			(pads allowed)
			(copperpour not_allowed)
			(footprints allowed)
		)
		(placement
			(enabled no)
			(sheetname "")
		)
		(fill yes
			(thermal_gap 0.5)
			(thermal_bridge_width 0.5)
			(island_removal_mode 0)
		)
		(polygon
			(pts
				(arc
					(start 296.054272 -272.984976)
					(mid 295.393872 -272.984976)
					(end 296.054272 -272.984976)
				)
			)
		)
	)
	(zone
		(layers "In1.Cu" "In2.Cu")
		(hatch none 0.5)
		(connect_pads
			(clearance 0)
		)
		(min_thickness 0.25)
		(keepout
			(tracks not_allowed)
			(vias allowed)
			(pads allowed)
			(copperpour not_allowed)
			(footprints allowed)
		)
		(placement
			(enabled no)
			(sheetname "")
		)
		(fill yes
			(thermal_gap 0.5)
			(thermal_bridge_width 0.5)
			(island_removal_mode 0)
		)
		(polygon
			(pts
				(arc
					(start 33.026096 -201.585322)
					(mid 32.365696 -201.585322)
					(end 33.026096 -201.585322)
				)
			)
		)
	)
	(zone
		(layers "In1.Cu" "In2.Cu")
		(hatch none 0.5)
		(connect_pads
			(clearance 0)
		)
		(min_thickness 0.25)
		(keepout
			(tracks not_allowed)
			(vias allowed)
			(pads allowed)
			(copperpour not_allowed)
			(footprints allowed)
		)
		(placement
			(enabled no)
			(sheetname "")
		)
		(fill yes
			(thermal_gap 0.5)
			(thermal_bridge_width 0.5)
			(island_removal_mode 0)
		)
		(polygon
			(pts
				(arc
					(start 454.518268 -203.28509)
					(mid 453.857868 -203.28509)
					(end 454.518268 -203.28509)
				)
			)
		)
	)
	(zone
		(layers "In1.Cu" "In2.Cu")
		(hatch none 0.5)
		(connect_pads
			(clearance 0)
		)
		(min_thickness 0.25)
		(keepout
			(tracks not_allowed)
			(vias allowed)
			(pads allowed)
			(copperpour not_allowed)
			(footprints allowed)
		)
		(placement
			(enabled no)
			(sheetname "")
		)
		(fill yes
			(thermal_gap 0.5)
			(thermal_bridge_width 0.5)
			(island_removal_mode 0)
		)
		(polygon
			(pts
				(arc
					(start 280.966164 -268.735048)
					(mid 280.305764 -268.735048)
					(end 280.966164 -268.735048)
				)
			)
		)
	)
	(zone
		(layers "In1.Cu" "In2.Cu")
		(hatch none 0.5)
		(connect_pads
			(clearance 0)
		)
		(min_thickness 0.25)
		(keepout
			(tracks not_allowed)
			(vias allowed)
			(pads allowed)
			(copperpour not_allowed)
			(footprints allowed)
		)
		(placement
			(enabled no)
			(sheetname "")
		)
		(fill yes
			(thermal_gap 0.5)
			(thermal_bridge_width 0.5)
			(island_removal_mode 0)
		)
		(polygon
			(pts
				(arc
					(start 25.482296 -211.7852)
					(mid 24.821896 -211.7852)
					(end 25.482296 -211.7852)
				)
			)
		)
	)
	(zone
		(layers "In1.Cu" "In2.Cu")
		(hatch none 0.5)
		(connect_pads
			(clearance 0)
		)
		(min_thickness 0.25)
		(keepout
			(tracks not_allowed)
			(vias allowed)
			(pads allowed)
			(copperpour not_allowed)
			(footprints allowed)
		)
		(placement
			(enabled no)
			(sheetname "")
		)
		(fill yes
			(thermal_gap 0.5)
			(thermal_bridge_width 0.5)
			(island_removal_mode 0)
		)
		(polygon
			(pts
				(arc
					(start 17.938242 -237.285276)
					(mid 17.277842 -237.285276)
					(end 17.938242 -237.285276)
				)
			)
		)
	)
	(zone
		(layers "In1.Cu" "In2.Cu")
		(hatch none 0.5)
		(connect_pads
			(clearance 0)
		)
		(min_thickness 0.25)
		(keepout
			(tracks not_allowed)
			(vias allowed)
			(pads allowed)
			(copperpour not_allowed)
			(footprints allowed)
		)
		(placement
			(enabled no)
			(sheetname "")
		)
		(fill yes
			(thermal_gap 0.5)
			(thermal_bridge_width 0.5)
			(island_removal_mode 0)
		)
		(polygon
			(pts
				(arc
					(start 172.30217 -246.63527)
					(mid 171.64177 -246.63527)
					(end 172.30217 -246.63527)
				)
			)
		)
	)
	(zone
		(layers "In1.Cu" "In2.Cu")
		(hatch none 0.5)
		(connect_pads
			(clearance 0)
		)
		(min_thickness 0.25)
		(keepout
			(tracks not_allowed)
			(vias allowed)
			(pads allowed)
			(copperpour not_allowed)
			(footprints allowed)
		)
		(placement
			(enabled no)
			(sheetname "")
		)
		(fill yes
			(thermal_gap 0.5)
			(thermal_bridge_width 0.5)
			(island_removal_mode 0)
		)
		(polygon
			(pts
				(arc
					(start 380.497842 -381.824484)
					(mid 380.517766 -381.83372)
					(end 380.539498 -381.83693)
				)
				(arc
					(start 380.734062 -381.83693)
					(mid 380.787944 -381.814612)
					(end 380.810262 -381.76073)
				)
				(arc
					(start 380.810262 -381.07493)
					(mid 380.787944 -381.021048)
					(end 380.734062 -380.99873)
				)
				(arc
					(start 380.539498 -380.99873)
					(mid 380.517754 -381.001898)
					(end 380.497842 -381.011176)
				)
				(arc
					(start 380.201678 -381.203962)
					(mid 380.159994 -381.216184)
					(end 380.118366 -381.203708)
				)
				(arc
					(start 379.824742 -381.011176)
					(mid 379.804818 -381.00194)
					(end 379.783086 -380.99873)
				)
				(arc
					(start 379.588522 -380.99873)
					(mid 379.53464 -381.021048)
					(end 379.512322 -381.07493)
				)
				(arc
					(start 379.512322 -381.76073)
					(mid 379.53464 -381.814612)
					(end 379.588522 -381.83693)
				)
				(arc
					(start 379.784356 -381.83693)
					(mid 379.8061 -381.833762)
					(end 379.826012 -381.824484)
				)
				(arc
					(start 380.119636 -381.631952)
					(mid 380.161292 -381.61955)
					(end 380.202948 -381.631952)
				)
			)
		)
	)
	(zone
		(layers "In1.Cu" "In2.Cu")
		(hatch none 0.5)
		(connect_pads
			(clearance 0)
		)
		(min_thickness 0.25)
		(keepout
			(tracks not_allowed)
			(vias allowed)
			(pads allowed)
			(copperpour not_allowed)
			(footprints allowed)
		)
		(placement
			(enabled no)
			(sheetname "")
		)
		(fill yes
			(thermal_gap 0.5)
			(thermal_bridge_width 0.5)
			(island_removal_mode 0)
		)
		(polygon
			(pts
				(arc
					(start 176.402238 -269.58544)
					(mid 175.741838 -269.58544)
					(end 176.402238 -269.58544)
				)
			)
		)
	)
	(zone
		(layers "In1.Cu" "In2.Cu")
		(hatch none 0.5)
		(connect_pads
			(clearance 0)
		)
		(min_thickness 0.25)
		(keepout
			(tracks not_allowed)
			(vias allowed)
			(pads allowed)
			(copperpour not_allowed)
			(footprints allowed)
		)
		(placement
			(enabled no)
			(sheetname "")
		)
		(fill yes
			(thermal_gap 0.5)
			(thermal_bridge_width 0.5)
			(island_removal_mode 0)
		)
		(polygon
			(pts
				(arc
					(start 439.430414 -204.985112)
					(mid 438.770014 -204.985112)
					(end 439.430414 -204.985112)
				)
			)
		)
	)
	(zone
		(layers "In1.Cu" "In2.Cu")
		(hatch none 0.5)
		(connect_pads
			(clearance 0)
		)
		(min_thickness 0.25)
		(keepout
			(tracks not_allowed)
			(vias allowed)
			(pads allowed)
			(copperpour not_allowed)
			(footprints allowed)
		)
		(placement
			(enabled no)
			(sheetname "")
		)
		(fill yes
			(thermal_gap 0.5)
			(thermal_bridge_width 0.5)
			(island_removal_mode 0)
		)
		(polygon
			(pts
				(arc
					(start 158.727394 -370.978684)
					(mid 158.747318 -370.98792)
					(end 158.76905 -370.99113)
				)
				(arc
					(start 158.963614 -370.99113)
					(mid 159.017496 -370.968812)
					(end 159.039814 -370.91493)
				)
				(arc
					(start 159.039814 -370.22913)
					(mid 159.017496 -370.175248)
					(end 158.963614 -370.15293)
				)
				(arc
					(start 158.76905 -370.15293)
					(mid 158.747306 -370.156098)
					(end 158.727394 -370.165376)
				)
				(arc
					(start 158.43123 -370.358162)
					(mid 158.389546 -370.370384)
					(end 158.347918 -370.357908)
				)
				(arc
					(start 158.054294 -370.165376)
					(mid 158.03437 -370.15614)
					(end 158.012638 -370.15293)
				)
				(arc
					(start 157.818074 -370.15293)
					(mid 157.764192 -370.175248)
					(end 157.741874 -370.22913)
				)
				(arc
					(start 157.741874 -370.91493)
					(mid 157.764192 -370.968812)
					(end 157.818074 -370.99113)
				)
				(arc
					(start 158.013908 -370.99113)
					(mid 158.035652 -370.987962)
					(end 158.055564 -370.978684)
				)
				(arc
					(start 158.349188 -370.786152)
					(mid 158.390844 -370.77375)
					(end 158.4325 -370.786152)
				)
			)
		)
	)
	(zone
		(layers "In1.Cu" "In2.Cu")
		(hatch none 0.5)
		(connect_pads
			(clearance 0)
		)
		(min_thickness 0.25)
		(keepout
			(tracks not_allowed)
			(vias allowed)
			(pads allowed)
			(copperpour not_allowed)
			(footprints allowed)
		)
		(placement
			(enabled no)
			(sheetname "")
		)
		(fill yes
			(thermal_gap 0.5)
			(thermal_bridge_width 0.5)
			(island_removal_mode 0)
		)
		(polygon
			(pts
				(arc
					(start 202.478132 -304.435256)
					(mid 201.817732 -304.435256)
					(end 202.478132 -304.435256)
				)
			)
		)
	)
	(zone
		(layers "In1.Cu" "In2.Cu")
		(hatch none 0.5)
		(connect_pads
			(clearance 0)
		)
		(min_thickness 0.25)
		(keepout
			(tracks not_allowed)
			(vias allowed)
			(pads allowed)
			(copperpour not_allowed)
			(footprints allowed)
		)
		(placement
			(enabled no)
			(sheetname "")
		)
		(fill yes
			(thermal_gap 0.5)
			(thermal_bridge_width 0.5)
			(island_removal_mode 0)
		)
		(polygon
			(pts
				(arc
					(start 17.938242 -207.535272)
					(mid 17.277842 -207.535272)
					(end 17.938242 -207.535272)
				)
			)
		)
	)
	(zone
		(layers "In1.Cu" "In2.Cu")
		(hatch none 0.5)
		(connect_pads
			(clearance 0)
		)
		(min_thickness 0.25)
		(keepout
			(tracks not_allowed)
			(vias allowed)
			(pads allowed)
			(copperpour not_allowed)
			(footprints allowed)
		)
		(placement
			(enabled no)
			(sheetname "")
		)
		(fill yes
			(thermal_gap 0.5)
			(thermal_bridge_width 0.5)
			(island_removal_mode 0)
		)
		(polygon
			(pts
				(arc
					(start 202.478132 -227.935282)
					(mid 201.817732 -227.935282)
					(end 202.478132 -227.935282)
				)
			)
		)
	)
	(zone
		(layers "In1.Cu" "In2.Cu")
		(hatch none 0.5)
		(connect_pads
			(clearance 0)
		)
		(min_thickness 0.25)
		(keepout
			(tracks not_allowed)
			(vias allowed)
			(pads allowed)
			(copperpour not_allowed)
			(footprints allowed)
		)
		(placement
			(enabled no)
			(sheetname "")
		)
		(fill yes
			(thermal_gap 0.5)
			(thermal_bridge_width 0.5)
			(island_removal_mode 0)
		)
		(polygon
			(pts
				(arc
					(start 277.522432 -233.035094)
					(mid 276.862032 -233.035094)
					(end 277.522432 -233.035094)
				)
			)
		)
	)
	(zone
		(layers "In1.Cu" "In2.Cu")
		(hatch none 0.5)
		(connect_pads
			(clearance 0)
		)
		(min_thickness 0.25)
		(keepout
			(tracks not_allowed)
			(vias allowed)
			(pads allowed)
			(copperpour not_allowed)
			(footprints allowed)
		)
		(placement
			(enabled no)
			(sheetname "")
		)
		(fill yes
			(thermal_gap 0.5)
			(thermal_bridge_width 0.5)
			(island_removal_mode 0)
		)
		(polygon
			(pts
				(arc
					(start 424.962066 -388.647178)
					(mid 424.95283 -388.667102)
					(end 424.94962 -388.688834)
				)
				(arc
					(start 424.94962 -388.883398)
					(mid 424.971938 -388.93728)
					(end 425.02582 -388.959598)
				)
				(arc
					(start 425.71162 -388.959598)
					(mid 425.765502 -388.93728)
					(end 425.78782 -388.883398)
				)
				(arc
					(start 425.78782 -388.688834)
					(mid 425.784652 -388.66709)
					(end 425.775374 -388.647178)
				)
				(arc
					(start 425.582588 -388.351014)
					(mid 425.570366 -388.30933)
					(end 425.582842 -388.267702)
				)
				(arc
					(start 425.775374 -387.974078)
					(mid 425.78461 -387.954154)
					(end 425.78782 -387.932422)
				)
				(arc
					(start 425.78782 -387.737858)
					(mid 425.765502 -387.683976)
					(end 425.71162 -387.661658)
				)
				(arc
					(start 425.02582 -387.661658)
					(mid 424.971938 -387.683976)
					(end 424.94962 -387.737858)
				)
				(arc
					(start 424.94962 -387.933692)
					(mid 424.952788 -387.955436)
					(end 424.962066 -387.975348)
				)
				(arc
					(start 425.154598 -388.268972)
					(mid 425.167 -388.310628)
					(end 425.154598 -388.352284)
				)
			)
		)
	)
	(zone
		(layers "In1.Cu" "In2.Cu")
		(hatch none 0.5)
		(connect_pads
			(clearance 0)
		)
		(min_thickness 0.25)
		(keepout
			(tracks not_allowed)
			(vias allowed)
			(pads allowed)
			(copperpour not_allowed)
			(footprints allowed)
		)
		(placement
			(enabled no)
			(sheetname "")
		)
		(fill yes
			(thermal_gap 0.5)
			(thermal_bridge_width 0.5)
			(island_removal_mode 0)
		)
		(polygon
			(pts
				(arc
					(start 17.166844 -7.67461)
					(mid 17.189162 -7.620728)
					(end 17.243044 -7.59841)
				)
				(arc
					(start 18.058384 -7.59841)
					(mid 18.112266 -7.620728)
					(end 18.134584 -7.67461)
				)
				(arc
					(start 18.134584 -8.98017)
					(mid 18.112266 -9.034052)
					(end 18.058384 -9.05637)
				)
				(arc
					(start 17.243044 -9.05637)
					(mid 17.189162 -9.034052)
					(end 17.166844 -8.98017)
				)
			)
		)
	)
	(zone
		(layers "In1.Cu" "In2.Cu")
		(hatch none 0.5)
		(connect_pads
			(clearance 0)
		)
		(min_thickness 0.25)
		(keepout
			(tracks not_allowed)
			(vias allowed)
			(pads allowed)
			(copperpour not_allowed)
			(footprints allowed)
		)
		(placement
			(enabled no)
			(sheetname "")
		)
		(fill yes
			(thermal_gap 0.5)
			(thermal_bridge_width 0.5)
			(island_removal_mode 0)
		)
		(polygon
			(pts
				(arc
					(start 269.978378 -278.085042)
					(mid 269.317978 -278.085042)
					(end 269.978378 -278.085042)
				)
			)
		)
	)
	(zone
		(layers "In1.Cu" "In2.Cu")
		(hatch none 0.5)
		(connect_pads
			(clearance 0)
		)
		(min_thickness 0.25)
		(keepout
			(tracks not_allowed)
			(vias allowed)
			(pads allowed)
			(copperpour not_allowed)
			(footprints allowed)
		)
		(placement
			(enabled no)
			(sheetname "")
		)
		(fill yes
			(thermal_gap 0.5)
			(thermal_bridge_width 0.5)
			(island_removal_mode 0)
		)
		(polygon
			(pts
				(arc
					(start 280.966164 -297.635168)
					(mid 280.305764 -297.635168)
					(end 280.966164 -297.635168)
				)
			)
		)
	)
	(zone
		(layers "In1.Cu" "In2.Cu")
		(hatch none 0.5)
		(connect_pads
			(clearance 0)
		)
		(min_thickness 0.25)
		(keepout
			(tracks not_allowed)
			(vias allowed)
			(pads allowed)
			(copperpour not_allowed)
			(footprints allowed)
		)
		(placement
			(enabled no)
			(sheetname "")
		)
		(fill yes
			(thermal_gap 0.5)
			(thermal_bridge_width 0.5)
			(island_removal_mode 0)
		)
		(polygon
			(pts
				(arc
					(start 300.15434 -200.735184)
					(mid 299.49394 -200.735184)
					(end 300.15434 -200.735184)
				)
			)
		)
	)
	(zone
		(layers "In1.Cu" "In2.Cu")
		(hatch none 0.5)
		(connect_pads
			(clearance 0)
		)
		(min_thickness 0.25)
		(keepout
			(tracks not_allowed)
			(vias allowed)
			(pads allowed)
			(copperpour not_allowed)
			(footprints allowed)
		)
		(placement
			(enabled no)
			(sheetname "")
		)
		(fill yes
			(thermal_gap 0.5)
			(thermal_bridge_width 0.5)
			(island_removal_mode 0)
		)
		(polygon
			(pts
				(arc
					(start 52.214272 -264.485374)
					(mid 51.553872 -264.485374)
					(end 52.214272 -264.485374)
				)
			)
		)
	)
	(zone
		(layers "In1.Cu" "In2.Cu")
		(hatch none 0.5)
		(connect_pads
			(clearance 0)
		)
		(min_thickness 0.25)
		(keepout
			(tracks not_allowed)
			(vias allowed)
			(pads allowed)
			(copperpour not_allowed)
			(footprints allowed)
		)
		(placement
			(enabled no)
			(sheetname "")
		)
		(fill yes
			(thermal_gap 0.5)
			(thermal_bridge_width 0.5)
			(island_removal_mode 0)
		)
		(polygon
			(pts
				(arc
					(start 194.934332 -301.035212)
					(mid 194.273932 -301.035212)
					(end 194.934332 -301.035212)
				)
			)
		)
	)
	(zone
		(layers "In1.Cu" "In2.Cu")
		(hatch none 0.5)
		(connect_pads
			(clearance 0)
		)
		(min_thickness 0.25)
		(keepout
			(tracks not_allowed)
			(vias allowed)
			(pads allowed)
			(copperpour not_allowed)
			(footprints allowed)
		)
		(placement
			(enabled no)
			(sheetname "")
		)
		(fill yes
			(thermal_gap 0.5)
			(thermal_bridge_width 0.5)
			(island_removal_mode 0)
		)
		(polygon
			(pts
				(arc
					(start 450.4182 -291.684964)
					(mid 449.7578 -291.684964)
					(end 450.4182 -291.684964)
				)
			)
		)
	)
	(zone
		(layers "In1.Cu" "In2.Cu")
		(hatch none 0.5)
		(connect_pads
			(clearance 0)
		)
		(min_thickness 0.25)
		(keepout
			(tracks not_allowed)
			(vias allowed)
			(pads allowed)
			(copperpour not_allowed)
			(footprints allowed)
		)
		(placement
			(enabled no)
			(sheetname "")
		)
		(fill yes
			(thermal_gap 0.5)
			(thermal_bridge_width 0.5)
			(island_removal_mode 0)
		)
		(polygon
			(pts
				(arc
					(start 114.626898 -26.792936)
					(mid 114.662819 -26.807815)
					(end 114.677698 -26.843736)
				)
				(arc
					(start 114.677698 -27.351736)
					(mid 114.662819 -27.387657)
					(end 114.626898 -27.402536)
				)
				(arc
					(start 113.970562 -27.402536)
					(mid 113.934641 -27.387657)
					(end 113.919762 -27.351736)
				)
				(arc
					(start 113.919762 -26.843736)
					(mid 113.934641 -26.807815)
					(end 113.970562 -26.792936)
				)
			)
		)
	)
	(zone
		(layers "In1.Cu" "In2.Cu")
		(hatch none 0.5)
		(connect_pads
			(clearance 0)
		)
		(min_thickness 0.25)
		(keepout
			(tracks not_allowed)
			(vias allowed)
			(pads allowed)
			(copperpour not_allowed)
			(footprints allowed)
		)
		(placement
			(enabled no)
			(sheetname "")
		)
		(fill yes
			(thermal_gap 0.5)
			(thermal_bridge_width 0.5)
			(island_removal_mode 0)
		)
		(polygon
			(pts
				(arc
					(start 288.510218 -286.585152)
					(mid 287.849818 -286.585152)
					(end 288.510218 -286.585152)
				)
			)
		)
	)
	(zone
		(layers "In1.Cu" "In2.Cu")
		(hatch none 0.5)
		(connect_pads
			(clearance 0)
		)
		(min_thickness 0.25)
		(keepout
			(tracks not_allowed)
			(vias allowed)
			(pads allowed)
			(copperpour not_allowed)
			(footprints allowed)
		)
		(placement
			(enabled no)
			(sheetname "")
		)
		(fill yes
			(thermal_gap 0.5)
			(thermal_bridge_width 0.5)
			(island_removal_mode 0)
		)
		(polygon
			(pts
				(arc
					(start 33.026096 -268.735302)
					(mid 32.365696 -268.735302)
					(end 33.026096 -268.735302)
				)
			)
		)
	)
	(zone
		(layers "In1.Cu" "In2.Cu")
		(hatch none 0.5)
		(connect_pads
			(clearance 0)
		)
		(min_thickness 0.25)
		(keepout
			(tracks not_allowed)
			(vias allowed)
			(pads allowed)
			(copperpour not_allowed)
			(footprints allowed)
		)
		(placement
			(enabled no)
			(sheetname "")
		)
		(fill yes
			(thermal_gap 0.5)
			(thermal_bridge_width 0.5)
			(island_removal_mode 0)
		)
		(polygon
			(pts
				(arc
					(start 172.30217 -221.135194)
					(mid 171.64177 -221.135194)
					(end 172.30217 -221.135194)
				)
			)
		)
	)
	(zone
		(layers "In1.Cu" "In2.Cu")
		(hatch none 0.5)
		(connect_pads
			(clearance 0)
		)
		(min_thickness 0.25)
		(keepout
			(tracks not_allowed)
			(vias allowed)
			(pads allowed)
			(copperpour not_allowed)
			(footprints allowed)
		)
		(placement
			(enabled no)
			(sheetname "")
		)
		(fill yes
			(thermal_gap 0.5)
			(thermal_bridge_width 0.5)
			(island_removal_mode 0)
		)
		(polygon
			(pts
				(arc
					(start 454.518268 -300.185074)
					(mid 453.857868 -300.185074)
					(end 454.518268 -300.185074)
				)
			)
		)
	)
	(zone
		(layers "In1.Cu" "In2.Cu")
		(hatch none 0.5)
		(connect_pads
			(clearance 0)
		)
		(min_thickness 0.25)
		(keepout
			(tracks not_allowed)
			(vias allowed)
			(pads allowed)
			(copperpour not_allowed)
			(footprints allowed)
		)
		(placement
			(enabled no)
			(sheetname "")
		)
		(fill yes
			(thermal_gap 0.5)
			(thermal_bridge_width 0.5)
			(island_removal_mode 0)
		)
		(polygon
			(pts
				(arc
					(start 288.510218 -243.234972)
					(mid 287.849818 -243.234972)
					(end 288.510218 -243.234972)
				)
			)
		)
	)
	(zone
		(layers "In1.Cu" "In2.Cu")
		(hatch none 0.5)
		(connect_pads
			(clearance 0)
		)
		(min_thickness 0.25)
		(keepout
			(tracks not_allowed)
			(vias allowed)
			(pads allowed)
			(copperpour not_allowed)
			(footprints allowed)
		)
		(placement
			(enabled no)
			(sheetname "")
		)
		(fill yes
			(thermal_gap 0.5)
			(thermal_bridge_width 0.5)
			(island_removal_mode 0)
		)
		(polygon
			(pts
				(arc
					(start 22.03831 -238.985298)
					(mid 21.37791 -238.985298)
					(end 22.03831 -238.985298)
				)
			)
		)
	)
	(zone
		(layers "In1.Cu" "In2.Cu")
		(hatch none 0.5)
		(connect_pads
			(clearance 0)
		)
		(min_thickness 0.25)
		(keepout
			(tracks not_allowed)
			(vias allowed)
			(pads allowed)
			(copperpour not_allowed)
			(footprints allowed)
		)
		(placement
			(enabled no)
			(sheetname "")
		)
		(fill yes
			(thermal_gap 0.5)
			(thermal_bridge_width 0.5)
			(island_removal_mode 0)
		)
		(polygon
			(pts
				(arc
					(start 48.114204 -305.285394)
					(mid 47.453804 -305.285394)
					(end 48.114204 -305.285394)
				)
			)
		)
	)
	(zone
		(layers "In1.Cu" "In2.Cu")
		(hatch none 0.5)
		(connect_pads
			(clearance 0)
		)
		(min_thickness 0.25)
		(keepout
			(tracks not_allowed)
			(vias allowed)
			(pads allowed)
			(copperpour not_allowed)
			(footprints allowed)
		)
		(placement
			(enabled no)
			(sheetname "")
		)
		(fill yes
			(thermal_gap 0.5)
			(thermal_bridge_width 0.5)
			(island_removal_mode 0)
		)
		(polygon
			(pts
				(arc
					(start 191.490346 -212.635338)
					(mid 190.829946 -212.635338)
					(end 191.490346 -212.635338)
				)
			)
		)
	)
	(zone
		(layers "In1.Cu" "In2.Cu")
		(hatch none 0.5)
		(connect_pads
			(clearance 0)
		)
		(min_thickness 0.25)
		(keepout
			(tracks not_allowed)
			(vias allowed)
			(pads allowed)
			(copperpour not_allowed)
			(footprints allowed)
		)
		(placement
			(enabled no)
			(sheetname "")
		)
		(fill yes
			(thermal_gap 0.5)
			(thermal_bridge_width 0.5)
			(island_removal_mode 0)
		)
		(polygon
			(pts
				(arc
					(start 427.786292 -299.33519)
					(mid 427.125892 -299.33519)
					(end 427.786292 -299.33519)
				)
			)
		)
	)
	(zone
		(layers "In1.Cu" "In2.Cu")
		(hatch none 0.5)
		(connect_pads
			(clearance 0)
		)
		(min_thickness 0.25)
		(keepout
			(tracks not_allowed)
			(vias allowed)
			(pads allowed)
			(copperpour not_allowed)
			(footprints allowed)
		)
		(placement
			(enabled no)
			(sheetname "")
		)
		(fill yes
			(thermal_gap 0.5)
			(thermal_bridge_width 0.5)
			(island_removal_mode 0)
		)
		(polygon
			(pts
				(arc
					(start 424.342306 -212.635084)
					(mid 423.681906 -212.635084)
					(end 424.342306 -212.635084)
				)
			)
		)
	)
	(zone
		(layers "In1.Cu" "In2.Cu")
		(hatch none 0.5)
		(connect_pads
			(clearance 0)
		)
		(min_thickness 0.25)
		(keepout
			(tracks not_allowed)
			(vias allowed)
			(pads allowed)
			(copperpour not_allowed)
			(footprints allowed)
		)
		(placement
			(enabled no)
			(sheetname "")
		)
		(fill yes
			(thermal_gap 0.5)
			(thermal_bridge_width 0.5)
			(island_removal_mode 0)
		)
		(polygon
			(pts
				(arc
					(start 29.582364 -272.135346)
					(mid 28.921964 -272.135346)
					(end 29.582364 -272.135346)
				)
			)
		)
	)
	(zone
		(layers "In1.Cu" "In2.Cu")
		(hatch none 0.5)
		(connect_pads
			(clearance 0)
		)
		(min_thickness 0.25)
		(keepout
			(tracks not_allowed)
			(vias allowed)
			(pads allowed)
			(copperpour not_allowed)
			(footprints allowed)
		)
		(placement
			(enabled no)
			(sheetname "")
		)
		(fill yes
			(thermal_gap 0.5)
			(thermal_bridge_width 0.5)
			(island_removal_mode 0)
		)
		(polygon
			(pts
				(arc
					(start 40.57015 -253.435358)
					(mid 39.90975 -253.435358)
					(end 40.57015 -253.435358)
				)
			)
		)
	)
	(zone
		(layers "In1.Cu" "In2.Cu")
		(hatch none 0.5)
		(connect_pads
			(clearance 0)
		)
		(min_thickness 0.25)
		(keepout
			(tracks not_allowed)
			(vias allowed)
			(pads allowed)
			(copperpour not_allowed)
			(footprints allowed)
		)
		(placement
			(enabled no)
			(sheetname "")
		)
		(fill yes
			(thermal_gap 0.5)
			(thermal_bridge_width 0.5)
			(island_removal_mode 0)
		)
		(polygon
			(pts
				(arc
					(start 269.978378 -264.48512)
					(mid 269.317978 -264.48512)
					(end 269.978378 -264.48512)
				)
			)
		)
	)
	(zone
		(layers "In1.Cu" "In2.Cu")
		(hatch none 0.5)
		(connect_pads
			(clearance 0)
		)
		(min_thickness 0.25)
		(keepout
			(tracks not_allowed)
			(vias allowed)
			(pads allowed)
			(copperpour not_allowed)
			(footprints allowed)
		)
		(placement
			(enabled no)
			(sheetname "")
		)
		(fill yes
			(thermal_gap 0.5)
			(thermal_bridge_width 0.5)
			(island_removal_mode 0)
		)
		(polygon
			(pts
				(arc
					(start 442.8744 -235.585)
					(mid 442.214 -235.585)
					(end 442.8744 -235.585)
				)
			)
		)
	)
	(zone
		(layers "In1.Cu" "In2.Cu")
		(hatch none 0.5)
		(connect_pads
			(clearance 0)
		)
		(min_thickness 0.25)
		(keepout
			(tracks not_allowed)
			(vias allowed)
			(pads allowed)
			(copperpour not_allowed)
			(footprints allowed)
		)
		(placement
			(enabled no)
			(sheetname "")
		)
		(fill yes
			(thermal_gap 0.5)
			(thermal_bridge_width 0.5)
			(island_removal_mode 0)
		)
		(polygon
			(pts
				(arc
					(start 273.422364 -313.784996)
					(mid 272.761964 -313.784996)
					(end 273.422364 -313.784996)
				)
			)
		)
	)
	(zone
		(layers "In1.Cu" "In2.Cu")
		(hatch none 0.5)
		(connect_pads
			(clearance 0)
		)
		(min_thickness 0.25)
		(keepout
			(tracks not_allowed)
			(vias allowed)
			(pads allowed)
			(copperpour not_allowed)
			(footprints allowed)
		)
		(placement
			(enabled no)
			(sheetname "")
		)
		(fill yes
			(thermal_gap 0.5)
			(thermal_bridge_width 0.5)
			(island_removal_mode 0)
		)
		(polygon
			(pts
				(arc
					(start 29.582364 -290.835334)
					(mid 28.921964 -290.835334)
					(end 29.582364 -290.835334)
				)
			)
		)
	)
	(zone
		(layers "In1.Cu" "In2.Cu")
		(hatch none 0.5)
		(connect_pads
			(clearance 0)
		)
		(min_thickness 0.25)
		(keepout
			(tracks not_allowed)
			(vias allowed)
			(pads allowed)
			(copperpour not_allowed)
			(footprints allowed)
		)
		(placement
			(enabled no)
			(sheetname "")
		)
		(fill yes
			(thermal_gap 0.5)
			(thermal_bridge_width 0.5)
			(island_removal_mode 0)
		)
		(polygon
			(pts
				(arc
					(start 296.054272 -284.034992)
					(mid 295.393872 -284.034992)
					(end 296.054272 -284.034992)
				)
			)
		)
	)
	(zone
		(layers "In1.Cu" "In2.Cu")
		(hatch none 0.5)
		(connect_pads
			(clearance 0)
		)
		(min_thickness 0.25)
		(keepout
			(tracks not_allowed)
			(vias allowed)
			(pads allowed)
			(copperpour not_allowed)
			(footprints allowed)
		)
		(placement
			(enabled no)
			(sheetname "")
		)
		(fill yes
			(thermal_gap 0.5)
			(thermal_bridge_width 0.5)
			(island_removal_mode 0)
		)
		(polygon
			(pts
				(arc
					(start 52.214272 -206.685388)
					(mid 51.553872 -206.685388)
					(end 52.214272 -206.685388)
				)
			)
		)
	)
	(zone
		(layers "In1.Cu" "In2.Cu")
		(hatch none 0.5)
		(connect_pads
			(clearance 0)
		)
		(min_thickness 0.25)
		(keepout
			(tracks not_allowed)
			(vias allowed)
			(pads allowed)
			(copperpour not_allowed)
			(footprints allowed)
		)
		(placement
			(enabled no)
			(sheetname "")
		)
		(fill yes
			(thermal_gap 0.5)
			(thermal_bridge_width 0.5)
			(island_removal_mode 0)
		)
		(polygon
			(pts
				(arc
					(start 38.762432 -7.672324)
					(mid 38.78475 -7.618442)
					(end 38.838632 -7.596124)
				)
				(arc
					(start 39.875206 -7.596124)
					(mid 39.929088 -7.618442)
					(end 39.951406 -7.672324)
				)
				(arc
					(start 39.951406 -9.071864)
					(mid 39.929088 -9.125746)
					(end 39.875206 -9.148064)
				)
				(arc
					(start 38.838632 -9.148064)
					(mid 38.78475 -9.125746)
					(end 38.762432 -9.071864)
				)
			)
		)
	)
	(zone
		(layers "In1.Cu" "In2.Cu")
		(hatch none 0.5)
		(connect_pads
			(clearance 0)
		)
		(min_thickness 0.25)
		(keepout
			(tracks not_allowed)
			(vias allowed)
			(pads allowed)
			(copperpour not_allowed)
			(footprints allowed)
		)
		(placement
			(enabled no)
			(sheetname "")
		)
		(fill yes
			(thermal_gap 0.5)
			(thermal_bridge_width 0.5)
			(island_removal_mode 0)
		)
		(polygon
			(pts
				(arc
					(start 269.978378 -290.83508)
					(mid 269.317978 -290.83508)
					(end 269.978378 -290.83508)
				)
			)
		)
	)
	(zone
		(layers "In1.Cu" "In2.Cu")
		(hatch none 0.5)
		(connect_pads
			(clearance 0)
		)
		(min_thickness 0.25)
		(keepout
			(tracks not_allowed)
			(vias allowed)
			(pads allowed)
			(copperpour not_allowed)
			(footprints allowed)
		)
		(placement
			(enabled no)
			(sheetname "")
		)
		(fill yes
			(thermal_gap 0.5)
			(thermal_bridge_width 0.5)
			(island_removal_mode 0)
		)
		(polygon
			(pts
				(arc
					(start 420.242238 -202.434952)
					(mid 419.581838 -202.434952)
					(end 420.242238 -202.434952)
				)
			)
		)
	)
	(zone
		(layers "In1.Cu" "In2.Cu")
		(hatch none 0.5)
		(connect_pads
			(clearance 0)
		)
		(min_thickness 0.25)
		(keepout
			(tracks not_allowed)
			(vias allowed)
			(pads allowed)
			(copperpour not_allowed)
			(footprints allowed)
		)
		(placement
			(enabled no)
			(sheetname "")
		)
		(fill yes
			(thermal_gap 0.5)
			(thermal_bridge_width 0.5)
			(island_removal_mode 0)
		)
		(polygon
			(pts
				(arc
					(start 65.906904 -370.978684)
					(mid 65.926828 -370.98792)
					(end 65.94856 -370.99113)
				)
				(arc
					(start 66.143124 -370.99113)
					(mid 66.197006 -370.968812)
					(end 66.219324 -370.91493)
				)
				(arc
					(start 66.219324 -370.22913)
					(mid 66.197006 -370.175248)
					(end 66.143124 -370.15293)
				)
				(arc
					(start 65.94856 -370.15293)
					(mid 65.926816 -370.156098)
					(end 65.906904 -370.165376)
				)
				(arc
					(start 65.61074 -370.358162)
					(mid 65.569056 -370.370384)
					(end 65.527428 -370.357908)
				)
				(arc
					(start 65.233804 -370.165376)
					(mid 65.21388 -370.15614)
					(end 65.192148 -370.15293)
				)
				(arc
					(start 64.997584 -370.15293)
					(mid 64.943702 -370.175248)
					(end 64.921384 -370.22913)
				)
				(arc
					(start 64.921384 -370.91493)
					(mid 64.943702 -370.968812)
					(end 64.997584 -370.99113)
				)
				(arc
					(start 65.193418 -370.99113)
					(mid 65.215162 -370.987962)
					(end 65.235074 -370.978684)
				)
				(arc
					(start 65.528698 -370.786152)
					(mid 65.570354 -370.77375)
					(end 65.61201 -370.786152)
				)
			)
		)
	)
	(zone
		(layers "In1.Cu" "In2.Cu")
		(hatch none 0.5)
		(connect_pads
			(clearance 0)
		)
		(min_thickness 0.25)
		(keepout
			(tracks not_allowed)
			(vias allowed)
			(pads allowed)
			(copperpour not_allowed)
			(footprints allowed)
		)
		(placement
			(enabled no)
			(sheetname "")
		)
		(fill yes
			(thermal_gap 0.5)
			(thermal_bridge_width 0.5)
			(island_removal_mode 0)
		)
		(polygon
			(pts
				(arc
					(start 191.490346 -203.285344)
					(mid 190.829946 -203.285344)
					(end 191.490346 -203.285344)
				)
			)
		)
	)
	(zone
		(layers "In1.Cu" "In2.Cu")
		(hatch none 0.5)
		(connect_pads
			(clearance 0)
		)
		(min_thickness 0.25)
		(keepout
			(tracks not_allowed)
			(vias allowed)
			(pads allowed)
			(copperpour not_allowed)
			(footprints allowed)
		)
		(placement
			(enabled no)
			(sheetname "")
		)
		(fill yes
			(thermal_gap 0.5)
			(thermal_bridge_width 0.5)
			(island_removal_mode 0)
		)
		(polygon
			(pts
				(arc
					(start 199.0344 -285.735268)
					(mid 198.374 -285.735268)
					(end 199.0344 -285.735268)
				)
			)
		)
	)
	(zone
		(layers "In1.Cu" "In2.Cu")
		(hatch none 0.5)
		(connect_pads
			(clearance 0)
		)
		(min_thickness 0.25)
		(keepout
			(tracks not_allowed)
			(vias allowed)
			(pads allowed)
			(copperpour not_allowed)
			(footprints allowed)
		)
		(placement
			(enabled no)
			(sheetname "")
		)
		(fill yes
			(thermal_gap 0.5)
			(thermal_bridge_width 0.5)
			(island_removal_mode 0)
		)
		(polygon
			(pts
				(arc
					(start 194.934332 -222.835216)
					(mid 194.273932 -222.835216)
					(end 194.934332 -222.835216)
				)
			)
		)
	)
	(zone
		(layers "In1.Cu" "In2.Cu")
		(hatch none 0.5)
		(connect_pads
			(clearance 0)
		)
		(min_thickness 0.25)
		(keepout
			(tracks not_allowed)
			(vias allowed)
			(pads allowed)
			(copperpour not_allowed)
			(footprints allowed)
		)
		(placement
			(enabled no)
			(sheetname "")
		)
		(fill yes
			(thermal_gap 0.5)
			(thermal_bridge_width 0.5)
			(island_removal_mode 0)
		)
		(polygon
			(pts
				(arc
					(start 442.8744 -297.635168)
					(mid 442.214 -297.635168)
					(end 442.8744 -297.635168)
				)
			)
		)
	)
	(zone
		(layers "In1.Cu" "In2.Cu")
		(hatch none 0.5)
		(connect_pads
			(clearance 0)
		)
		(min_thickness 0.25)
		(keepout
			(tracks not_allowed)
			(vias allowed)
			(pads allowed)
			(copperpour not_allowed)
			(footprints allowed)
		)
		(placement
			(enabled no)
			(sheetname "")
		)
		(fill yes
			(thermal_gap 0.5)
			(thermal_bridge_width 0.5)
			(island_removal_mode 0)
		)
		(polygon
			(pts
				(arc
					(start 44.670218 -247.485408)
					(mid 44.009818 -247.485408)
					(end 44.670218 -247.485408)
				)
			)
		)
	)
	(zone
		(layers "In1.Cu" "In2.Cu")
		(hatch none 0.5)
		(connect_pads
			(clearance 0)
		)
		(min_thickness 0.25)
		(keepout
			(tracks not_allowed)
			(vias allowed)
			(pads allowed)
			(copperpour not_allowed)
			(footprints allowed)
		)
		(placement
			(enabled no)
			(sheetname "")
		)
		(fill yes
			(thermal_gap 0.5)
			(thermal_bridge_width 0.5)
			(island_removal_mode 0)
		)
		(polygon
			(pts
				(arc
					(start 421.53459 -379.360684)
					(mid 421.554514 -379.36992)
					(end 421.576246 -379.37313)
				)
				(arc
					(start 421.77081 -379.37313)
					(mid 421.824692 -379.350812)
					(end 421.84701 -379.29693)
				)
				(arc
					(start 421.84701 -378.61113)
					(mid 421.824692 -378.557248)
					(end 421.77081 -378.53493)
				)
				(arc
					(start 421.576246 -378.53493)
					(mid 421.554502 -378.538098)
					(end 421.53459 -378.547376)
				)
				(arc
					(start 421.238426 -378.740162)
					(mid 421.196742 -378.752384)
					(end 421.155114 -378.739908)
				)
				(arc
					(start 420.86149 -378.547376)
					(mid 420.841566 -378.53814)
					(end 420.819834 -378.53493)
				)
				(arc
					(start 420.62527 -378.53493)
					(mid 420.571388 -378.557248)
					(end 420.54907 -378.61113)
				)
				(arc
					(start 420.54907 -379.29693)
					(mid 420.571388 -379.350812)
					(end 420.62527 -379.37313)
				)
				(arc
					(start 420.821104 -379.37313)
					(mid 420.842848 -379.369962)
					(end 420.86276 -379.360684)
				)
				(arc
					(start 421.156384 -379.168152)
					(mid 421.19804 -379.15575)
					(end 421.239696 -379.168152)
				)
			)
		)
	)
	(zone
		(layers "In1.Cu" "In2.Cu")
		(hatch none 0.5)
		(connect_pads
			(clearance 0)
		)
		(min_thickness 0.25)
		(keepout
			(tracks not_allowed)
			(vias allowed)
			(pads allowed)
			(copperpour not_allowed)
			(footprints allowed)
		)
		(placement
			(enabled no)
			(sheetname "")
		)
		(fill yes
			(thermal_gap 0.5)
			(thermal_bridge_width 0.5)
			(island_removal_mode 0)
		)
		(polygon
			(pts
				(arc
					(start 52.214272 -214.33536)
					(mid 51.553872 -214.33536)
					(end 52.214272 -214.33536)
				)
			)
		)
	)
	(zone
		(layers "In1.Cu" "In2.Cu")
		(hatch none 0.5)
		(connect_pads
			(clearance 0)
		)
		(min_thickness 0.25)
		(keepout
			(tracks not_allowed)
			(vias allowed)
			(pads allowed)
			(copperpour not_allowed)
			(footprints allowed)
		)
		(placement
			(enabled no)
			(sheetname "")
		)
		(fill yes
			(thermal_gap 0.5)
			(thermal_bridge_width 0.5)
			(island_removal_mode 0)
		)
		(polygon
			(pts
				(arc
					(start 199.0344 -300.185328)
					(mid 198.374 -300.185328)
					(end 199.0344 -300.185328)
				)
			)
		)
	)
	(zone
		(layers "In1.Cu" "In2.Cu")
		(hatch none 0.5)
		(connect_pads
			(clearance 0)
		)
		(min_thickness 0.25)
		(keepout
			(tracks not_allowed)
			(vias allowed)
			(pads allowed)
			(copperpour not_allowed)
			(footprints allowed)
		)
		(placement
			(enabled no)
			(sheetname "")
		)
		(fill yes
			(thermal_gap 0.5)
			(thermal_bridge_width 0.5)
			(island_removal_mode 0)
		)
		(polygon
			(pts
				(arc
					(start 439.430414 -199.035162)
					(mid 438.770014 -199.035162)
					(end 439.430414 -199.035162)
				)
			)
		)
	)
	(zone
		(layers "In1.Cu" "In2.Cu")
		(hatch none 0.5)
		(connect_pads
			(clearance 0)
		)
		(min_thickness 0.25)
		(keepout
			(tracks not_allowed)
			(vias allowed)
			(pads allowed)
			(copperpour not_allowed)
			(footprints allowed)
		)
		(placement
			(enabled no)
			(sheetname "")
		)
		(fill yes
			(thermal_gap 0.5)
			(thermal_bridge_width 0.5)
			(island_removal_mode 0)
		)
		(polygon
			(pts
				(arc
					(start 22.03831 -270.435324)
					(mid 21.37791 -270.435324)
					(end 22.03831 -270.435324)
				)
			)
		)
	)
	(zone
		(layers "In1.Cu" "In2.Cu")
		(hatch none 0.5)
		(connect_pads
			(clearance 0)
		)
		(min_thickness 0.25)
		(keepout
			(tracks not_allowed)
			(vias allowed)
			(pads allowed)
			(copperpour not_allowed)
			(footprints allowed)
		)
		(placement
			(enabled no)
			(sheetname "")
		)
		(fill yes
			(thermal_gap 0.5)
			(thermal_bridge_width 0.5)
			(island_removal_mode 0)
		)
		(polygon
			(pts
				(arc
					(start 273.422364 -299.33519)
					(mid 272.761964 -299.33519)
					(end 273.422364 -299.33519)
				)
			)
		)
	)
	(zone
		(layers "In1.Cu" "In2.Cu")
		(hatch none 0.5)
		(connect_pads
			(clearance 0)
		)
		(min_thickness 0.25)
		(keepout
			(tracks not_allowed)
			(vias allowed)
			(pads allowed)
			(copperpour not_allowed)
			(footprints allowed)
		)
		(placement
			(enabled no)
			(sheetname "")
		)
		(fill yes
			(thermal_gap 0.5)
			(thermal_bridge_width 0.5)
			(island_removal_mode 0)
		)
		(polygon
			(pts
				(arc
					(start 420.242238 -285.735014)
					(mid 419.581838 -285.735014)
					(end 420.242238 -285.735014)
				)
			)
		)
	)
	(zone
		(layers "In1.Cu" "In2.Cu")
		(hatch none 0.5)
		(connect_pads
			(clearance 0)
		)
		(min_thickness 0.25)
		(keepout
			(tracks not_allowed)
			(vias allowed)
			(pads allowed)
			(copperpour not_allowed)
			(footprints allowed)
		)
		(placement
			(enabled no)
			(sheetname "")
		)
		(fill yes
			(thermal_gap 0.5)
			(thermal_bridge_width 0.5)
			(island_removal_mode 0)
		)
		(polygon
			(pts
				(arc
					(start 454.518268 -285.735014)
					(mid 453.857868 -285.735014)
					(end 454.518268 -285.735014)
				)
			)
		)
	)
	(zone
		(layers "In1.Cu" "In2.Cu")
		(hatch none 0.5)
		(connect_pads
			(clearance 0)
		)
		(min_thickness 0.25)
		(keepout
			(tracks not_allowed)
			(vias allowed)
			(pads allowed)
			(copperpour not_allowed)
			(footprints allowed)
		)
		(placement
			(enabled no)
			(sheetname "")
		)
		(fill yes
			(thermal_gap 0.5)
			(thermal_bridge_width 0.5)
			(island_removal_mode 0)
		)
		(polygon
			(pts
				(arc
					(start 439.430414 -267.885164)
					(mid 438.770014 -267.885164)
					(end 439.430414 -267.885164)
				)
			)
		)
	)
	(zone
		(layers "In1.Cu" "In2.Cu")
		(hatch none 0.5)
		(connect_pads
			(clearance 0)
		)
		(min_thickness 0.25)
		(keepout
			(tracks not_allowed)
			(vias allowed)
			(pads allowed)
			(copperpour not_allowed)
			(footprints allowed)
		)
		(placement
			(enabled no)
			(sheetname "")
		)
		(fill yes
			(thermal_gap 0.5)
			(thermal_bridge_width 0.5)
			(island_removal_mode 0)
		)
		(polygon
			(pts
				(arc
					(start 37.126164 -300.185328)
					(mid 36.465764 -300.185328)
					(end 37.126164 -300.185328)
				)
			)
		)
	)
	(zone
		(layers "In1.Cu" "In2.Cu")
		(hatch none 0.5)
		(connect_pads
			(clearance 0)
		)
		(min_thickness 0.25)
		(keepout
			(tracks not_allowed)
			(vias allowed)
			(pads allowed)
			(copperpour not_allowed)
			(footprints allowed)
		)
		(placement
			(enabled no)
			(sheetname "")
		)
		(fill yes
			(thermal_gap 0.5)
			(thermal_bridge_width 0.5)
			(island_removal_mode 0)
		)
		(polygon
			(pts
				(arc
					(start 431.88636 -204.985112)
					(mid 431.22596 -204.985112)
					(end 431.88636 -204.985112)
				)
			)
		)
	)
	(zone
		(layers "In1.Cu" "In2.Cu")
		(hatch none 0.5)
		(connect_pads
			(clearance 0)
		)
		(min_thickness 0.25)
		(keepout
			(tracks not_allowed)
			(vias allowed)
			(pads allowed)
			(copperpour not_allowed)
			(footprints allowed)
		)
		(placement
			(enabled no)
			(sheetname "")
		)
		(fill yes
			(thermal_gap 0.5)
			(thermal_bridge_width 0.5)
			(island_removal_mode 0)
		)
		(polygon
			(pts
				(arc
					(start 450.4182 -222.834962)
					(mid 449.7578 -222.834962)
					(end 450.4182 -222.834962)
				)
			)
		)
	)
	(zone
		(layers "In1.Cu" "In2.Cu")
		(hatch none 0.5)
		(connect_pads
			(clearance 0)
		)
		(min_thickness 0.25)
		(keepout
			(tracks not_allowed)
			(vias allowed)
			(pads allowed)
			(copperpour not_allowed)
			(footprints allowed)
		)
		(placement
			(enabled no)
			(sheetname "")
		)
		(fill yes
			(thermal_gap 0.5)
			(thermal_bridge_width 0.5)
			(island_removal_mode 0)
		)
		(polygon
			(pts
				(arc
					(start 199.0344 -298.485306)
					(mid 198.374 -298.485306)
					(end 199.0344 -298.485306)
				)
			)
		)
	)
	(zone
		(layers "In1.Cu" "In2.Cu")
		(hatch none 0.5)
		(connect_pads
			(clearance 0)
		)
		(min_thickness 0.25)
		(keepout
			(tracks not_allowed)
			(vias allowed)
			(pads allowed)
			(copperpour not_allowed)
			(footprints allowed)
		)
		(placement
			(enabled no)
			(sheetname "")
		)
		(fill yes
			(thermal_gap 0.5)
			(thermal_bridge_width 0.5)
			(island_removal_mode 0)
		)
		(polygon
			(pts
				(arc
					(start 420.242238 -301.034958)
					(mid 419.581838 -301.034958)
					(end 420.242238 -301.034958)
				)
			)
		)
	)
	(zone
		(layers "In1.Cu" "In2.Cu")
		(hatch none 0.5)
		(connect_pads
			(clearance 0)
		)
		(min_thickness 0.25)
		(keepout
			(tracks not_allowed)
			(vias allowed)
			(pads allowed)
			(copperpour not_allowed)
			(footprints allowed)
		)
		(placement
			(enabled no)
			(sheetname "")
		)
		(fill yes
			(thermal_gap 0.5)
			(thermal_bridge_width 0.5)
			(island_removal_mode 0)
		)
		(polygon
			(pts
				(arc
					(start 398.197578 -17.967198)
					(mid 398.219896 -18.02108)
					(end 398.273778 -18.043398)
				)
				(arc
					(start 398.469358 -18.043398)
					(mid 398.491234 -18.040266)
					(end 398.511268 -18.030952)
				)
				(arc
					(start 398.804892 -17.83842)
					(mid 398.846548 -17.826018)
					(end 398.888204 -17.83842)
				)
				(arc
					(start 399.183098 -18.030952)
					(mid 399.203022 -18.040188)
					(end 399.224754 -18.043398)
				)
				(arc
					(start 399.419318 -18.043398)
					(mid 399.4732 -18.02108)
					(end 399.495518 -17.967198)
				)
				(arc
					(start 399.495518 -17.281398)
					(mid 399.4732 -17.227516)
					(end 399.419318 -17.205198)
				)
				(arc
					(start 399.224754 -17.205198)
					(mid 399.20301 -17.208366)
					(end 399.183098 -17.217644)
				)
				(arc
					(start 398.886934 -17.41043)
					(mid 398.84525 -17.422652)
					(end 398.803622 -17.410176)
				)
				(arc
					(start 398.509998 -17.217644)
					(mid 398.490074 -17.208408)
					(end 398.468342 -17.205198)
				)
				(arc
					(start 398.273778 -17.205198)
					(mid 398.219896 -17.227516)
					(end 398.197578 -17.281398)
				)
			)
		)
	)
	(zone
		(layers "In1.Cu" "In2.Cu")
		(hatch none 0.5)
		(connect_pads
			(clearance 0)
		)
		(min_thickness 0.25)
		(keepout
			(tracks not_allowed)
			(vias allowed)
			(pads allowed)
			(copperpour not_allowed)
			(footprints allowed)
		)
		(placement
			(enabled no)
			(sheetname "")
		)
		(fill yes
			(thermal_gap 0.5)
			(thermal_bridge_width 0.5)
			(island_removal_mode 0)
		)
		(polygon
			(pts
				(arc
					(start 446.974468 -264.48512)
					(mid 446.314068 -264.48512)
					(end 446.974468 -264.48512)
				)
			)
		)
	)
	(zone
		(layers "In1.Cu" "In2.Cu")
		(hatch none 0.5)
		(connect_pads
			(clearance 0)
		)
		(min_thickness 0.25)
		(keepout
			(tracks not_allowed)
			(vias allowed)
			(pads allowed)
			(copperpour not_allowed)
			(footprints allowed)
		)
		(placement
			(enabled no)
			(sheetname "")
		)
		(fill yes
			(thermal_gap 0.5)
			(thermal_bridge_width 0.5)
			(island_removal_mode 0)
		)
		(polygon
			(pts
				(arc
					(start 300.15434 -225.385122)
					(mid 299.49394 -225.385122)
					(end 300.15434 -225.385122)
				)
			)
		)
	)
	(zone
		(layers "In1.Cu" "In2.Cu")
		(hatch none 0.5)
		(connect_pads
			(clearance 0)
		)
		(min_thickness 0.25)
		(keepout
			(tracks not_allowed)
			(vias allowed)
			(pads allowed)
			(copperpour not_allowed)
			(footprints allowed)
		)
		(placement
			(enabled no)
			(sheetname "")
		)
		(fill yes
			(thermal_gap 0.5)
			(thermal_bridge_width 0.5)
			(island_removal_mode 0)
		)
		(polygon
			(pts
				(arc
					(start 439.430414 -238.985044)
					(mid 438.770014 -238.985044)
					(end 439.430414 -238.985044)
				)
			)
		)
	)
	(zone
		(layers "In1.Cu" "In2.Cu")
		(hatch none 0.5)
		(connect_pads
			(clearance 0)
		)
		(min_thickness 0.25)
		(keepout
			(tracks not_allowed)
			(vias allowed)
			(pads allowed)
			(copperpour not_allowed)
			(footprints allowed)
		)
		(placement
			(enabled no)
			(sheetname "")
		)
		(fill yes
			(thermal_gap 0.5)
			(thermal_bridge_width 0.5)
			(island_removal_mode 0)
		)
		(polygon
			(pts
				(arc
					(start 17.938242 -289.98545)
					(mid 17.277842 -289.98545)
					(end 17.938242 -289.98545)
				)
			)
		)
	)
	(zone
		(layers "In1.Cu" "In2.Cu")
		(hatch none 0.5)
		(connect_pads
			(clearance 0)
		)
		(min_thickness 0.25)
		(keepout
			(tracks not_allowed)
			(vias allowed)
			(pads allowed)
			(copperpour not_allowed)
			(footprints allowed)
		)
		(placement
			(enabled no)
			(sheetname "")
		)
		(fill yes
			(thermal_gap 0.5)
			(thermal_bridge_width 0.5)
			(island_removal_mode 0)
		)
		(polygon
			(pts
				(arc
					(start 25.482296 -232.18521)
					(mid 24.821896 -232.18521)
					(end 25.482296 -232.18521)
				)
			)
		)
	)
	(zone
		(layers "In1.Cu" "In2.Cu")
		(hatch none 0.5)
		(connect_pads
			(clearance 0)
		)
		(min_thickness 0.25)
		(keepout
			(tracks not_allowed)
			(vias allowed)
			(pads allowed)
			(copperpour not_allowed)
			(footprints allowed)
		)
		(placement
			(enabled no)
			(sheetname "")
		)
		(fill yes
			(thermal_gap 0.5)
			(thermal_bridge_width 0.5)
			(island_removal_mode 0)
		)
		(polygon
			(pts
				(arc
					(start 277.522432 -304.435002)
					(mid 276.862032 -304.435002)
					(end 277.522432 -304.435002)
				)
			)
		)
	)
	(zone
		(layers "In1.Cu" "In2.Cu")
		(hatch none 0.5)
		(connect_pads
			(clearance 0)
		)
		(min_thickness 0.25)
		(keepout
			(tracks not_allowed)
			(vias allowed)
			(pads allowed)
			(copperpour not_allowed)
			(footprints allowed)
		)
		(placement
			(enabled no)
			(sheetname "")
		)
		(fill yes
			(thermal_gap 0.5)
			(thermal_bridge_width 0.5)
			(island_removal_mode 0)
		)
		(polygon
			(pts
				(arc
					(start 72.082914 -408.860244)
					(mid 72.105232 -408.914126)
					(end 72.159114 -408.936444)
				)
				(arc
					(start 72.354694 -408.936444)
					(mid 72.37657 -408.933312)
					(end 72.396604 -408.923998)
				)
				(arc
					(start 72.690228 -408.731466)
					(mid 72.731884 -408.719064)
					(end 72.77354 -408.731466)
				)
				(arc
					(start 73.068434 -408.923998)
					(mid 73.088358 -408.933234)
					(end 73.11009 -408.936444)
				)
				(arc
					(start 73.304654 -408.936444)
					(mid 73.358536 -408.914126)
					(end 73.380854 -408.860244)
				)
				(arc
					(start 73.380854 -408.174444)
					(mid 73.358536 -408.120562)
					(end 73.304654 -408.098244)
				)
				(arc
					(start 73.11009 -408.098244)
					(mid 73.088346 -408.101412)
					(end 73.068434 -408.11069)
				)
				(arc
					(start 72.77227 -408.303476)
					(mid 72.730586 -408.315698)
					(end 72.688958 -408.303222)
				)
				(arc
					(start 72.395334 -408.11069)
					(mid 72.37541 -408.101454)
					(end 72.353678 -408.098244)
				)
				(arc
					(start 72.159114 -408.098244)
					(mid 72.105232 -408.120562)
					(end 72.082914 -408.174444)
				)
			)
		)
	)
	(zone
		(layers "In1.Cu" "In2.Cu")
		(hatch none 0.5)
		(connect_pads
			(clearance 0)
		)
		(min_thickness 0.25)
		(keepout
			(tracks not_allowed)
			(vias allowed)
			(pads allowed)
			(copperpour not_allowed)
			(footprints allowed)
		)
		(placement
			(enabled no)
			(sheetname "")
		)
		(fill yes
			(thermal_gap 0.5)
			(thermal_bridge_width 0.5)
			(island_removal_mode 0)
		)
		(polygon
			(pts
				(arc
					(start 52.214272 -306.135278)
					(mid 51.553872 -306.135278)
					(end 52.214272 -306.135278)
				)
			)
		)
	)
	(zone
		(layers "In1.Cu" "In2.Cu")
		(hatch none 0.5)
		(connect_pads
			(clearance 0)
		)
		(min_thickness 0.25)
		(keepout
			(tracks not_allowed)
			(vias allowed)
			(pads allowed)
			(copperpour not_allowed)
			(footprints allowed)
		)
		(placement
			(enabled no)
			(sheetname "")
		)
		(fill yes
			(thermal_gap 0.5)
			(thermal_bridge_width 0.5)
			(island_removal_mode 0)
		)
		(polygon
			(pts
				(arc
					(start 33.026096 -216.885266)
					(mid 32.365696 -216.885266)
					(end 33.026096 -216.885266)
				)
			)
		)
	)
	(zone
		(layers "In1.Cu" "In2.Cu")
		(hatch none 0.5)
		(connect_pads
			(clearance 0)
		)
		(min_thickness 0.25)
		(keepout
			(tracks not_allowed)
			(vias allowed)
			(pads allowed)
			(copperpour not_allowed)
			(footprints allowed)
		)
		(placement
			(enabled no)
			(sheetname "")
		)
		(fill yes
			(thermal_gap 0.5)
			(thermal_bridge_width 0.5)
			(island_removal_mode 0)
		)
		(polygon
			(pts
				(arc
					(start 176.402238 -201.585322)
					(mid 175.741838 -201.585322)
					(end 176.402238 -201.585322)
				)
			)
		)
	)
	(zone
		(layers "In1.Cu" "In2.Cu")
		(hatch none 0.5)
		(connect_pads
			(clearance 0)
		)
		(min_thickness 0.25)
		(keepout
			(tracks not_allowed)
			(vias allowed)
			(pads allowed)
			(copperpour not_allowed)
			(footprints allowed)
		)
		(placement
			(enabled no)
			(sheetname "")
		)
		(fill yes
			(thermal_gap 0.5)
			(thermal_bridge_width 0.5)
			(island_removal_mode 0)
		)
		(polygon
			(pts
				(arc
					(start 22.03831 -290.835334)
					(mid 21.37791 -290.835334)
					(end 22.03831 -290.835334)
				)
			)
		)
	)
	(zone
		(layers "In1.Cu" "In2.Cu")
		(hatch none 0.5)
		(connect_pads
			(clearance 0)
		)
		(min_thickness 0.25)
		(keepout
			(tracks not_allowed)
			(vias allowed)
			(pads allowed)
			(copperpour not_allowed)
			(footprints allowed)
		)
		(placement
			(enabled no)
			(sheetname "")
		)
		(fill yes
			(thermal_gap 0.5)
			(thermal_bridge_width 0.5)
			(island_removal_mode 0)
		)
		(polygon
			(pts
				(arc
					(start 172.30217 -201.585322)
					(mid 171.64177 -201.585322)
					(end 172.30217 -201.585322)
				)
			)
		)
	)
	(zone
		(layers "In1.Cu" "In2.Cu")
		(hatch none 0.5)
		(connect_pads
			(clearance 0)
		)
		(min_thickness 0.25)
		(keepout
			(tracks not_allowed)
			(vias allowed)
			(pads allowed)
			(copperpour not_allowed)
			(footprints allowed)
		)
		(placement
			(enabled no)
			(sheetname "")
		)
		(fill yes
			(thermal_gap 0.5)
			(thermal_bridge_width 0.5)
			(island_removal_mode 0)
		)
		(polygon
			(pts
				(arc
					(start 378.796042 -384.288284)
					(mid 378.815966 -384.29752)
					(end 378.837698 -384.30073)
				)
				(arc
					(start 379.032262 -384.30073)
					(mid 379.086144 -384.278412)
					(end 379.108462 -384.22453)
				)
				(arc
					(start 379.108462 -383.53873)
					(mid 379.086144 -383.484848)
					(end 379.032262 -383.46253)
				)
				(arc
					(start 378.837698 -383.46253)
					(mid 378.815954 -383.465698)
					(end 378.796042 -383.474976)
				)
				(arc
					(start 378.499878 -383.667762)
					(mid 378.458194 -383.679984)
					(end 378.416566 -383.667508)
				)
				(arc
					(start 378.122942 -383.474976)
					(mid 378.103018 -383.46574)
					(end 378.081286 -383.46253)
				)
				(arc
					(start 377.886722 -383.46253)
					(mid 377.83284 -383.484848)
					(end 377.810522 -383.53873)
				)
				(arc
					(start 377.810522 -384.22453)
					(mid 377.83284 -384.278412)
					(end 377.886722 -384.30073)
				)
				(arc
					(start 378.082556 -384.30073)
					(mid 378.1043 -384.297562)
					(end 378.124212 -384.288284)
				)
				(arc
					(start 378.417836 -384.095752)
					(mid 378.459492 -384.08335)
					(end 378.501148 -384.095752)
				)
			)
		)
	)
	(zone
		(layers "In1.Cu" "In2.Cu")
		(hatch none 0.5)
		(connect_pads
			(clearance 0)
		)
		(min_thickness 0.25)
		(keepout
			(tracks not_allowed)
			(vias allowed)
			(pads allowed)
			(copperpour not_allowed)
			(footprints allowed)
		)
		(placement
			(enabled no)
			(sheetname "")
		)
		(fill yes
			(thermal_gap 0.5)
			(thermal_bridge_width 0.5)
			(island_removal_mode 0)
		)
		(polygon
			(pts
				(arc
					(start 442.8744 -202.434952)
					(mid 442.214 -202.434952)
					(end 442.8744 -202.434952)
				)
			)
		)
	)
	(zone
		(layers "In1.Cu" "In2.Cu")
		(hatch none 0.5)
		(connect_pads
			(clearance 0)
		)
		(min_thickness 0.25)
		(keepout
			(tracks not_allowed)
			(vias allowed)
			(pads allowed)
			(copperpour not_allowed)
			(footprints allowed)
		)
		(placement
			(enabled no)
			(sheetname "")
		)
		(fill yes
			(thermal_gap 0.5)
			(thermal_bridge_width 0.5)
			(island_removal_mode 0)
		)
		(polygon
			(pts
				(arc
					(start 191.490346 -313.78525)
					(mid 190.829946 -313.78525)
					(end 191.490346 -313.78525)
				)
			)
		)
	)
	(zone
		(layers "In1.Cu" "In2.Cu")
		(hatch none 0.5)
		(connect_pads
			(clearance 0)
		)
		(min_thickness 0.25)
		(keepout
			(tracks not_allowed)
			(vias allowed)
			(pads allowed)
			(copperpour not_allowed)
			(footprints allowed)
		)
		(placement
			(enabled no)
			(sheetname "")
		)
		(fill yes
			(thermal_gap 0.5)
			(thermal_bridge_width 0.5)
			(island_removal_mode 0)
		)
		(polygon
			(pts
				(arc
					(start 442.8744 -280.634948)
					(mid 442.214 -280.634948)
					(end 442.8744 -280.634948)
				)
			)
		)
	)
	(zone
		(layers "In1.Cu" "In2.Cu")
		(hatch none 0.5)
		(connect_pads
			(clearance 0)
		)
		(min_thickness 0.25)
		(keepout
			(tracks not_allowed)
			(vias allowed)
			(pads allowed)
			(copperpour not_allowed)
			(footprints allowed)
		)
		(placement
			(enabled no)
			(sheetname "")
		)
		(fill yes
			(thermal_gap 0.5)
			(thermal_bridge_width 0.5)
			(island_removal_mode 0)
		)
		(polygon
			(pts
				(arc
					(start 454.518268 -247.485154)
					(mid 453.857868 -247.485154)
					(end 454.518268 -247.485154)
				)
			)
		)
	)
	(zone
		(layers "In1.Cu" "In2.Cu")
		(hatch none 0.5)
		(connect_pads
			(clearance 0)
		)
		(min_thickness 0.25)
		(keepout
			(tracks not_allowed)
			(vias allowed)
			(pads allowed)
			(copperpour not_allowed)
			(footprints allowed)
		)
		(placement
			(enabled no)
			(sheetname "")
		)
		(fill yes
			(thermal_gap 0.5)
			(thermal_bridge_width 0.5)
			(island_removal_mode 0)
		)
		(polygon
			(pts
				(arc
					(start 285.066232 -199.035162)
					(mid 284.405832 -199.035162)
					(end 285.066232 -199.035162)
				)
			)
		)
	)
	(zone
		(layers "In1.Cu" "In2.Cu")
		(hatch none 0.5)
		(connect_pads
			(clearance 0)
		)
		(min_thickness 0.25)
		(keepout
			(tracks not_allowed)
			(vias allowed)
			(pads allowed)
			(copperpour not_allowed)
			(footprints allowed)
		)
		(placement
			(enabled no)
			(sheetname "")
		)
		(fill yes
			(thermal_gap 0.5)
			(thermal_bridge_width 0.5)
			(island_removal_mode 0)
		)
		(polygon
			(pts
				(arc
					(start 194.934332 -272.98523)
					(mid 194.273932 -272.98523)
					(end 194.934332 -272.98523)
				)
			)
		)
	)
	(zone
		(layers "In1.Cu" "In2.Cu")
		(hatch none 0.5)
		(connect_pads
			(clearance 0)
		)
		(min_thickness 0.25)
		(keepout
			(tracks not_allowed)
			(vias allowed)
			(pads allowed)
			(copperpour not_allowed)
			(footprints allowed)
		)
		(placement
			(enabled no)
			(sheetname "")
		)
		(fill yes
			(thermal_gap 0.5)
			(thermal_bridge_width 0.5)
			(island_removal_mode 0)
		)
		(polygon
			(pts
				(arc
					(start 48.114204 -265.335258)
					(mid 47.453804 -265.335258)
					(end 48.114204 -265.335258)
				)
			)
		)
	)
	(zone
		(layers "In1.Cu" "In2.Cu")
		(hatch none 0.5)
		(connect_pads
			(clearance 0)
		)
		(min_thickness 0.25)
		(keepout
			(tracks not_allowed)
			(vias allowed)
			(pads allowed)
			(copperpour not_allowed)
			(footprints allowed)
		)
		(placement
			(enabled no)
			(sheetname "")
		)
		(fill yes
			(thermal_gap 0.5)
			(thermal_bridge_width 0.5)
			(island_removal_mode 0)
		)
		(polygon
			(pts
				(arc
					(start 25.482296 -213.485222)
					(mid 24.821896 -213.485222)
					(end 25.482296 -213.485222)
				)
			)
		)
	)
	(zone
		(layers "In1.Cu" "In2.Cu")
		(hatch none 0.5)
		(connect_pads
			(clearance 0)
		)
		(min_thickness 0.25)
		(keepout
			(tracks not_allowed)
			(vias allowed)
			(pads allowed)
			(copperpour not_allowed)
			(footprints allowed)
		)
		(placement
			(enabled no)
			(sheetname "")
		)
		(fill yes
			(thermal_gap 0.5)
			(thermal_bridge_width 0.5)
			(island_removal_mode 0)
		)
		(polygon
			(pts
				(arc
					(start 17.938242 -297.635422)
					(mid 17.277842 -297.635422)
					(end 17.938242 -297.635422)
				)
			)
		)
	)
	(zone
		(layers "In1.Cu" "In2.Cu")
		(hatch none 0.5)
		(connect_pads
			(clearance 0)
		)
		(min_thickness 0.25)
		(keepout
			(tracks not_allowed)
			(vias allowed)
			(pads allowed)
			(copperpour not_allowed)
			(footprints allowed)
		)
		(placement
			(enabled no)
			(sheetname "")
		)
		(fill yes
			(thermal_gap 0.5)
			(thermal_bridge_width 0.5)
			(island_removal_mode 0)
		)
		(polygon
			(pts
				(arc
					(start 40.57015 -305.285394)
					(mid 39.90975 -305.285394)
					(end 40.57015 -305.285394)
				)
			)
		)
	)
	(zone
		(layers "In1.Cu" "In2.Cu")
		(hatch none 0.5)
		(connect_pads
			(clearance 0)
		)
		(min_thickness 0.25)
		(keepout
			(tracks not_allowed)
			(vias allowed)
			(pads allowed)
			(copperpour not_allowed)
			(footprints allowed)
		)
		(placement
			(enabled no)
			(sheetname "")
		)
		(fill yes
			(thermal_gap 0.5)
			(thermal_bridge_width 0.5)
			(island_removal_mode 0)
		)
		(polygon
			(pts
				(arc
					(start 454.518268 -210.085178)
					(mid 453.857868 -210.085178)
					(end 454.518268 -210.085178)
				)
			)
		)
	)
	(zone
		(layers "In1.Cu" "In2.Cu")
		(hatch none 0.5)
		(connect_pads
			(clearance 0)
		)
		(min_thickness 0.25)
		(keepout
			(tracks not_allowed)
			(vias allowed)
			(pads allowed)
			(copperpour not_allowed)
			(footprints allowed)
		)
		(placement
			(enabled no)
			(sheetname "")
		)
		(fill yes
			(thermal_gap 0.5)
			(thermal_bridge_width 0.5)
			(island_removal_mode 0)
		)
		(polygon
			(pts
				(arc
					(start 337.272376 -417.242244)
					(mid 337.294694 -417.296126)
					(end 337.348576 -417.318444)
				)
				(arc
					(start 337.544156 -417.318444)
					(mid 337.566032 -417.315312)
					(end 337.586066 -417.305998)
				)
				(arc
					(start 337.87969 -417.113466)
					(mid 337.921346 -417.101064)
					(end 337.963002 -417.113466)
				)
				(arc
					(start 338.257896 -417.305998)
					(mid 338.27782 -417.315234)
					(end 338.299552 -417.318444)
				)
				(arc
					(start 338.494116 -417.318444)
					(mid 338.547998 -417.296126)
					(end 338.570316 -417.242244)
				)
				(arc
					(start 338.570316 -416.556444)
					(mid 338.547998 -416.502562)
					(end 338.494116 -416.480244)
				)
				(arc
					(start 338.299552 -416.480244)
					(mid 338.277808 -416.483412)
					(end 338.257896 -416.49269)
				)
				(arc
					(start 337.961732 -416.685476)
					(mid 337.920048 -416.697698)
					(end 337.87842 -416.685222)
				)
				(arc
					(start 337.584796 -416.49269)
					(mid 337.564872 -416.483454)
					(end 337.54314 -416.480244)
				)
				(arc
					(start 337.348576 -416.480244)
					(mid 337.294694 -416.502562)
					(end 337.272376 -416.556444)
				)
			)
		)
	)
	(zone
		(layers "In1.Cu" "In2.Cu")
		(hatch none 0.5)
		(connect_pads
			(clearance 0)
		)
		(min_thickness 0.25)
		(keepout
			(tracks not_allowed)
			(vias allowed)
			(pads allowed)
			(copperpour not_allowed)
			(footprints allowed)
		)
		(placement
			(enabled no)
			(sheetname "")
		)
		(fill yes
			(thermal_gap 0.5)
			(thermal_bridge_width 0.5)
			(island_removal_mode 0)
		)
		(polygon
			(pts
				(arc
					(start 179.846224 -312.085228)
					(mid 179.185824 -312.085228)
					(end 179.846224 -312.085228)
				)
			)
		)
	)
	(zone
		(layers "In1.Cu" "In2.Cu")
		(hatch none 0.5)
		(connect_pads
			(clearance 0)
		)
		(min_thickness 0.25)
		(keepout
			(tracks not_allowed)
			(vias allowed)
			(pads allowed)
			(copperpour not_allowed)
			(footprints allowed)
		)
		(placement
			(enabled no)
			(sheetname "")
		)
		(fill yes
			(thermal_gap 0.5)
			(thermal_bridge_width 0.5)
			(island_removal_mode 0)
		)
		(polygon
			(pts
				(arc
					(start 446.974468 -270.43507)
					(mid 446.314068 -270.43507)
					(end 446.974468 -270.43507)
				)
			)
		)
	)
	(zone
		(layers "In1.Cu" "In2.Cu")
		(hatch none 0.5)
		(connect_pads
			(clearance 0)
		)
		(min_thickness 0.25)
		(keepout
			(tracks not_allowed)
			(vias allowed)
			(pads allowed)
			(copperpour not_allowed)
			(footprints allowed)
		)
		(placement
			(enabled no)
			(sheetname "")
		)
		(fill yes
			(thermal_gap 0.5)
			(thermal_bridge_width 0.5)
			(island_removal_mode 0)
		)
		(polygon
			(pts
				(arc
					(start 420.242238 -314.635134)
					(mid 419.581838 -314.635134)
					(end 420.242238 -314.635134)
				)
			)
		)
	)
	(zone
		(layers "In1.Cu" "In2.Cu")
		(hatch none 0.5)
		(connect_pads
			(clearance 0)
		)
		(min_thickness 0.25)
		(keepout
			(tracks not_allowed)
			(vias allowed)
			(pads allowed)
			(copperpour not_allowed)
			(footprints allowed)
		)
		(placement
			(enabled no)
			(sheetname "")
		)
		(fill yes
			(thermal_gap 0.5)
			(thermal_bridge_width 0.5)
			(island_removal_mode 0)
		)
		(polygon
			(pts
				(arc
					(start 183.946292 -204.985366)
					(mid 183.285892 -204.985366)
					(end 183.946292 -204.985366)
				)
			)
		)
	)
	(zone
		(layers "In1.Cu" "In2.Cu")
		(hatch none 0.5)
		(connect_pads
			(clearance 0)
		)
		(min_thickness 0.25)
		(keepout
			(tracks not_allowed)
			(vias allowed)
			(pads allowed)
			(copperpour not_allowed)
			(footprints allowed)
		)
		(placement
			(enabled no)
			(sheetname "")
		)
		(fill yes
			(thermal_gap 0.5)
			(thermal_bridge_width 0.5)
			(island_removal_mode 0)
		)
		(polygon
			(pts
				(arc
					(start 29.582364 -234.73537)
					(mid 28.921964 -234.73537)
					(end 29.582364 -234.73537)
				)
			)
		)
	)
	(zone
		(layers "In1.Cu" "In2.Cu")
		(hatch none 0.5)
		(connect_pads
			(clearance 0)
		)
		(min_thickness 0.25)
		(keepout
			(tracks not_allowed)
			(vias allowed)
			(pads allowed)
			(copperpour not_allowed)
			(footprints allowed)
		)
		(placement
			(enabled no)
			(sheetname "")
		)
		(fill yes
			(thermal_gap 0.5)
			(thermal_bridge_width 0.5)
			(island_removal_mode 0)
		)
		(polygon
			(pts
				(arc
					(start 454.518268 -245.785132)
					(mid 453.857868 -245.785132)
					(end 454.518268 -245.785132)
				)
			)
		)
	)
	(zone
		(layers "In1.Cu" "In2.Cu")
		(hatch none 0.5)
		(connect_pads
			(clearance 0)
		)
		(min_thickness 0.25)
		(keepout
			(tracks not_allowed)
			(vias allowed)
			(pads allowed)
			(copperpour not_allowed)
			(footprints allowed)
		)
		(placement
			(enabled no)
			(sheetname "")
		)
		(fill yes
			(thermal_gap 0.5)
			(thermal_bridge_width 0.5)
			(island_removal_mode 0)
		)
		(polygon
			(pts
				(arc
					(start 431.88636 -276.38502)
					(mid 431.22596 -276.38502)
					(end 431.88636 -276.38502)
				)
			)
		)
	)
	(zone
		(layers "In1.Cu" "In2.Cu")
		(hatch none 0.5)
		(connect_pads
			(clearance 0)
		)
		(min_thickness 0.25)
		(keepout
			(tracks not_allowed)
			(vias allowed)
			(pads allowed)
			(copperpour not_allowed)
			(footprints allowed)
		)
		(placement
			(enabled no)
			(sheetname "")
		)
		(fill yes
			(thermal_gap 0.5)
			(thermal_bridge_width 0.5)
			(island_removal_mode 0)
		)
		(polygon
			(pts
				(arc
					(start 54.761638 -11.91768)
					(mid 54.73932 -11.971562)
					(end 54.685438 -11.99388)
				)
				(arc
					(start 53.648864 -11.99388)
					(mid 53.594982 -11.971562)
					(end 53.572664 -11.91768)
				)
				(arc
					(start 53.572664 -10.51814)
					(mid 53.594982 -10.464258)
					(end 53.648864 -10.44194)
				)
				(arc
					(start 54.685438 -10.44194)
					(mid 54.73932 -10.464258)
					(end 54.761638 -10.51814)
				)
			)
		)
	)
	(zone
		(layers "In1.Cu" "In2.Cu")
		(hatch none 0.5)
		(connect_pads
			(clearance 0)
		)
		(min_thickness 0.25)
		(keepout
			(tracks not_allowed)
			(vias allowed)
			(pads allowed)
			(copperpour not_allowed)
			(footprints allowed)
		)
		(placement
			(enabled no)
			(sheetname "")
		)
		(fill yes
			(thermal_gap 0.5)
			(thermal_bridge_width 0.5)
			(island_removal_mode 0)
		)
		(polygon
			(pts
				(arc
					(start 44.670218 -199.035416)
					(mid 44.009818 -199.035416)
					(end 44.670218 -199.035416)
				)
			)
		)
	)
	(zone
		(layers "In1.Cu" "In2.Cu")
		(hatch none 0.5)
		(connect_pads
			(clearance 0)
		)
		(min_thickness 0.25)
		(keepout
			(tracks not_allowed)
			(vias allowed)
			(pads allowed)
			(copperpour not_allowed)
			(footprints allowed)
		)
		(placement
			(enabled no)
			(sheetname "")
		)
		(fill yes
			(thermal_gap 0.5)
			(thermal_bridge_width 0.5)
			(island_removal_mode 0)
		)
		(polygon
			(pts
				(arc
					(start 44.670218 -208.38541)
					(mid 44.009818 -208.38541)
					(end 44.670218 -208.38541)
				)
			)
		)
	)
	(zone
		(layers "In1.Cu" "In2.Cu")
		(hatch none 0.5)
		(connect_pads
			(clearance 0)
		)
		(min_thickness 0.25)
		(keepout
			(tracks not_allowed)
			(vias allowed)
			(pads allowed)
			(copperpour not_allowed)
			(footprints allowed)
		)
		(placement
			(enabled no)
			(sheetname "")
		)
		(fill yes
			(thermal_gap 0.5)
			(thermal_bridge_width 0.5)
			(island_removal_mode 0)
		)
		(polygon
			(pts
				(arc
					(start 142.246096 -408.860244)
					(mid 142.268414 -408.914126)
					(end 142.322296 -408.936444)
				)
				(arc
					(start 142.517876 -408.936444)
					(mid 142.539752 -408.933312)
					(end 142.559786 -408.923998)
				)
				(arc
					(start 142.85341 -408.731466)
					(mid 142.895066 -408.719064)
					(end 142.936722 -408.731466)
				)
				(arc
					(start 143.231616 -408.923998)
					(mid 143.25154 -408.933234)
					(end 143.273272 -408.936444)
				)
				(arc
					(start 143.467836 -408.936444)
					(mid 143.521718 -408.914126)
					(end 143.544036 -408.860244)
				)
				(arc
					(start 143.544036 -408.174444)
					(mid 143.521718 -408.120562)
					(end 143.467836 -408.098244)
				)
				(arc
					(start 143.273272 -408.098244)
					(mid 143.251528 -408.101412)
					(end 143.231616 -408.11069)
				)
				(arc
					(start 142.935452 -408.303476)
					(mid 142.893768 -408.315698)
					(end 142.85214 -408.303222)
				)
				(arc
					(start 142.558516 -408.11069)
					(mid 142.538592 -408.101454)
					(end 142.51686 -408.098244)
				)
				(arc
					(start 142.322296 -408.098244)
					(mid 142.268414 -408.120562)
					(end 142.246096 -408.174444)
				)
			)
		)
	)
	(zone
		(layers "In1.Cu" "In2.Cu")
		(hatch none 0.5)
		(connect_pads
			(clearance 0)
		)
		(min_thickness 0.25)
		(keepout
			(tracks not_allowed)
			(vias allowed)
			(pads allowed)
			(copperpour not_allowed)
			(footprints allowed)
		)
		(placement
			(enabled no)
			(sheetname "")
		)
		(fill yes
			(thermal_gap 0.5)
			(thermal_bridge_width 0.5)
			(island_removal_mode 0)
		)
		(polygon
			(pts
				(arc
					(start 176.402238 -208.38541)
					(mid 175.741838 -208.38541)
					(end 176.402238 -208.38541)
				)
			)
		)
	)
	(zone
		(layers "In1.Cu" "In2.Cu")
		(hatch none 0.5)
		(connect_pads
			(clearance 0)
		)
		(min_thickness 0.25)
		(keepout
			(tracks not_allowed)
			(vias allowed)
			(pads allowed)
			(copperpour not_allowed)
			(footprints allowed)
		)
		(placement
			(enabled no)
			(sheetname "")
		)
		(fill yes
			(thermal_gap 0.5)
			(thermal_bridge_width 0.5)
			(island_removal_mode 0)
		)
		(polygon
			(pts
				(arc
					(start 29.582364 -199.035416)
					(mid 28.921964 -199.035416)
					(end 29.582364 -199.035416)
				)
			)
		)
	)
	(zone
		(layers "In1.Cu" "In2.Cu")
		(hatch none 0.5)
		(connect_pads
			(clearance 0)
		)
		(min_thickness 0.25)
		(keepout
			(tracks not_allowed)
			(vias allowed)
			(pads allowed)
			(copperpour not_allowed)
			(footprints allowed)
		)
		(placement
			(enabled no)
			(sheetname "")
		)
		(fill yes
			(thermal_gap 0.5)
			(thermal_bridge_width 0.5)
			(island_removal_mode 0)
		)
		(polygon
			(pts
				(arc
					(start 424.342306 -210.085178)
					(mid 423.681906 -210.085178)
					(end 424.342306 -210.085178)
				)
			)
		)
	)
	(zone
		(layers "In1.Cu" "In2.Cu")
		(hatch none 0.5)
		(connect_pads
			(clearance 0)
		)
		(min_thickness 0.25)
		(keepout
			(tracks not_allowed)
			(vias allowed)
			(pads allowed)
			(copperpour not_allowed)
			(footprints allowed)
		)
		(placement
			(enabled no)
			(sheetname "")
		)
		(fill yes
			(thermal_gap 0.5)
			(thermal_bridge_width 0.5)
			(island_removal_mode 0)
		)
		(polygon
			(pts
				(arc
					(start 300.15434 -227.085144)
					(mid 299.49394 -227.085144)
					(end 300.15434 -227.085144)
				)
			)
		)
	)
	(zone
		(layers "In1.Cu" "In2.Cu")
		(hatch none 0.5)
		(connect_pads
			(clearance 0)
		)
		(min_thickness 0.25)
		(keepout
			(tracks not_allowed)
			(vias allowed)
			(pads allowed)
			(copperpour not_allowed)
			(footprints allowed)
		)
		(placement
			(enabled no)
			(sheetname "")
		)
		(fill yes
			(thermal_gap 0.5)
			(thermal_bridge_width 0.5)
			(island_removal_mode 0)
		)
		(polygon
			(pts
				(arc
					(start 280.966164 -239.835182)
					(mid 280.305764 -239.835182)
					(end 280.966164 -239.835182)
				)
			)
		)
	)
	(zone
		(layers "In1.Cu" "In2.Cu")
		(hatch none 0.5)
		(connect_pads
			(clearance 0)
		)
		(min_thickness 0.25)
		(keepout
			(tracks not_allowed)
			(vias allowed)
			(pads allowed)
			(copperpour not_allowed)
			(footprints allowed)
		)
		(placement
			(enabled no)
			(sheetname "")
		)
		(fill yes
			(thermal_gap 0.5)
			(thermal_bridge_width 0.5)
			(island_removal_mode 0)
		)
		(polygon
			(pts
				(arc
					(start 177.832258 -44.05884)
					(mid 177.88614 -44.081158)
					(end 177.908458 -44.13504)
				)
				(arc
					(start 177.908458 -44.965112)
					(mid 177.88614 -45.018994)
					(end 177.832258 -45.041312)
				)
				(arc
					(start 176.384458 -45.041312)
					(mid 176.330576 -45.018994)
					(end 176.308258 -44.965112)
				)
				(arc
					(start 176.308258 -44.13504)
					(mid 176.330576 -44.081158)
					(end 176.384458 -44.05884)
				)
			)
		)
	)
	(zone
		(layers "In1.Cu" "In2.Cu")
		(hatch none 0.5)
		(connect_pads
			(clearance 0)
		)
		(min_thickness 0.25)
		(keepout
			(tracks not_allowed)
			(vias allowed)
			(pads allowed)
			(copperpour not_allowed)
			(footprints allowed)
		)
		(placement
			(enabled no)
			(sheetname "")
		)
		(fill yes
			(thermal_gap 0.5)
			(thermal_bridge_width 0.5)
			(island_removal_mode 0)
		)
		(polygon
			(pts
				(arc
					(start 172.30217 -209.235294)
					(mid 171.64177 -209.235294)
					(end 172.30217 -209.235294)
				)
			)
		)
	)
	(zone
		(layers "In1.Cu" "In2.Cu")
		(hatch none 0.5)
		(connect_pads
			(clearance 0)
		)
		(min_thickness 0.25)
		(keepout
			(tracks not_allowed)
			(vias allowed)
			(pads allowed)
			(copperpour not_allowed)
			(footprints allowed)
		)
		(placement
			(enabled no)
			(sheetname "")
		)
		(fill yes
			(thermal_gap 0.5)
			(thermal_bridge_width 0.5)
			(island_removal_mode 0)
		)
		(polygon
			(pts
				(arc
					(start 446.974468 -225.385122)
					(mid 446.314068 -225.385122)
					(end 446.974468 -225.385122)
				)
			)
		)
	)
	(zone
		(layers "In1.Cu" "In2.Cu")
		(hatch none 0.5)
		(connect_pads
			(clearance 0)
		)
		(min_thickness 0.25)
		(keepout
			(tracks not_allowed)
			(vias allowed)
			(pads allowed)
			(copperpour not_allowed)
			(footprints allowed)
		)
		(placement
			(enabled no)
			(sheetname "")
		)
		(fill yes
			(thermal_gap 0.5)
			(thermal_bridge_width 0.5)
			(island_removal_mode 0)
		)
		(polygon
			(pts
				(arc
					(start 172.30217 -284.035246)
					(mid 171.64177 -284.035246)
					(end 172.30217 -284.035246)
				)
			)
		)
	)
	(zone
		(layers "In1.Cu" "In2.Cu")
		(hatch none 0.5)
		(connect_pads
			(clearance 0)
		)
		(min_thickness 0.25)
		(keepout
			(tracks not_allowed)
			(vias allowed)
			(pads allowed)
			(copperpour not_allowed)
			(footprints allowed)
		)
		(placement
			(enabled no)
			(sheetname "")
		)
		(fill yes
			(thermal_gap 0.5)
			(thermal_bridge_width 0.5)
			(island_removal_mode 0)
		)
		(polygon
			(pts
				(arc
					(start 442.8744 -316.335156)
					(mid 442.214 -316.335156)
					(end 442.8744 -316.335156)
				)
			)
		)
	)
	(zone
		(layers "In1.Cu" "In2.Cu")
		(hatch none 0.5)
		(connect_pads
			(clearance 0)
		)
		(min_thickness 0.25)
		(keepout
			(tracks not_allowed)
			(vias allowed)
			(pads allowed)
			(copperpour not_allowed)
			(footprints allowed)
		)
		(placement
			(enabled no)
			(sheetname "")
		)
		(fill yes
			(thermal_gap 0.5)
			(thermal_bridge_width 0.5)
			(island_removal_mode 0)
		)
		(polygon
			(pts
				(arc
					(start 25.482296 -285.735268)
					(mid 24.821896 -285.735268)
					(end 25.482296 -285.735268)
				)
			)
		)
	)
	(zone
		(layers "In1.Cu" "In2.Cu")
		(hatch none 0.5)
		(connect_pads
			(clearance 0)
		)
		(min_thickness 0.25)
		(keepout
			(tracks not_allowed)
			(vias allowed)
			(pads allowed)
			(copperpour not_allowed)
			(footprints allowed)
		)
		(placement
			(enabled no)
			(sheetname "")
		)
		(fill yes
			(thermal_gap 0.5)
			(thermal_bridge_width 0.5)
			(island_removal_mode 0)
		)
		(polygon
			(pts
				(arc
					(start 277.522432 -234.735116)
					(mid 276.862032 -234.735116)
					(end 277.522432 -234.735116)
				)
			)
		)
	)
	(zone
		(layers "In1.Cu" "In2.Cu")
		(hatch none 0.5)
		(connect_pads
			(clearance 0)
		)
		(min_thickness 0.25)
		(keepout
			(tracks not_allowed)
			(vias allowed)
			(pads allowed)
			(copperpour not_allowed)
			(footprints allowed)
		)
		(placement
			(enabled no)
			(sheetname "")
		)
		(fill yes
			(thermal_gap 0.5)
			(thermal_bridge_width 0.5)
			(island_removal_mode 0)
		)
		(polygon
			(pts
				(arc
					(start 296.054272 -305.28514)
					(mid 295.393872 -305.28514)
					(end 296.054272 -305.28514)
				)
			)
		)
	)
	(zone
		(layers "In1.Cu" "In2.Cu")
		(hatch none 0.5)
		(connect_pads
			(clearance 0)
		)
		(min_thickness 0.25)
		(keepout
			(tracks not_allowed)
			(vias allowed)
			(pads allowed)
			(copperpour not_allowed)
			(footprints allowed)
		)
		(placement
			(enabled no)
			(sheetname "")
		)
		(fill yes
			(thermal_gap 0.5)
			(thermal_bridge_width 0.5)
			(island_removal_mode 0)
		)
		(polygon
			(pts
				(arc
					(start 113.6269 -26.792936)
					(mid 113.662821 -26.807815)
					(end 113.6777 -26.843736)
				)
				(arc
					(start 113.6777 -27.351736)
					(mid 113.662821 -27.387657)
					(end 113.6269 -27.402536)
				)
				(arc
					(start 112.970564 -27.402536)
					(mid 112.934643 -27.387657)
					(end 112.919764 -27.351736)
				)
				(arc
					(start 112.919764 -26.843736)
					(mid 112.934643 -26.807815)
					(end 112.970564 -26.792936)
				)
			)
		)
	)
	(zone
		(layers "In1.Cu" "In2.Cu")
		(hatch none 0.5)
		(connect_pads
			(clearance 0)
		)
		(min_thickness 0.25)
		(keepout
			(tracks not_allowed)
			(vias allowed)
			(pads allowed)
			(copperpour not_allowed)
			(footprints allowed)
		)
		(placement
			(enabled no)
			(sheetname "")
		)
		(fill yes
			(thermal_gap 0.5)
			(thermal_bridge_width 0.5)
			(island_removal_mode 0)
		)
		(polygon
			(pts
				(arc
					(start 435.330346 -304.435002)
					(mid 434.669946 -304.435002)
					(end 435.330346 -304.435002)
				)
			)
		)
	)
	(zone
		(layers "In1.Cu" "In2.Cu")
		(hatch none 0.5)
		(connect_pads
			(clearance 0)
		)
		(min_thickness 0.25)
		(keepout
			(tracks not_allowed)
			(vias allowed)
			(pads allowed)
			(copperpour not_allowed)
			(footprints allowed)
		)
		(placement
			(enabled no)
			(sheetname "")
		)
		(fill yes
			(thermal_gap 0.5)
			(thermal_bridge_width 0.5)
			(island_removal_mode 0)
		)
		(polygon
			(pts
				(arc
					(start 27.2415 -11.91768)
					(mid 27.219182 -11.971562)
					(end 27.1653 -11.99388)
				)
				(arc
					(start 26.128726 -11.99388)
					(mid 26.074844 -11.971562)
					(end 26.052526 -11.91768)
				)
				(arc
					(start 26.052526 -10.51814)
					(mid 26.074844 -10.464258)
					(end 26.128726 -10.44194)
				)
				(arc
					(start 27.1653 -10.44194)
					(mid 27.219182 -10.464258)
					(end 27.2415 -10.51814)
				)
			)
		)
	)
	(zone
		(layers "In1.Cu" "In2.Cu")
		(hatch none 0.5)
		(connect_pads
			(clearance 0)
		)
		(min_thickness 0.25)
		(keepout
			(tracks not_allowed)
			(vias allowed)
			(pads allowed)
			(copperpour not_allowed)
			(footprints allowed)
		)
		(placement
			(enabled no)
			(sheetname "")
		)
		(fill yes
			(thermal_gap 0.5)
			(thermal_bridge_width 0.5)
			(island_removal_mode 0)
		)
		(polygon
			(pts
				(arc
					(start 179.846224 -209.235294)
					(mid 179.185824 -209.235294)
					(end 179.846224 -209.235294)
				)
			)
		)
	)
	(zone
		(layers "In1.Cu" "In2.Cu")
		(hatch none 0.5)
		(connect_pads
			(clearance 0)
		)
		(min_thickness 0.25)
		(keepout
			(tracks not_allowed)
			(vias allowed)
			(pads allowed)
			(copperpour not_allowed)
			(footprints allowed)
		)
		(placement
			(enabled no)
			(sheetname "")
		)
		(fill yes
			(thermal_gap 0.5)
			(thermal_bridge_width 0.5)
			(island_removal_mode 0)
		)
		(polygon
			(pts
				(arc
					(start 44.670218 -283.185362)
					(mid 44.009818 -283.185362)
					(end 44.670218 -283.185362)
				)
			)
		)
	)
	(zone
		(layers "In1.Cu" "In2.Cu")
		(hatch none 0.5)
		(connect_pads
			(clearance 0)
		)
		(min_thickness 0.25)
		(keepout
			(tracks not_allowed)
			(vias allowed)
			(pads allowed)
			(copperpour not_allowed)
			(footprints allowed)
		)
		(placement
			(enabled no)
			(sheetname "")
		)
		(fill yes
			(thermal_gap 0.5)
			(thermal_bridge_width 0.5)
			(island_removal_mode 0)
		)
		(polygon
			(pts
				(arc
					(start 202.478132 -268.735302)
					(mid 201.817732 -268.735302)
					(end 202.478132 -268.735302)
				)
			)
		)
	)
	(zone
		(layers "In1.Cu" "In2.Cu")
		(hatch none 0.5)
		(connect_pads
			(clearance 0)
		)
		(min_thickness 0.25)
		(keepout
			(tracks not_allowed)
			(vias allowed)
			(pads allowed)
			(copperpour not_allowed)
			(footprints allowed)
		)
		(placement
			(enabled no)
			(sheetname "")
		)
		(fill yes
			(thermal_gap 0.5)
			(thermal_bridge_width 0.5)
			(island_removal_mode 0)
		)
		(polygon
			(pts
				(arc
					(start 202.478132 -235.585254)
					(mid 201.817732 -235.585254)
					(end 202.478132 -235.585254)
				)
			)
		)
	)
	(zone
		(layers "In1.Cu" "In2.Cu")
		(hatch none 0.5)
		(connect_pads
			(clearance 0)
		)
		(min_thickness 0.25)
		(keepout
			(tracks not_allowed)
			(vias allowed)
			(pads allowed)
			(copperpour not_allowed)
			(footprints allowed)
		)
		(placement
			(enabled no)
			(sheetname "")
		)
		(fill yes
			(thermal_gap 0.5)
			(thermal_bridge_width 0.5)
			(island_removal_mode 0)
		)
		(polygon
			(pts
				(arc
					(start 454.518268 -315.485018)
					(mid 453.857868 -315.485018)
					(end 454.518268 -315.485018)
				)
			)
		)
	)
	(zone
		(layers "In1.Cu" "In2.Cu")
		(hatch none 0.5)
		(connect_pads
			(clearance 0)
		)
		(min_thickness 0.25)
		(keepout
			(tracks not_allowed)
			(vias allowed)
			(pads allowed)
			(copperpour not_allowed)
			(footprints allowed)
		)
		(placement
			(enabled no)
			(sheetname "")
		)
		(fill yes
			(thermal_gap 0.5)
			(thermal_bridge_width 0.5)
			(island_removal_mode 0)
		)
		(polygon
			(pts
				(arc
					(start 296.054272 -289.985196)
					(mid 295.393872 -289.985196)
					(end 296.054272 -289.985196)
				)
			)
		)
	)
	(zone
		(layers "In1.Cu" "In2.Cu")
		(hatch none 0.5)
		(connect_pads
			(clearance 0)
		)
		(min_thickness 0.25)
		(keepout
			(tracks not_allowed)
			(vias allowed)
			(pads allowed)
			(copperpour not_allowed)
			(footprints allowed)
		)
		(placement
			(enabled no)
			(sheetname "")
		)
		(fill yes
			(thermal_gap 0.5)
			(thermal_bridge_width 0.5)
			(island_removal_mode 0)
		)
		(polygon
			(pts
				(arc
					(start 277.522432 -200.735184)
					(mid 276.862032 -200.735184)
					(end 277.522432 -200.735184)
				)
			)
		)
	)
	(zone
		(layers "In1.Cu" "In2.Cu")
		(hatch none 0.5)
		(connect_pads
			(clearance 0)
		)
		(min_thickness 0.25)
		(keepout
			(tracks not_allowed)
			(vias allowed)
			(pads allowed)
			(copperpour not_allowed)
			(footprints allowed)
		)
		(placement
			(enabled no)
			(sheetname "")
		)
		(fill yes
			(thermal_gap 0.5)
			(thermal_bridge_width 0.5)
			(island_removal_mode 0)
		)
		(polygon
			(pts
				(arc
					(start 427.786292 -261.93496)
					(mid 427.125892 -261.93496)
					(end 427.786292 -261.93496)
				)
			)
		)
	)
	(zone
		(layers "In1.Cu" "In2.Cu")
		(hatch none 0.5)
		(connect_pads
			(clearance 0)
		)
		(min_thickness 0.25)
		(keepout
			(tracks not_allowed)
			(vias allowed)
			(pads allowed)
			(copperpour not_allowed)
			(footprints allowed)
		)
		(placement
			(enabled no)
			(sheetname "")
		)
		(fill yes
			(thermal_gap 0.5)
			(thermal_bridge_width 0.5)
			(island_removal_mode 0)
		)
		(polygon
			(pts
				(arc
					(start 442.8744 -299.33519)
					(mid 442.214 -299.33519)
					(end 442.8744 -299.33519)
				)
			)
		)
	)
	(zone
		(layers "In1.Cu" "In2.Cu")
		(hatch none 0.5)
		(connect_pads
			(clearance 0)
		)
		(min_thickness 0.25)
		(keepout
			(tracks not_allowed)
			(vias allowed)
			(pads allowed)
			(copperpour not_allowed)
			(footprints allowed)
		)
		(placement
			(enabled no)
			(sheetname "")
		)
		(fill yes
			(thermal_gap 0.5)
			(thermal_bridge_width 0.5)
			(island_removal_mode 0)
		)
		(polygon
			(pts
				(arc
					(start 446.974468 -317.18504)
					(mid 446.314068 -317.18504)
					(end 446.974468 -317.18504)
				)
			)
		)
	)
	(zone
		(layers "In1.Cu" "In2.Cu")
		(hatch none 0.5)
		(connect_pads
			(clearance 0)
		)
		(min_thickness 0.25)
		(keepout
			(tracks not_allowed)
			(vias allowed)
			(pads allowed)
			(copperpour not_allowed)
			(footprints allowed)
		)
		(placement
			(enabled no)
			(sheetname "")
		)
		(fill yes
			(thermal_gap 0.5)
			(thermal_bridge_width 0.5)
			(island_removal_mode 0)
		)
		(polygon
			(pts
				(arc
					(start 454.518268 -317.18504)
					(mid 453.857868 -317.18504)
					(end 454.518268 -317.18504)
				)
			)
		)
	)
	(zone
		(layers "In1.Cu" "In2.Cu")
		(hatch none 0.5)
		(connect_pads
			(clearance 0)
		)
		(min_thickness 0.25)
		(keepout
			(tracks not_allowed)
			(vias allowed)
			(pads allowed)
			(copperpour not_allowed)
			(footprints allowed)
		)
		(placement
			(enabled no)
			(sheetname "")
		)
		(fill yes
			(thermal_gap 0.5)
			(thermal_bridge_width 0.5)
			(island_removal_mode 0)
		)
		(polygon
			(pts
				(arc
					(start 280.966164 -280.634948)
					(mid 280.305764 -280.634948)
					(end 280.966164 -280.634948)
				)
			)
		)
	)
	(zone
		(layers "In1.Cu" "In2.Cu")
		(hatch none 0.5)
		(connect_pads
			(clearance 0)
		)
		(min_thickness 0.25)
		(keepout
			(tracks not_allowed)
			(vias allowed)
			(pads allowed)
			(copperpour not_allowed)
			(footprints allowed)
		)
		(placement
			(enabled no)
			(sheetname "")
		)
		(fill yes
			(thermal_gap 0.5)
			(thermal_bridge_width 0.5)
			(island_removal_mode 0)
		)
		(polygon
			(pts
				(arc
					(start 45.3517 -11.91768)
					(mid 45.329382 -11.971562)
					(end 45.2755 -11.99388)
				)
				(arc
					(start 44.238926 -11.99388)
					(mid 44.185044 -11.971562)
					(end 44.162726 -11.91768)
				)
				(arc
					(start 44.162726 -10.51814)
					(mid 44.185044 -10.464258)
					(end 44.238926 -10.44194)
				)
				(arc
					(start 45.2755 -10.44194)
					(mid 45.329382 -10.464258)
					(end 45.3517 -10.51814)
				)
			)
		)
	)
	(zone
		(layers "In1.Cu" "In2.Cu")
		(hatch none 0.5)
		(connect_pads
			(clearance 0)
		)
		(min_thickness 0.25)
		(keepout
			(tracks not_allowed)
			(vias allowed)
			(pads allowed)
			(copperpour not_allowed)
			(footprints allowed)
		)
		(placement
			(enabled no)
			(sheetname "")
		)
		(fill yes
			(thermal_gap 0.5)
			(thermal_bridge_width 0.5)
			(island_removal_mode 0)
		)
		(polygon
			(pts
				(arc
					(start 52.214272 -313.78525)
					(mid 51.553872 -313.78525)
					(end 52.214272 -313.78525)
				)
			)
		)
	)
	(zone
		(layers "In1.Cu" "In2.Cu")
		(hatch none 0.5)
		(connect_pads
			(clearance 0)
		)
		(min_thickness 0.25)
		(keepout
			(tracks not_allowed)
			(vias allowed)
			(pads allowed)
			(copperpour not_allowed)
			(footprints allowed)
		)
		(placement
			(enabled no)
			(sheetname "")
		)
		(fill yes
			(thermal_gap 0.5)
			(thermal_bridge_width 0.5)
			(island_removal_mode 0)
		)
		(polygon
			(pts
				(arc
					(start 431.88636 -289.135058)
					(mid 431.22596 -289.135058)
					(end 431.88636 -289.135058)
				)
			)
		)
	)
	(zone
		(layers "In1.Cu" "In2.Cu")
		(hatch none 0.5)
		(connect_pads
			(clearance 0)
		)
		(min_thickness 0.25)
		(keepout
			(tracks not_allowed)
			(vias allowed)
			(pads allowed)
			(copperpour not_allowed)
			(footprints allowed)
		)
		(placement
			(enabled no)
			(sheetname "")
		)
		(fill yes
			(thermal_gap 0.5)
			(thermal_bridge_width 0.5)
			(island_removal_mode 0)
		)
		(polygon
			(pts
				(arc
					(start 431.88636 -225.385122)
					(mid 431.22596 -225.385122)
					(end 431.88636 -225.385122)
				)
			)
		)
	)
	(zone
		(layers "In1.Cu" "In2.Cu")
		(hatch none 0.5)
		(connect_pads
			(clearance 0)
		)
		(min_thickness 0.25)
		(keepout
			(tracks not_allowed)
			(vias allowed)
			(pads allowed)
			(copperpour not_allowed)
			(footprints allowed)
		)
		(placement
			(enabled no)
			(sheetname "")
		)
		(fill yes
			(thermal_gap 0.5)
			(thermal_bridge_width 0.5)
			(island_removal_mode 0)
		)
		(polygon
			(pts
				(arc
					(start 52.214272 -283.185362)
					(mid 51.553872 -283.185362)
					(end 52.214272 -283.185362)
				)
			)
		)
	)
	(zone
		(layers "In1.Cu" "In2.Cu")
		(hatch none 0.5)
		(connect_pads
			(clearance 0)
		)
		(min_thickness 0.25)
		(keepout
			(tracks not_allowed)
			(vias allowed)
			(pads allowed)
			(copperpour not_allowed)
			(footprints allowed)
		)
		(placement
			(enabled no)
			(sheetname "")
		)
		(fill yes
			(thermal_gap 0.5)
			(thermal_bridge_width 0.5)
			(island_removal_mode 0)
		)
		(polygon
			(pts
				(arc
					(start 442.8744 -318.035178)
					(mid 442.214 -318.035178)
					(end 442.8744 -318.035178)
				)
			)
		)
	)
	(zone
		(layers "In1.Cu" "In2.Cu")
		(hatch none 0.5)
		(connect_pads
			(clearance 0)
		)
		(min_thickness 0.25)
		(keepout
			(tracks not_allowed)
			(vias allowed)
			(pads allowed)
			(copperpour not_allowed)
			(footprints allowed)
		)
		(placement
			(enabled no)
			(sheetname "")
		)
		(fill yes
			(thermal_gap 0.5)
			(thermal_bridge_width 0.5)
			(island_removal_mode 0)
		)
		(polygon
			(pts
				(arc
					(start 300.15434 -216.035128)
					(mid 299.49394 -216.035128)
					(end 300.15434 -216.035128)
				)
			)
		)
	)
	(zone
		(layers "In1.Cu" "In2.Cu")
		(hatch none 0.5)
		(connect_pads
			(clearance 0)
		)
		(min_thickness 0.25)
		(keepout
			(tracks not_allowed)
			(vias allowed)
			(pads allowed)
			(copperpour not_allowed)
			(footprints allowed)
		)
		(placement
			(enabled no)
			(sheetname "")
		)
		(fill yes
			(thermal_gap 0.5)
			(thermal_bridge_width 0.5)
			(island_removal_mode 0)
		)
		(polygon
			(pts
				(arc
					(start 442.8744 -232.184956)
					(mid 442.214 -232.184956)
					(end 442.8744 -232.184956)
				)
			)
		)
	)
	(zone
		(layers "In1.Cu" "In2.Cu")
		(hatch none 0.5)
		(connect_pads
			(clearance 0)
		)
		(min_thickness 0.25)
		(keepout
			(tracks not_allowed)
			(vias allowed)
			(pads allowed)
			(copperpour not_allowed)
			(footprints allowed)
		)
		(placement
			(enabled no)
			(sheetname "")
		)
		(fill yes
			(thermal_gap 0.5)
			(thermal_bridge_width 0.5)
			(island_removal_mode 0)
		)
		(polygon
			(pts
				(arc
					(start 269.978378 -234.735116)
					(mid 269.317978 -234.735116)
					(end 269.978378 -234.735116)
				)
			)
		)
	)
	(zone
		(layers "In1.Cu" "In2.Cu")
		(hatch none 0.5)
		(connect_pads
			(clearance 0)
		)
		(min_thickness 0.25)
		(keepout
			(tracks not_allowed)
			(vias allowed)
			(pads allowed)
			(copperpour not_allowed)
			(footprints allowed)
		)
		(placement
			(enabled no)
			(sheetname "")
		)
		(fill yes
			(thermal_gap 0.5)
			(thermal_bridge_width 0.5)
			(island_removal_mode 0)
		)
		(polygon
			(pts
				(arc
					(start 273.422364 -304.435002)
					(mid 272.761964 -304.435002)
					(end 273.422364 -304.435002)
				)
			)
		)
	)
	(zone
		(layers "In1.Cu" "In2.Cu")
		(hatch none 0.5)
		(connect_pads
			(clearance 0)
		)
		(min_thickness 0.25)
		(keepout
			(tracks not_allowed)
			(vias allowed)
			(pads allowed)
			(copperpour not_allowed)
			(footprints allowed)
		)
		(placement
			(enabled no)
			(sheetname "")
		)
		(fill yes
			(thermal_gap 0.5)
			(thermal_bridge_width 0.5)
			(island_removal_mode 0)
		)
		(polygon
			(pts
				(arc
					(start 44.670218 -313.78525)
					(mid 44.009818 -313.78525)
					(end 44.670218 -313.78525)
				)
			)
		)
	)
	(zone
		(layers "In1.Cu" "In2.Cu")
		(hatch none 0.5)
		(connect_pads
			(clearance 0)
		)
		(min_thickness 0.25)
		(keepout
			(tracks not_allowed)
			(vias allowed)
			(pads allowed)
			(copperpour not_allowed)
			(footprints allowed)
		)
		(placement
			(enabled no)
			(sheetname "")
		)
		(fill yes
			(thermal_gap 0.5)
			(thermal_bridge_width 0.5)
			(island_removal_mode 0)
		)
		(polygon
			(pts
				(arc
					(start 52.214272 -273.835368)
					(mid 51.553872 -273.835368)
					(end 52.214272 -273.835368)
				)
			)
		)
	)
	(zone
		(layers "In1.Cu" "In2.Cu")
		(hatch none 0.5)
		(connect_pads
			(clearance 0)
		)
		(min_thickness 0.25)
		(keepout
			(tracks not_allowed)
			(vias allowed)
			(pads allowed)
			(copperpour not_allowed)
			(footprints allowed)
		)
		(placement
			(enabled no)
			(sheetname "")
		)
		(fill yes
			(thermal_gap 0.5)
			(thermal_bridge_width 0.5)
			(island_removal_mode 0)
		)
		(polygon
			(pts
				(arc
					(start 300.15434 -238.13516)
					(mid 299.49394 -238.13516)
					(end 300.15434 -238.13516)
				)
			)
		)
	)
	(zone
		(layers "In1.Cu" "In2.Cu")
		(hatch none 0.5)
		(connect_pads
			(clearance 0)
		)
		(min_thickness 0.25)
		(keepout
			(tracks not_allowed)
			(vias allowed)
			(pads allowed)
			(copperpour not_allowed)
			(footprints allowed)
		)
		(placement
			(enabled no)
			(sheetname "")
		)
		(fill yes
			(thermal_gap 0.5)
			(thermal_bridge_width 0.5)
			(island_removal_mode 0)
		)
		(polygon
			(pts
				(arc
					(start 187.390278 -210.935316)
					(mid 186.729878 -210.935316)
					(end 187.390278 -210.935316)
				)
			)
		)
	)
	(zone
		(layers "In1.Cu" "In2.Cu")
		(hatch none 0.5)
		(connect_pads
			(clearance 0)
		)
		(min_thickness 0.25)
		(keepout
			(tracks not_allowed)
			(vias allowed)
			(pads allowed)
			(copperpour not_allowed)
			(footprints allowed)
		)
		(placement
			(enabled no)
			(sheetname "")
		)
		(fill yes
			(thermal_gap 0.5)
			(thermal_bridge_width 0.5)
			(island_removal_mode 0)
		)
		(polygon
			(pts
				(arc
					(start 52.214272 -221.985332)
					(mid 51.553872 -221.985332)
					(end 52.214272 -221.985332)
				)
			)
		)
	)
	(zone
		(layers "In1.Cu" "In2.Cu")
		(hatch none 0.5)
		(connect_pads
			(clearance 0)
		)
		(min_thickness 0.25)
		(keepout
			(tracks not_allowed)
			(vias allowed)
			(pads allowed)
			(copperpour not_allowed)
			(footprints allowed)
		)
		(placement
			(enabled no)
			(sheetname "")
		)
		(fill yes
			(thermal_gap 0.5)
			(thermal_bridge_width 0.5)
			(island_removal_mode 0)
		)
		(polygon
			(pts
				(arc
					(start 37.126164 -220.28531)
					(mid 36.465764 -220.28531)
					(end 37.126164 -220.28531)
				)
			)
		)
	)
	(zone
		(layers "In1.Cu" "In2.Cu")
		(hatch none 0.5)
		(connect_pads
			(clearance 0)
		)
		(min_thickness 0.25)
		(keepout
			(tracks not_allowed)
			(vias allowed)
			(pads allowed)
			(copperpour not_allowed)
			(footprints allowed)
		)
		(placement
			(enabled no)
			(sheetname "")
		)
		(fill yes
			(thermal_gap 0.5)
			(thermal_bridge_width 0.5)
			(island_removal_mode 0)
		)
		(polygon
			(pts
				(arc
					(start 187.390278 -232.18521)
					(mid 186.729878 -232.18521)
					(end 187.390278 -232.18521)
				)
			)
		)
	)
	(zone
		(layers "In1.Cu" "In2.Cu")
		(hatch none 0.5)
		(connect_pads
			(clearance 0)
		)
		(min_thickness 0.25)
		(keepout
			(tracks not_allowed)
			(vias allowed)
			(pads allowed)
			(copperpour not_allowed)
			(footprints allowed)
		)
		(placement
			(enabled no)
			(sheetname "")
		)
		(fill yes
			(thermal_gap 0.5)
			(thermal_bridge_width 0.5)
			(island_removal_mode 0)
		)
		(polygon
			(pts
				(arc
					(start 187.390278 -216.885266)
					(mid 186.729878 -216.885266)
					(end 187.390278 -216.885266)
				)
			)
		)
	)
	(zone
		(layers "In1.Cu" "In2.Cu")
		(hatch none 0.5)
		(connect_pads
			(clearance 0)
		)
		(min_thickness 0.25)
		(keepout
			(tracks not_allowed)
			(vias allowed)
			(pads allowed)
			(copperpour not_allowed)
			(footprints allowed)
		)
		(placement
			(enabled no)
			(sheetname "")
		)
		(fill yes
			(thermal_gap 0.5)
			(thermal_bridge_width 0.5)
			(island_removal_mode 0)
		)
		(polygon
			(pts
				(arc
					(start 424.342306 -203.28509)
					(mid 423.681906 -203.28509)
					(end 424.342306 -203.28509)
				)
			)
		)
	)
	(zone
		(layers "In1.Cu" "In2.Cu")
		(hatch none 0.5)
		(connect_pads
			(clearance 0)
		)
		(min_thickness 0.25)
		(keepout
			(tracks not_allowed)
			(vias allowed)
			(pads allowed)
			(copperpour not_allowed)
			(footprints allowed)
		)
		(placement
			(enabled no)
			(sheetname "")
		)
		(fill yes
			(thermal_gap 0.5)
			(thermal_bridge_width 0.5)
			(island_removal_mode 0)
		)
		(polygon
			(pts
				(arc
					(start 442.8744 -251.735082)
					(mid 442.214 -251.735082)
					(end 442.8744 -251.735082)
				)
			)
		)
	)
	(zone
		(layers "In1.Cu" "In2.Cu")
		(hatch none 0.5)
		(connect_pads
			(clearance 0)
		)
		(min_thickness 0.25)
		(keepout
			(tracks not_allowed)
			(vias allowed)
			(pads allowed)
			(copperpour not_allowed)
			(footprints allowed)
		)
		(placement
			(enabled no)
			(sheetname "")
		)
		(fill yes
			(thermal_gap 0.5)
			(thermal_bridge_width 0.5)
			(island_removal_mode 0)
		)
		(polygon
			(pts
				(arc
					(start 427.786292 -244.934994)
					(mid 427.125892 -244.934994)
					(end 427.786292 -244.934994)
				)
			)
		)
	)
	(zone
		(layers "In1.Cu" "In2.Cu")
		(hatch none 0.5)
		(connect_pads
			(clearance 0)
		)
		(min_thickness 0.25)
		(keepout
			(tracks not_allowed)
			(vias allowed)
			(pads allowed)
			(copperpour not_allowed)
			(footprints allowed)
		)
		(placement
			(enabled no)
			(sheetname "")
		)
		(fill yes
			(thermal_gap 0.5)
			(thermal_bridge_width 0.5)
			(island_removal_mode 0)
		)
		(polygon
			(pts
				(arc
					(start 187.390278 -295.085262)
					(mid 186.729878 -295.085262)
					(end 187.390278 -295.085262)
				)
			)
		)
	)
	(zone
		(layers "In1.Cu" "In2.Cu")
		(hatch none 0.5)
		(connect_pads
			(clearance 0)
		)
		(min_thickness 0.25)
		(keepout
			(tracks not_allowed)
			(vias allowed)
			(pads allowed)
			(copperpour not_allowed)
			(footprints allowed)
		)
		(placement
			(enabled no)
			(sheetname "")
		)
		(fill yes
			(thermal_gap 0.5)
			(thermal_bridge_width 0.5)
			(island_removal_mode 0)
		)
		(polygon
			(pts
				(arc
					(start 52.214272 -223.685354)
					(mid 51.553872 -223.685354)
					(end 52.214272 -223.685354)
				)
			)
		)
	)
	(zone
		(layers "In1.Cu" "In2.Cu")
		(hatch none 0.5)
		(connect_pads
			(clearance 0)
		)
		(min_thickness 0.25)
		(keepout
			(tracks not_allowed)
			(vias allowed)
			(pads allowed)
			(copperpour not_allowed)
			(footprints allowed)
		)
		(placement
			(enabled no)
			(sheetname "")
		)
		(fill yes
			(thermal_gap 0.5)
			(thermal_bridge_width 0.5)
			(island_removal_mode 0)
		)
		(polygon
			(pts
				(arc
					(start 37.126164 -242.385342)
					(mid 36.465764 -242.385342)
					(end 37.126164 -242.385342)
				)
			)
		)
	)
	(zone
		(layers "In1.Cu" "In2.Cu")
		(hatch none 0.5)
		(connect_pads
			(clearance 0)
		)
		(min_thickness 0.25)
		(keepout
			(tracks not_allowed)
			(vias allowed)
			(pads allowed)
			(copperpour not_allowed)
			(footprints allowed)
		)
		(placement
			(enabled no)
			(sheetname "")
		)
		(fill yes
			(thermal_gap 0.5)
			(thermal_bridge_width 0.5)
			(island_removal_mode 0)
		)
		(polygon
			(pts
				(arc
					(start 199.0344 -229.635304)
					(mid 198.374 -229.635304)
					(end 199.0344 -229.635304)
				)
			)
		)
	)
	(zone
		(layers "In1.Cu" "In2.Cu")
		(hatch none 0.5)
		(connect_pads
			(clearance 0)
		)
		(min_thickness 0.25)
		(keepout
			(tracks not_allowed)
			(vias allowed)
			(pads allowed)
			(copperpour not_allowed)
			(footprints allowed)
		)
		(placement
			(enabled no)
			(sheetname "")
		)
		(fill yes
			(thermal_gap 0.5)
			(thermal_bridge_width 0.5)
			(island_removal_mode 0)
		)
		(polygon
			(pts
				(arc
					(start 183.946292 -240.68532)
					(mid 183.285892 -240.68532)
					(end 183.946292 -240.68532)
				)
			)
		)
	)
	(zone
		(layers "In1.Cu" "In2.Cu")
		(hatch none 0.5)
		(connect_pads
			(clearance 0)
		)
		(min_thickness 0.25)
		(keepout
			(tracks not_allowed)
			(vias allowed)
			(pads allowed)
			(copperpour not_allowed)
			(footprints allowed)
		)
		(placement
			(enabled no)
			(sheetname "")
		)
		(fill yes
			(thermal_gap 0.5)
			(thermal_bridge_width 0.5)
			(island_removal_mode 0)
		)
		(polygon
			(pts
				(arc
					(start 48.114204 -254.285242)
					(mid 47.453804 -254.285242)
					(end 48.114204 -254.285242)
				)
			)
		)
	)
	(zone
		(layers "In1.Cu" "In2.Cu")
		(hatch none 0.5)
		(connect_pads
			(clearance 0)
		)
		(min_thickness 0.25)
		(keepout
			(tracks not_allowed)
			(vias allowed)
			(pads allowed)
			(copperpour not_allowed)
			(footprints allowed)
		)
		(placement
			(enabled no)
			(sheetname "")
		)
		(fill yes
			(thermal_gap 0.5)
			(thermal_bridge_width 0.5)
			(island_removal_mode 0)
		)
		(polygon
			(pts
				(arc
					(start 439.430414 -233.035094)
					(mid 438.770014 -233.035094)
					(end 439.430414 -233.035094)
				)
			)
		)
	)
	(zone
		(layers "In1.Cu" "In2.Cu")
		(hatch none 0.5)
		(connect_pads
			(clearance 0)
		)
		(min_thickness 0.25)
		(keepout
			(tracks not_allowed)
			(vias allowed)
			(pads allowed)
			(copperpour not_allowed)
			(footprints allowed)
		)
		(placement
			(enabled no)
			(sheetname "")
		)
		(fill yes
			(thermal_gap 0.5)
			(thermal_bridge_width 0.5)
			(island_removal_mode 0)
		)
		(polygon
			(pts
				(arc
					(start 407.92019 -379.360684)
					(mid 407.940114 -379.36992)
					(end 407.961846 -379.37313)
				)
				(arc
					(start 408.15641 -379.37313)
					(mid 408.210292 -379.350812)
					(end 408.23261 -379.29693)
				)
				(arc
					(start 408.23261 -378.61113)
					(mid 408.210292 -378.557248)
					(end 408.15641 -378.53493)
				)
				(arc
					(start 407.961846 -378.53493)
					(mid 407.940102 -378.538098)
					(end 407.92019 -378.547376)
				)
				(arc
					(start 407.624026 -378.740162)
					(mid 407.582342 -378.752384)
					(end 407.540714 -378.739908)
				)
				(arc
					(start 407.24709 -378.547376)
					(mid 407.227166 -378.53814)
					(end 407.205434 -378.53493)
				)
				(arc
					(start 407.01087 -378.53493)
					(mid 406.956988 -378.557248)
					(end 406.93467 -378.61113)
				)
				(arc
					(start 406.93467 -379.29693)
					(mid 406.956988 -379.350812)
					(end 407.01087 -379.37313)
				)
				(arc
					(start 407.206704 -379.37313)
					(mid 407.228448 -379.369962)
					(end 407.24836 -379.360684)
				)
				(arc
					(start 407.541984 -379.168152)
					(mid 407.58364 -379.15575)
					(end 407.625296 -379.168152)
				)
			)
		)
	)
	(zone
		(layers "In1.Cu" "In2.Cu")
		(hatch none 0.5)
		(connect_pads
			(clearance 0)
		)
		(min_thickness 0.25)
		(keepout
			(tracks not_allowed)
			(vias allowed)
			(pads allowed)
			(copperpour not_allowed)
			(footprints allowed)
		)
		(placement
			(enabled no)
			(sheetname "")
		)
		(fill yes
			(thermal_gap 0.5)
			(thermal_bridge_width 0.5)
			(island_removal_mode 0)
		)
		(polygon
			(pts
				(arc
					(start 454.518268 -220.285056)
					(mid 453.857868 -220.285056)
					(end 454.518268 -220.285056)
				)
			)
		)
	)
	(zone
		(layers "In1.Cu" "In2.Cu")
		(hatch none 0.5)
		(connect_pads
			(clearance 0)
		)
		(min_thickness 0.25)
		(keepout
			(tracks not_allowed)
			(vias allowed)
			(pads allowed)
			(copperpour not_allowed)
			(footprints allowed)
		)
		(placement
			(enabled no)
			(sheetname "")
		)
		(fill yes
			(thermal_gap 0.5)
			(thermal_bridge_width 0.5)
			(island_removal_mode 0)
		)
		(polygon
			(pts
				(arc
					(start 431.88636 -201.585068)
					(mid 431.22596 -201.585068)
					(end 431.88636 -201.585068)
				)
			)
		)
	)
	(zone
		(layers "In1.Cu" "In2.Cu")
		(hatch none 0.5)
		(connect_pads
			(clearance 0)
		)
		(min_thickness 0.25)
		(keepout
			(tracks not_allowed)
			(vias allowed)
			(pads allowed)
			(copperpour not_allowed)
			(footprints allowed)
		)
		(placement
			(enabled no)
			(sheetname "")
		)
		(fill yes
			(thermal_gap 0.5)
			(thermal_bridge_width 0.5)
			(island_removal_mode 0)
		)
		(polygon
			(pts
				(arc
					(start 199.0344 -233.035348)
					(mid 198.374 -233.035348)
					(end 199.0344 -233.035348)
				)
			)
		)
	)
	(zone
		(layers "In1.Cu" "In2.Cu")
		(hatch none 0.5)
		(connect_pads
			(clearance 0)
		)
		(min_thickness 0.25)
		(keepout
			(tracks not_allowed)
			(vias allowed)
			(pads allowed)
			(copperpour not_allowed)
			(footprints allowed)
		)
		(placement
			(enabled no)
			(sheetname "")
		)
		(fill yes
			(thermal_gap 0.5)
			(thermal_bridge_width 0.5)
			(island_removal_mode 0)
		)
		(polygon
			(pts
				(arc
					(start 285.066232 -249.185176)
					(mid 284.405832 -249.185176)
					(end 285.066232 -249.185176)
				)
			)
		)
	)
	(zone
		(layers "In1.Cu" "In2.Cu")
		(hatch none 0.5)
		(connect_pads
			(clearance 0)
		)
		(min_thickness 0.25)
		(keepout
			(tracks not_allowed)
			(vias allowed)
			(pads allowed)
			(copperpour not_allowed)
			(footprints allowed)
		)
		(placement
			(enabled no)
			(sheetname "")
		)
		(fill yes
			(thermal_gap 0.5)
			(thermal_bridge_width 0.5)
			(island_removal_mode 0)
		)
		(polygon
			(pts
				(arc
					(start 191.490346 -219.435426)
					(mid 190.829946 -219.435426)
					(end 191.490346 -219.435426)
				)
			)
		)
	)
	(zone
		(layers "In1.Cu" "In2.Cu")
		(hatch none 0.5)
		(connect_pads
			(clearance 0)
		)
		(min_thickness 0.25)
		(keepout
			(tracks not_allowed)
			(vias allowed)
			(pads allowed)
			(copperpour not_allowed)
			(footprints allowed)
		)
		(placement
			(enabled no)
			(sheetname "")
		)
		(fill yes
			(thermal_gap 0.5)
			(thermal_bridge_width 0.5)
			(island_removal_mode 0)
		)
		(polygon
			(pts
				(arc
					(start 44.670218 -294.235378)
					(mid 44.009818 -294.235378)
					(end 44.670218 -294.235378)
				)
			)
		)
	)
	(zone
		(layers "In1.Cu" "In2.Cu")
		(hatch none 0.5)
		(connect_pads
			(clearance 0)
		)
		(min_thickness 0.25)
		(keepout
			(tracks not_allowed)
			(vias allowed)
			(pads allowed)
			(copperpour not_allowed)
			(footprints allowed)
		)
		(placement
			(enabled no)
			(sheetname "")
		)
		(fill yes
			(thermal_gap 0.5)
			(thermal_bridge_width 0.5)
			(island_removal_mode 0)
		)
		(polygon
			(pts
				(arc
					(start 442.8744 -229.63505)
					(mid 442.214 -229.63505)
					(end 442.8744 -229.63505)
				)
			)
		)
	)
	(zone
		(layers "In1.Cu" "In2.Cu")
		(hatch none 0.5)
		(connect_pads
			(clearance 0)
		)
		(min_thickness 0.25)
		(keepout
			(tracks not_allowed)
			(vias allowed)
			(pads allowed)
			(copperpour not_allowed)
			(footprints allowed)
		)
		(placement
			(enabled no)
			(sheetname "")
		)
		(fill yes
			(thermal_gap 0.5)
			(thermal_bridge_width 0.5)
			(island_removal_mode 0)
		)
		(polygon
			(pts
				(arc
					(start 420.242238 -274.684998)
					(mid 419.581838 -274.684998)
					(end 420.242238 -274.684998)
				)
			)
		)
	)
	(zone
		(layers "In1.Cu" "In2.Cu")
		(hatch none 0.5)
		(connect_pads
			(clearance 0)
		)
		(min_thickness 0.25)
		(keepout
			(tracks not_allowed)
			(vias allowed)
			(pads allowed)
			(copperpour not_allowed)
			(footprints allowed)
		)
		(placement
			(enabled no)
			(sheetname "")
		)
		(fill yes
			(thermal_gap 0.5)
			(thermal_bridge_width 0.5)
			(island_removal_mode 0)
		)
		(polygon
			(pts
				(arc
					(start 412.167578 -16.443198)
					(mid 412.189896 -16.49708)
					(end 412.243778 -16.519398)
				)
				(arc
					(start 412.439358 -16.519398)
					(mid 412.461234 -16.516266)
					(end 412.481268 -16.506952)
				)
				(arc
					(start 412.774892 -16.31442)
					(mid 412.816548 -16.302018)
					(end 412.858204 -16.31442)
				)
				(arc
					(start 413.153098 -16.506952)
					(mid 413.173022 -16.516188)
					(end 413.194754 -16.519398)
				)
				(arc
					(start 413.389318 -16.519398)
					(mid 413.4432 -16.49708)
					(end 413.465518 -16.443198)
				)
				(arc
					(start 413.465518 -15.757398)
					(mid 413.4432 -15.703516)
					(end 413.389318 -15.681198)
				)
				(arc
					(start 413.194754 -15.681198)
					(mid 413.17301 -15.684366)
					(end 413.153098 -15.693644)
				)
				(arc
					(start 412.856934 -15.88643)
					(mid 412.81525 -15.898652)
					(end 412.773622 -15.886176)
				)
				(arc
					(start 412.479998 -15.693644)
					(mid 412.460074 -15.684408)
					(end 412.438342 -15.681198)
				)
				(arc
					(start 412.243778 -15.681198)
					(mid 412.189896 -15.703516)
					(end 412.167578 -15.757398)
				)
			)
		)
	)
	(zone
		(layers "In1.Cu" "In2.Cu")
		(hatch none 0.5)
		(connect_pads
			(clearance 0)
		)
		(min_thickness 0.25)
		(keepout
			(tracks not_allowed)
			(vias allowed)
			(pads allowed)
			(copperpour not_allowed)
			(footprints allowed)
		)
		(placement
			(enabled no)
			(sheetname "")
		)
		(fill yes
			(thermal_gap 0.5)
			(thermal_bridge_width 0.5)
			(island_removal_mode 0)
		)
		(polygon
			(pts
				(arc
					(start 17.938242 -282.335224)
					(mid 17.277842 -282.335224)
					(end 17.938242 -282.335224)
				)
			)
		)
	)
	(zone
		(layers "In1.Cu" "In2.Cu")
		(hatch none 0.5)
		(connect_pads
			(clearance 0)
		)
		(min_thickness 0.25)
		(keepout
			(tracks not_allowed)
			(vias allowed)
			(pads allowed)
			(copperpour not_allowed)
			(footprints allowed)
		)
		(placement
			(enabled no)
			(sheetname "")
		)
		(fill yes
			(thermal_gap 0.5)
			(thermal_bridge_width 0.5)
			(island_removal_mode 0)
		)
		(polygon
			(pts
				(arc
					(start 179.846224 -276.385274)
					(mid 179.185824 -276.385274)
					(end 179.846224 -276.385274)
				)
			)
		)
	)
	(zone
		(layers "In1.Cu" "In2.Cu")
		(hatch none 0.5)
		(connect_pads
			(clearance 0)
		)
		(min_thickness 0.25)
		(keepout
			(tracks not_allowed)
			(vias allowed)
			(pads allowed)
			(copperpour not_allowed)
			(footprints allowed)
		)
		(placement
			(enabled no)
			(sheetname "")
		)
		(fill yes
			(thermal_gap 0.5)
			(thermal_bridge_width 0.5)
			(island_removal_mode 0)
		)
		(polygon
			(pts
				(arc
					(start 296.054272 -227.935028)
					(mid 295.393872 -227.935028)
					(end 296.054272 -227.935028)
				)
			)
		)
	)
	(zone
		(layers "In1.Cu" "In2.Cu")
		(hatch none 0.5)
		(connect_pads
			(clearance 0)
		)
		(min_thickness 0.25)
		(keepout
			(tracks not_allowed)
			(vias allowed)
			(pads allowed)
			(copperpour not_allowed)
			(footprints allowed)
		)
		(placement
			(enabled no)
			(sheetname "")
		)
		(fill yes
			(thermal_gap 0.5)
			(thermal_bridge_width 0.5)
			(island_removal_mode 0)
		)
		(polygon
			(pts
				(arc
					(start 20.041616 -11.91768)
					(mid 20.019298 -11.971562)
					(end 19.965416 -11.99388)
				)
				(arc
					(start 18.928842 -11.99388)
					(mid 18.87496 -11.971562)
					(end 18.852642 -11.91768)
				)
				(arc
					(start 18.852642 -10.51814)
					(mid 18.87496 -10.464258)
					(end 18.928842 -10.44194)
				)
				(arc
					(start 19.965416 -10.44194)
					(mid 20.019298 -10.464258)
					(end 20.041616 -10.51814)
				)
			)
		)
	)
	(zone
		(layers "In1.Cu" "In2.Cu")
		(hatch none 0.5)
		(connect_pads
			(clearance 0)
		)
		(min_thickness 0.25)
		(keepout
			(tracks not_allowed)
			(vias allowed)
			(pads allowed)
			(copperpour not_allowed)
			(footprints allowed)
		)
		(placement
			(enabled no)
			(sheetname "")
		)
		(fill yes
			(thermal_gap 0.5)
			(thermal_bridge_width 0.5)
			(island_removal_mode 0)
		)
		(polygon
			(pts
				(arc
					(start 180.121814 -53.859684)
					(mid 180.112578 -53.879608)
					(end 180.109368 -53.90134)
				)
				(arc
					(start 180.109368 -54.095904)
					(mid 180.131686 -54.149786)
					(end 180.185568 -54.172104)
				)
				(arc
					(start 180.871368 -54.172104)
					(mid 180.92525 -54.149786)
					(end 180.947568 -54.095904)
				)
				(arc
					(start 180.947568 -53.90134)
					(mid 180.9444 -53.879596)
					(end 180.935122 -53.859684)
				)
				(arc
					(start 180.742336 -53.56352)
					(mid 180.730114 -53.521836)
					(end 180.74259 -53.480208)
				)
				(arc
					(start 180.935122 -53.186584)
					(mid 180.944358 -53.16666)
					(end 180.947568 -53.144928)
				)
				(arc
					(start 180.947568 -52.950364)
					(mid 180.92525 -52.896482)
					(end 180.871368 -52.874164)
				)
				(arc
					(start 180.185568 -52.874164)
					(mid 180.131686 -52.896482)
					(end 180.109368 -52.950364)
				)
				(arc
					(start 180.109368 -53.146198)
					(mid 180.112536 -53.167942)
					(end 180.121814 -53.187854)
				)
				(arc
					(start 180.314346 -53.481478)
					(mid 180.326748 -53.523134)
					(end 180.314346 -53.56479)
				)
			)
		)
	)
	(zone
		(layers "In1.Cu" "In2.Cu")
		(hatch none 0.5)
		(connect_pads
			(clearance 0)
		)
		(min_thickness 0.25)
		(keepout
			(tracks not_allowed)
			(vias allowed)
			(pads allowed)
			(copperpour not_allowed)
			(footprints allowed)
		)
		(placement
			(enabled no)
			(sheetname "")
		)
		(fill yes
			(thermal_gap 0.5)
			(thermal_bridge_width 0.5)
			(island_removal_mode 0)
		)
		(polygon
			(pts
				(arc
					(start 277.522432 -231.335072)
					(mid 276.862032 -231.335072)
					(end 277.522432 -231.335072)
				)
			)
		)
	)
	(zone
		(layers "In1.Cu" "In2.Cu")
		(hatch none 0.5)
		(connect_pads
			(clearance 0)
		)
		(min_thickness 0.25)
		(keepout
			(tracks not_allowed)
			(vias allowed)
			(pads allowed)
			(copperpour not_allowed)
			(footprints allowed)
		)
		(placement
			(enabled no)
			(sheetname "")
		)
		(fill yes
			(thermal_gap 0.5)
			(thermal_bridge_width 0.5)
			(island_removal_mode 0)
		)
		(polygon
			(pts
				(arc
					(start 300.15434 -210.935062)
					(mid 299.49394 -210.935062)
					(end 300.15434 -210.935062)
				)
			)
		)
	)
	(zone
		(layers "In1.Cu" "In2.Cu")
		(hatch none 0.5)
		(connect_pads
			(clearance 0)
		)
		(min_thickness 0.25)
		(keepout
			(tracks not_allowed)
			(vias allowed)
			(pads allowed)
			(copperpour not_allowed)
			(footprints allowed)
		)
		(placement
			(enabled no)
			(sheetname "")
		)
		(fill yes
			(thermal_gap 0.5)
			(thermal_bridge_width 0.5)
			(island_removal_mode 0)
		)
		(polygon
			(pts
				(arc
					(start 427.786292 -222.834962)
					(mid 427.125892 -222.834962)
					(end 427.786292 -222.834962)
				)
			)
		)
	)
	(zone
		(layers "In1.Cu" "In2.Cu")
		(hatch none 0.5)
		(connect_pads
			(clearance 0)
		)
		(min_thickness 0.25)
		(keepout
			(tracks not_allowed)
			(vias allowed)
			(pads allowed)
			(copperpour not_allowed)
			(footprints allowed)
		)
		(placement
			(enabled no)
			(sheetname "")
		)
		(fill yes
			(thermal_gap 0.5)
			(thermal_bridge_width 0.5)
			(island_removal_mode 0)
		)
		(polygon
			(pts
				(arc
					(start 58.36158 -11.91768)
					(mid 58.339262 -11.971562)
					(end 58.28538 -11.99388)
				)
				(arc
					(start 57.248806 -11.99388)
					(mid 57.194924 -11.971562)
					(end 57.172606 -11.91768)
				)
				(arc
					(start 57.172606 -10.51814)
					(mid 57.194924 -10.464258)
					(end 57.248806 -10.44194)
				)
				(arc
					(start 58.28538 -10.44194)
					(mid 58.339262 -10.464258)
					(end 58.36158 -10.51814)
				)
			)
		)
	)
	(zone
		(layers "In1.Cu" "In2.Cu")
		(hatch none 0.5)
		(connect_pads
			(clearance 0)
		)
		(min_thickness 0.25)
		(keepout
			(tracks not_allowed)
			(vias allowed)
			(pads allowed)
			(copperpour not_allowed)
			(footprints allowed)
		)
		(placement
			(enabled no)
			(sheetname "")
		)
		(fill yes
			(thermal_gap 0.5)
			(thermal_bridge_width 0.5)
			(island_removal_mode 0)
		)
		(polygon
			(pts
				(arc
					(start 431.88636 -223.6851)
					(mid 431.22596 -223.6851)
					(end 431.88636 -223.6851)
				)
			)
		)
	)
	(zone
		(layers "In1.Cu" "In2.Cu")
		(hatch none 0.5)
		(connect_pads
			(clearance 0)
		)
		(min_thickness 0.25)
		(keepout
			(tracks not_allowed)
			(vias allowed)
			(pads allowed)
			(copperpour not_allowed)
			(footprints allowed)
		)
		(placement
			(enabled no)
			(sheetname "")
		)
		(fill yes
			(thermal_gap 0.5)
			(thermal_bridge_width 0.5)
			(island_removal_mode 0)
		)
		(polygon
			(pts
				(arc
					(start 81.416652 -375.906284)
					(mid 81.436576 -375.91552)
					(end 81.458308 -375.91873)
				)
				(arc
					(start 81.652872 -375.91873)
					(mid 81.706754 -375.896412)
					(end 81.729072 -375.84253)
				)
				(arc
					(start 81.729072 -375.15673)
					(mid 81.706754 -375.102848)
					(end 81.652872 -375.08053)
				)
				(arc
					(start 81.458308 -375.08053)
					(mid 81.436564 -375.083698)
					(end 81.416652 -375.092976)
				)
				(arc
					(start 81.120488 -375.285762)
					(mid 81.078804 -375.297984)
					(end 81.037176 -375.285508)
				)
				(arc
					(start 80.743552 -375.092976)
					(mid 80.723628 -375.08374)
					(end 80.701896 -375.08053)
				)
				(arc
					(start 80.507332 -375.08053)
					(mid 80.45345 -375.102848)
					(end 80.431132 -375.15673)
				)
				(arc
					(start 80.431132 -375.84253)
					(mid 80.45345 -375.896412)
					(end 80.507332 -375.91873)
				)
				(arc
					(start 80.703166 -375.91873)
					(mid 80.72491 -375.915562)
					(end 80.744822 -375.906284)
				)
				(arc
					(start 81.038446 -375.713752)
					(mid 81.080102 -375.70135)
					(end 81.121758 -375.713752)
				)
			)
		)
	)
	(zone
		(layers "In1.Cu" "In2.Cu")
		(hatch none 0.5)
		(connect_pads
			(clearance 0)
		)
		(min_thickness 0.25)
		(keepout
			(tracks not_allowed)
			(vias allowed)
			(pads allowed)
			(copperpour not_allowed)
			(footprints allowed)
		)
		(placement
			(enabled no)
			(sheetname "")
		)
		(fill yes
			(thermal_gap 0.5)
			(thermal_bridge_width 0.5)
			(island_removal_mode 0)
		)
		(polygon
			(pts
				(arc
					(start 17.938242 -285.735268)
					(mid 17.277842 -285.735268)
					(end 17.938242 -285.735268)
				)
			)
		)
	)
	(zone
		(layers "In1.Cu" "In2.Cu")
		(hatch none 0.5)
		(connect_pads
			(clearance 0)
		)
		(min_thickness 0.25)
		(keepout
			(tracks not_allowed)
			(vias allowed)
			(pads allowed)
			(copperpour not_allowed)
			(footprints allowed)
		)
		(placement
			(enabled no)
			(sheetname "")
		)
		(fill yes
			(thermal_gap 0.5)
			(thermal_bridge_width 0.5)
			(island_removal_mode 0)
		)
		(polygon
			(pts
				(arc
					(start 37.126164 -315.485272)
					(mid 36.465764 -315.485272)
					(end 37.126164 -315.485272)
				)
			)
		)
	)
	(zone
		(layers "In1.Cu" "In2.Cu")
		(hatch none 0.5)
		(connect_pads
			(clearance 0)
		)
		(min_thickness 0.25)
		(keepout
			(tracks not_allowed)
			(vias allowed)
			(pads allowed)
			(copperpour not_allowed)
			(footprints allowed)
		)
		(placement
			(enabled no)
			(sheetname "")
		)
		(fill yes
			(thermal_gap 0.5)
			(thermal_bridge_width 0.5)
			(island_removal_mode 0)
		)
		(polygon
			(pts
				(arc
					(start 22.03831 -219.435426)
					(mid 21.37791 -219.435426)
					(end 22.03831 -219.435426)
				)
			)
		)
	)
	(zone
		(layers "In1.Cu" "In2.Cu")
		(hatch none 0.5)
		(connect_pads
			(clearance 0)
		)
		(min_thickness 0.25)
		(keepout
			(tracks not_allowed)
			(vias allowed)
			(pads allowed)
			(copperpour not_allowed)
			(footprints allowed)
		)
		(placement
			(enabled no)
			(sheetname "")
		)
		(fill yes
			(thermal_gap 0.5)
			(thermal_bridge_width 0.5)
			(island_removal_mode 0)
		)
		(polygon
			(pts
				(arc
					(start 285.066232 -292.535102)
					(mid 284.405832 -292.535102)
					(end 285.066232 -292.535102)
				)
			)
		)
	)
	(zone
		(layers "In1.Cu" "In2.Cu")
		(hatch none 0.5)
		(connect_pads
			(clearance 0)
		)
		(min_thickness 0.25)
		(keepout
			(tracks not_allowed)
			(vias allowed)
			(pads allowed)
			(copperpour not_allowed)
			(footprints allowed)
		)
		(placement
			(enabled no)
			(sheetname "")
		)
		(fill yes
			(thermal_gap 0.5)
			(thermal_bridge_width 0.5)
			(island_removal_mode 0)
		)
		(polygon
			(pts
				(arc
					(start 292.610286 -234.735116)
					(mid 291.949886 -234.735116)
					(end 292.610286 -234.735116)
				)
			)
		)
	)
	(zone
		(layers "In1.Cu" "In2.Cu")
		(hatch none 0.5)
		(connect_pads
			(clearance 0)
		)
		(min_thickness 0.25)
		(keepout
			(tracks not_allowed)
			(vias allowed)
			(pads allowed)
			(copperpour not_allowed)
			(footprints allowed)
		)
		(placement
			(enabled no)
			(sheetname "")
		)
		(fill yes
			(thermal_gap 0.5)
			(thermal_bridge_width 0.5)
			(island_removal_mode 0)
		)
		(polygon
			(pts
				(arc
					(start 300.15434 -254.284988)
					(mid 299.49394 -254.284988)
					(end 300.15434 -254.284988)
				)
			)
		)
	)
	(zone
		(layers "In1.Cu" "In2.Cu")
		(hatch none 0.5)
		(connect_pads
			(clearance 0)
		)
		(min_thickness 0.25)
		(keepout
			(tracks not_allowed)
			(vias allowed)
			(pads allowed)
			(copperpour not_allowed)
			(footprints allowed)
		)
		(placement
			(enabled no)
			(sheetname "")
		)
		(fill yes
			(thermal_gap 0.5)
			(thermal_bridge_width 0.5)
			(island_removal_mode 0)
		)
		(polygon
			(pts
				(arc
					(start 25.482296 -272.98523)
					(mid 24.821896 -272.98523)
					(end 25.482296 -272.98523)
				)
			)
		)
	)
	(zone
		(layers "In1.Cu" "In2.Cu")
		(hatch none 0.5)
		(connect_pads
			(clearance 0)
		)
		(min_thickness 0.25)
		(keepout
			(tracks not_allowed)
			(vias allowed)
			(pads allowed)
			(copperpour not_allowed)
			(footprints allowed)
		)
		(placement
			(enabled no)
			(sheetname "")
		)
		(fill yes
			(thermal_gap 0.5)
			(thermal_bridge_width 0.5)
			(island_removal_mode 0)
		)
		(polygon
			(pts
				(arc
					(start 288.510218 -207.535018)
					(mid 287.849818 -207.535018)
					(end 288.510218 -207.535018)
				)
			)
		)
	)
	(zone
		(layers "In1.Cu" "In2.Cu")
		(hatch none 0.5)
		(connect_pads
			(clearance 0)
		)
		(min_thickness 0.25)
		(keepout
			(tracks not_allowed)
			(vias allowed)
			(pads allowed)
			(copperpour not_allowed)
			(footprints allowed)
		)
		(placement
			(enabled no)
			(sheetname "")
		)
		(fill yes
			(thermal_gap 0.5)
			(thermal_bridge_width 0.5)
			(island_removal_mode 0)
		)
		(polygon
			(pts
				(arc
					(start 191.490346 -303.585372)
					(mid 190.829946 -303.585372)
					(end 191.490346 -303.585372)
				)
			)
		)
	)
	(zone
		(layers "In1.Cu" "In2.Cu")
		(hatch none 0.5)
		(connect_pads
			(clearance 0)
		)
		(min_thickness 0.25)
		(keepout
			(tracks not_allowed)
			(vias allowed)
			(pads allowed)
			(copperpour not_allowed)
			(footprints allowed)
		)
		(placement
			(enabled no)
			(sheetname "")
		)
		(fill yes
			(thermal_gap 0.5)
			(thermal_bridge_width 0.5)
			(island_removal_mode 0)
		)
		(polygon
			(pts
				(arc
					(start 37.126164 -197.335394)
					(mid 36.465764 -197.335394)
					(end 37.126164 -197.335394)
				)
			)
		)
	)
	(zone
		(layers "In1.Cu" "In2.Cu")
		(hatch none 0.5)
		(connect_pads
			(clearance 0)
		)
		(min_thickness 0.25)
		(keepout
			(tracks not_allowed)
			(vias allowed)
			(pads allowed)
			(copperpour not_allowed)
			(footprints allowed)
		)
		(placement
			(enabled no)
			(sheetname "")
		)
		(fill yes
			(thermal_gap 0.5)
			(thermal_bridge_width 0.5)
			(island_removal_mode 0)
		)
		(polygon
			(pts
				(arc
					(start 431.88636 -228.785166)
					(mid 431.22596 -228.785166)
					(end 431.88636 -228.785166)
				)
			)
		)
	)
	(zone
		(layers "In1.Cu" "In2.Cu")
		(hatch none 0.5)
		(connect_pads
			(clearance 0)
		)
		(min_thickness 0.25)
		(keepout
			(tracks not_allowed)
			(vias allowed)
			(pads allowed)
			(copperpour not_allowed)
			(footprints allowed)
		)
		(placement
			(enabled no)
			(sheetname "")
		)
		(fill yes
			(thermal_gap 0.5)
			(thermal_bridge_width 0.5)
			(island_removal_mode 0)
		)
		(polygon
			(pts
				(arc
					(start 392.410442 -379.360684)
					(mid 392.430366 -379.36992)
					(end 392.452098 -379.37313)
				)
				(arc
					(start 392.646662 -379.37313)
					(mid 392.700544 -379.350812)
					(end 392.722862 -379.29693)
				)
				(arc
					(start 392.722862 -378.61113)
					(mid 392.700544 -378.557248)
					(end 392.646662 -378.53493)
				)
				(arc
					(start 392.452098 -378.53493)
					(mid 392.430354 -378.538098)
					(end 392.410442 -378.547376)
				)
				(arc
					(start 392.114278 -378.740162)
					(mid 392.072594 -378.752384)
					(end 392.030966 -378.739908)
				)
				(arc
					(start 391.737342 -378.547376)
					(mid 391.717418 -378.53814)
					(end 391.695686 -378.53493)
				)
				(arc
					(start 391.501122 -378.53493)
					(mid 391.44724 -378.557248)
					(end 391.424922 -378.61113)
				)
				(arc
					(start 391.424922 -379.29693)
					(mid 391.44724 -379.350812)
					(end 391.501122 -379.37313)
				)
				(arc
					(start 391.696956 -379.37313)
					(mid 391.7187 -379.369962)
					(end 391.738612 -379.360684)
				)
				(arc
					(start 392.032236 -379.168152)
					(mid 392.073892 -379.15575)
					(end 392.115548 -379.168152)
				)
			)
		)
	)
	(zone
		(layers "In1.Cu" "In2.Cu")
		(hatch none 0.5)
		(connect_pads
			(clearance 0)
		)
		(min_thickness 0.25)
		(keepout
			(tracks not_allowed)
			(vias allowed)
			(pads allowed)
			(copperpour not_allowed)
			(footprints allowed)
		)
		(placement
			(enabled no)
			(sheetname "")
		)
		(fill yes
			(thermal_gap 0.5)
			(thermal_bridge_width 0.5)
			(island_removal_mode 0)
		)
		(polygon
			(pts
				(arc
					(start 442.8744 -215.18499)
					(mid 442.214 -215.18499)
					(end 442.8744 -215.18499)
				)
			)
		)
	)
	(zone
		(layers "In1.Cu" "In2.Cu")
		(hatch none 0.5)
		(connect_pads
			(clearance 0)
		)
		(min_thickness 0.25)
		(keepout
			(tracks not_allowed)
			(vias allowed)
			(pads allowed)
			(copperpour not_allowed)
			(footprints allowed)
		)
		(placement
			(enabled no)
			(sheetname "")
		)
		(fill yes
			(thermal_gap 0.5)
			(thermal_bridge_width 0.5)
			(island_removal_mode 0)
		)
		(polygon
			(pts
				(arc
					(start 288.510218 -202.434952)
					(mid 287.849818 -202.434952)
					(end 288.510218 -202.434952)
				)
			)
		)
	)
	(zone
		(layers "In1.Cu" "In2.Cu")
		(hatch none 0.5)
		(connect_pads
			(clearance 0)
		)
		(min_thickness 0.25)
		(keepout
			(tracks not_allowed)
			(vias allowed)
			(pads allowed)
			(copperpour not_allowed)
			(footprints allowed)
		)
		(placement
			(enabled no)
			(sheetname "")
		)
		(fill yes
			(thermal_gap 0.5)
			(thermal_bridge_width 0.5)
			(island_removal_mode 0)
		)
		(polygon
			(pts
				(arc
					(start 191.490346 -228.78542)
					(mid 190.829946 -228.78542)
					(end 191.490346 -228.78542)
				)
			)
		)
	)
	(zone
		(layers "In1.Cu" "In2.Cu")
		(hatch none 0.5)
		(connect_pads
			(clearance 0)
		)
		(min_thickness 0.25)
		(keepout
			(tracks not_allowed)
			(vias allowed)
			(pads allowed)
			(copperpour not_allowed)
			(footprints allowed)
		)
		(placement
			(enabled no)
			(sheetname "")
		)
		(fill yes
			(thermal_gap 0.5)
			(thermal_bridge_width 0.5)
			(island_removal_mode 0)
		)
		(polygon
			(pts
				(arc
					(start 288.510218 -261.93496)
					(mid 287.849818 -261.93496)
					(end 288.510218 -261.93496)
				)
			)
		)
	)
	(zone
		(layers "In1.Cu" "In2.Cu")
		(hatch none 0.5)
		(connect_pads
			(clearance 0)
		)
		(min_thickness 0.25)
		(keepout
			(tracks not_allowed)
			(vias allowed)
			(pads allowed)
			(copperpour not_allowed)
			(footprints allowed)
		)
		(placement
			(enabled no)
			(sheetname "")
		)
		(fill yes
			(thermal_gap 0.5)
			(thermal_bridge_width 0.5)
			(island_removal_mode 0)
		)
		(polygon
			(pts
				(arc
					(start 143.411194 -373.442484)
					(mid 143.431118 -373.45172)
					(end 143.45285 -373.45493)
				)
				(arc
					(start 143.647414 -373.45493)
					(mid 143.701296 -373.432612)
					(end 143.723614 -373.37873)
				)
				(arc
					(start 143.723614 -372.69293)
					(mid 143.701296 -372.639048)
					(end 143.647414 -372.61673)
				)
				(arc
					(start 143.45285 -372.61673)
					(mid 143.431106 -372.619898)
					(end 143.411194 -372.629176)
				)
				(arc
					(start 143.11503 -372.821962)
					(mid 143.073346 -372.834184)
					(end 143.031718 -372.821708)
				)
				(arc
					(start 142.738094 -372.629176)
					(mid 142.71817 -372.61994)
					(end 142.696438 -372.61673)
				)
				(arc
					(start 142.501874 -372.61673)
					(mid 142.447992 -372.639048)
					(end 142.425674 -372.69293)
				)
				(arc
					(start 142.425674 -373.37873)
					(mid 142.447992 -373.432612)
					(end 142.501874 -373.45493)
				)
				(arc
					(start 142.697708 -373.45493)
					(mid 142.719452 -373.451762)
					(end 142.739364 -373.442484)
				)
				(arc
					(start 143.032988 -373.249952)
					(mid 143.074644 -373.23755)
					(end 143.1163 -373.249952)
				)
			)
		)
	)
	(zone
		(layers "In1.Cu" "In2.Cu")
		(hatch none 0.5)
		(connect_pads
			(clearance 0)
		)
		(min_thickness 0.25)
		(keepout
			(tracks not_allowed)
			(vias allowed)
			(pads allowed)
			(copperpour not_allowed)
			(footprints allowed)
		)
		(placement
			(enabled no)
			(sheetname "")
		)
		(fill yes
			(thermal_gap 0.5)
			(thermal_bridge_width 0.5)
			(island_removal_mode 0)
		)
		(polygon
			(pts
				(arc
					(start 296.054272 -216.885012)
					(mid 295.393872 -216.885012)
					(end 296.054272 -216.885012)
				)
			)
		)
	)
	(zone
		(layers "In1.Cu" "In2.Cu")
		(hatch none 0.5)
		(connect_pads
			(clearance 0)
		)
		(min_thickness 0.25)
		(keepout
			(tracks not_allowed)
			(vias allowed)
			(pads allowed)
			(copperpour not_allowed)
			(footprints allowed)
		)
		(placement
			(enabled no)
			(sheetname "")
		)
		(fill yes
			(thermal_gap 0.5)
			(thermal_bridge_width 0.5)
			(island_removal_mode 0)
		)
		(polygon
			(pts
				(arc
					(start 450.4182 -284.034992)
					(mid 449.7578 -284.034992)
					(end 450.4182 -284.034992)
				)
			)
		)
	)
	(zone
		(layers "In1.Cu" "In2.Cu")
		(hatch none 0.5)
		(connect_pads
			(clearance 0)
		)
		(min_thickness 0.25)
		(keepout
			(tracks not_allowed)
			(vias allowed)
			(pads allowed)
			(copperpour not_allowed)
			(footprints allowed)
		)
		(placement
			(enabled no)
			(sheetname "")
		)
		(fill yes
			(thermal_gap 0.5)
			(thermal_bridge_width 0.5)
			(island_removal_mode 0)
		)
		(polygon
			(pts
				(arc
					(start 431.88636 -290.83508)
					(mid 431.22596 -290.83508)
					(end 431.88636 -290.83508)
				)
			)
		)
	)
	(zone
		(layers "In1.Cu" "In2.Cu")
		(hatch none 0.5)
		(connect_pads
			(clearance 0)
		)
		(min_thickness 0.25)
		(keepout
			(tracks not_allowed)
			(vias allowed)
			(pads allowed)
			(copperpour not_allowed)
			(footprints allowed)
		)
		(placement
			(enabled no)
			(sheetname "")
		)
		(fill yes
			(thermal_gap 0.5)
			(thermal_bridge_width 0.5)
			(island_removal_mode 0)
		)
		(polygon
			(pts
				(arc
					(start 33.026096 -316.33541)
					(mid 32.365696 -316.33541)
					(end 33.026096 -316.33541)
				)
			)
		)
	)
	(zone
		(layers "In1.Cu" "In2.Cu")
		(hatch none 0.5)
		(connect_pads
			(clearance 0)
		)
		(min_thickness 0.25)
		(keepout
			(tracks not_allowed)
			(vias allowed)
			(pads allowed)
			(copperpour not_allowed)
			(footprints allowed)
		)
		(placement
			(enabled no)
			(sheetname "")
		)
		(fill yes
			(thermal_gap 0.5)
			(thermal_bridge_width 0.5)
			(island_removal_mode 0)
		)
		(polygon
			(pts
				(arc
					(start 450.4182 -289.985196)
					(mid 449.7578 -289.985196)
					(end 450.4182 -289.985196)
				)
			)
		)
	)
	(zone
		(layers "In1.Cu" "In2.Cu")
		(hatch none 0.5)
		(connect_pads
			(clearance 0)
		)
		(min_thickness 0.25)
		(keepout
			(tracks not_allowed)
			(vias allowed)
			(pads allowed)
			(copperpour not_allowed)
			(footprints allowed)
		)
		(placement
			(enabled no)
			(sheetname "")
		)
		(fill yes
			(thermal_gap 0.5)
			(thermal_bridge_width 0.5)
			(island_removal_mode 0)
		)
		(polygon
			(pts
				(arc
					(start 199.0344 -313.78525)
					(mid 198.374 -313.78525)
					(end 199.0344 -313.78525)
				)
			)
		)
	)
	(zone
		(layers "In1.Cu" "In2.Cu")
		(hatch none 0.5)
		(connect_pads
			(clearance 0)
		)
		(min_thickness 0.25)
		(keepout
			(tracks not_allowed)
			(vias allowed)
			(pads allowed)
			(copperpour not_allowed)
			(footprints allowed)
		)
		(placement
			(enabled no)
			(sheetname "")
		)
		(fill yes
			(thermal_gap 0.5)
			(thermal_bridge_width 0.5)
			(island_removal_mode 0)
		)
		(polygon
			(pts
				(arc
					(start 191.490346 -284.885384)
					(mid 190.829946 -284.885384)
					(end 191.490346 -284.885384)
				)
			)
		)
	)
	(zone
		(layers "In1.Cu" "In2.Cu")
		(hatch none 0.5)
		(connect_pads
			(clearance 0)
		)
		(min_thickness 0.25)
		(keepout
			(tracks not_allowed)
			(vias allowed)
			(pads allowed)
			(copperpour not_allowed)
			(footprints allowed)
		)
		(placement
			(enabled no)
			(sheetname "")
		)
		(fill yes
			(thermal_gap 0.5)
			(thermal_bridge_width 0.5)
			(island_removal_mode 0)
		)
		(polygon
			(pts
				(arc
					(start 420.242238 -308.685184)
					(mid 419.581838 -308.685184)
					(end 420.242238 -308.685184)
				)
			)
		)
	)
	(zone
		(layers "In1.Cu" "In2.Cu")
		(hatch none 0.5)
		(connect_pads
			(clearance 0)
		)
		(min_thickness 0.25)
		(keepout
			(tracks not_allowed)
			(vias allowed)
			(pads allowed)
			(copperpour not_allowed)
			(footprints allowed)
		)
		(placement
			(enabled no)
			(sheetname "")
		)
		(fill yes
			(thermal_gap 0.5)
			(thermal_bridge_width 0.5)
			(island_removal_mode 0)
		)
		(polygon
			(pts
				(arc
					(start 296.054272 -277.235158)
					(mid 295.393872 -277.235158)
					(end 296.054272 -277.235158)
				)
			)
		)
	)
	(zone
		(layers "In1.Cu" "In2.Cu")
		(hatch none 0.5)
		(connect_pads
			(clearance 0)
		)
		(min_thickness 0.25)
		(keepout
			(tracks not_allowed)
			(vias allowed)
			(pads allowed)
			(copperpour not_allowed)
			(footprints allowed)
		)
		(placement
			(enabled no)
			(sheetname "")
		)
		(fill yes
			(thermal_gap 0.5)
			(thermal_bridge_width 0.5)
			(island_removal_mode 0)
		)
		(polygon
			(pts
				(arc
					(start 17.938242 -299.335444)
					(mid 17.277842 -299.335444)
					(end 17.938242 -299.335444)
				)
			)
		)
	)
	(zone
		(layers "In1.Cu" "In2.Cu")
		(hatch none 0.5)
		(connect_pads
			(clearance 0)
		)
		(min_thickness 0.25)
		(keepout
			(tracks not_allowed)
			(vias allowed)
			(pads allowed)
			(copperpour not_allowed)
			(footprints allowed)
		)
		(placement
			(enabled no)
			(sheetname "")
		)
		(fill yes
			(thermal_gap 0.5)
			(thermal_bridge_width 0.5)
			(island_removal_mode 0)
		)
		(polygon
			(pts
				(arc
					(start 288.510218 -199.885046)
					(mid 287.849818 -199.885046)
					(end 288.510218 -199.885046)
				)
			)
		)
	)
	(zone
		(layers "In1.Cu" "In2.Cu")
		(hatch none 0.5)
		(connect_pads
			(clearance 0)
		)
		(min_thickness 0.25)
		(keepout
			(tracks not_allowed)
			(vias allowed)
			(pads allowed)
			(copperpour not_allowed)
			(footprints allowed)
		)
		(placement
			(enabled no)
			(sheetname "")
		)
		(fill yes
			(thermal_gap 0.5)
			(thermal_bridge_width 0.5)
			(island_removal_mode 0)
		)
		(polygon
			(pts
				(arc
					(start 48.114204 -314.635388)
					(mid 47.453804 -314.635388)
					(end 48.114204 -314.635388)
				)
			)
		)
	)
	(zone
		(layers "In1.Cu" "In2.Cu")
		(hatch none 0.5)
		(connect_pads
			(clearance 0)
		)
		(min_thickness 0.25)
		(keepout
			(tracks not_allowed)
			(vias allowed)
			(pads allowed)
			(copperpour not_allowed)
			(footprints allowed)
		)
		(placement
			(enabled no)
			(sheetname "")
		)
		(fill yes
			(thermal_gap 0.5)
			(thermal_bridge_width 0.5)
			(island_removal_mode 0)
		)
		(polygon
			(pts
				(arc
					(start 435.330346 -210.935062)
					(mid 434.669946 -210.935062)
					(end 435.330346 -210.935062)
				)
			)
		)
	)
	(zone
		(layers "In1.Cu" "In2.Cu")
		(hatch none 0.5)
		(connect_pads
			(clearance 0)
		)
		(min_thickness 0.25)
		(keepout
			(tracks not_allowed)
			(vias allowed)
			(pads allowed)
			(copperpour not_allowed)
			(footprints allowed)
		)
		(placement
			(enabled no)
			(sheetname "")
		)
		(fill yes
			(thermal_gap 0.5)
			(thermal_bridge_width 0.5)
			(island_removal_mode 0)
		)
		(polygon
			(pts
				(arc
					(start 292.610286 -301.885096)
					(mid 291.949886 -301.885096)
					(end 292.610286 -301.885096)
				)
			)
		)
	)
	(zone
		(layers "In1.Cu" "In2.Cu")
		(hatch none 0.5)
		(connect_pads
			(clearance 0)
		)
		(min_thickness 0.25)
		(keepout
			(tracks not_allowed)
			(vias allowed)
			(pads allowed)
			(copperpour not_allowed)
			(footprints allowed)
		)
		(placement
			(enabled no)
			(sheetname "")
		)
		(fill yes
			(thermal_gap 0.5)
			(thermal_bridge_width 0.5)
			(island_removal_mode 0)
		)
		(polygon
			(pts
				(arc
					(start 446.974468 -287.435036)
					(mid 446.314068 -287.435036)
					(end 446.974468 -287.435036)
				)
			)
		)
	)
	(zone
		(layers "In1.Cu" "In2.Cu")
		(hatch none 0.5)
		(connect_pads
			(clearance 0)
		)
		(min_thickness 0.25)
		(keepout
			(tracks not_allowed)
			(vias allowed)
			(pads allowed)
			(copperpour not_allowed)
			(footprints allowed)
		)
		(placement
			(enabled no)
			(sheetname "")
		)
		(fill yes
			(thermal_gap 0.5)
			(thermal_bridge_width 0.5)
			(island_removal_mode 0)
		)
		(polygon
			(pts
				(arc
					(start 420.242238 -243.234972)
					(mid 419.581838 -243.234972)
					(end 420.242238 -243.234972)
				)
			)
		)
	)
	(zone
		(layers "In1.Cu" "In2.Cu")
		(hatch none 0.5)
		(connect_pads
			(clearance 0)
		)
		(min_thickness 0.25)
		(keepout
			(tracks not_allowed)
			(vias allowed)
			(pads allowed)
			(copperpour not_allowed)
			(footprints allowed)
		)
		(placement
			(enabled no)
			(sheetname "")
		)
		(fill yes
			(thermal_gap 0.5)
			(thermal_bridge_width 0.5)
			(island_removal_mode 0)
		)
		(polygon
			(pts
				(arc
					(start 292.610286 -225.385122)
					(mid 291.949886 -225.385122)
					(end 292.610286 -225.385122)
				)
			)
		)
	)
	(zone
		(layers "In1.Cu" "In2.Cu")
		(hatch none 0.5)
		(connect_pads
			(clearance 0)
		)
		(min_thickness 0.25)
		(keepout
			(tracks not_allowed)
			(vias allowed)
			(pads allowed)
			(copperpour not_allowed)
			(footprints allowed)
		)
		(placement
			(enabled no)
			(sheetname "")
		)
		(fill yes
			(thermal_gap 0.5)
			(thermal_bridge_width 0.5)
			(island_removal_mode 0)
		)
		(polygon
			(pts
				(arc
					(start 176.402238 -217.735404)
					(mid 175.741838 -217.735404)
					(end 176.402238 -217.735404)
				)
			)
		)
	)
	(zone
		(layers "In1.Cu" "In2.Cu")
		(hatch none 0.5)
		(connect_pads
			(clearance 0)
		)
		(min_thickness 0.25)
		(keepout
			(tracks not_allowed)
			(vias allowed)
			(pads allowed)
			(copperpour not_allowed)
			(footprints allowed)
		)
		(placement
			(enabled no)
			(sheetname "")
		)
		(fill yes
			(thermal_gap 0.5)
			(thermal_bridge_width 0.5)
			(island_removal_mode 0)
		)
		(polygon
			(pts
				(arc
					(start 420.242238 -216.885012)
					(mid 419.581838 -216.885012)
					(end 420.242238 -216.885012)
				)
			)
		)
	)
	(zone
		(layers "In1.Cu" "In2.Cu")
		(hatch none 0.5)
		(connect_pads
			(clearance 0)
		)
		(min_thickness 0.25)
		(keepout
			(tracks not_allowed)
			(vias allowed)
			(pads allowed)
			(copperpour not_allowed)
			(footprints allowed)
		)
		(placement
			(enabled no)
			(sheetname "")
		)
		(fill yes
			(thermal_gap 0.5)
			(thermal_bridge_width 0.5)
			(island_removal_mode 0)
		)
		(polygon
			(pts
				(arc
					(start 454.518268 -267.885164)
					(mid 453.857868 -267.885164)
					(end 454.518268 -267.885164)
				)
			)
		)
	)
	(zone
		(layers "In1.Cu" "In2.Cu")
		(hatch none 0.5)
		(connect_pads
			(clearance 0)
		)
		(min_thickness 0.25)
		(keepout
			(tracks not_allowed)
			(vias allowed)
			(pads allowed)
			(copperpour not_allowed)
			(footprints allowed)
		)
		(placement
			(enabled no)
			(sheetname "")
		)
		(fill yes
			(thermal_gap 0.5)
			(thermal_bridge_width 0.5)
			(island_removal_mode 0)
		)
		(polygon
			(pts
				(arc
					(start 52.214272 -252.58522)
					(mid 51.553872 -252.58522)
					(end 52.214272 -252.58522)
				)
			)
		)
	)
	(zone
		(layers "In1.Cu" "In2.Cu")
		(hatch none 0.5)
		(connect_pads
			(clearance 0)
		)
		(min_thickness 0.25)
		(keepout
			(tracks not_allowed)
			(vias allowed)
			(pads allowed)
			(copperpour not_allowed)
			(footprints allowed)
		)
		(placement
			(enabled no)
			(sheetname "")
		)
		(fill yes
			(thermal_gap 0.5)
			(thermal_bridge_width 0.5)
			(island_removal_mode 0)
		)
		(polygon
			(pts
				(arc
					(start 427.786292 -284.034992)
					(mid 427.125892 -284.034992)
					(end 427.786292 -284.034992)
				)
			)
		)
	)
	(zone
		(layers "In1.Cu" "In2.Cu")
		(hatch none 0.5)
		(connect_pads
			(clearance 0)
		)
		(min_thickness 0.25)
		(keepout
			(tracks not_allowed)
			(vias allowed)
			(pads allowed)
			(copperpour not_allowed)
			(footprints allowed)
		)
		(placement
			(enabled no)
			(sheetname "")
		)
		(fill yes
			(thermal_gap 0.5)
			(thermal_bridge_width 0.5)
			(island_removal_mode 0)
		)
		(polygon
			(pts
				(arc
					(start 269.978378 -208.385156)
					(mid 269.317978 -208.385156)
					(end 269.978378 -208.385156)
				)
			)
		)
	)
	(zone
		(layers "In1.Cu" "In2.Cu")
		(hatch none 0.5)
		(connect_pads
			(clearance 0)
		)
		(min_thickness 0.25)
		(keepout
			(tracks not_allowed)
			(vias allowed)
			(pads allowed)
			(copperpour not_allowed)
			(footprints allowed)
		)
		(placement
			(enabled no)
			(sheetname "")
		)
		(fill yes
			(thermal_gap 0.5)
			(thermal_bridge_width 0.5)
			(island_removal_mode 0)
		)
		(polygon
			(pts
				(arc
					(start 435.330346 -235.585)
					(mid 434.669946 -235.585)
					(end 435.330346 -235.585)
				)
			)
		)
	)
	(zone
		(layers "In1.Cu" "In2.Cu")
		(hatch none 0.5)
		(connect_pads
			(clearance 0)
		)
		(min_thickness 0.25)
		(keepout
			(tracks not_allowed)
			(vias allowed)
			(pads allowed)
			(copperpour not_allowed)
			(footprints allowed)
		)
		(placement
			(enabled no)
			(sheetname "")
		)
		(fill yes
			(thermal_gap 0.5)
			(thermal_bridge_width 0.5)
			(island_removal_mode 0)
		)
		(polygon
			(pts
				(arc
					(start 48.114204 -226.23526)
					(mid 47.453804 -226.23526)
					(end 48.114204 -226.23526)
				)
			)
		)
	)
	(zone
		(layers "In1.Cu" "In2.Cu")
		(hatch none 0.5)
		(connect_pads
			(clearance 0)
		)
		(min_thickness 0.25)
		(keepout
			(tracks not_allowed)
			(vias allowed)
			(pads allowed)
			(copperpour not_allowed)
			(footprints allowed)
		)
		(placement
			(enabled no)
			(sheetname "")
		)
		(fill yes
			(thermal_gap 0.5)
			(thermal_bridge_width 0.5)
			(island_removal_mode 0)
		)
		(polygon
			(pts
				(arc
					(start 424.342306 -283.185108)
					(mid 423.681906 -283.185108)
					(end 424.342306 -283.185108)
				)
			)
		)
	)
	(zone
		(layers "In1.Cu" "In2.Cu")
		(hatch none 0.5)
		(connect_pads
			(clearance 0)
		)
		(min_thickness 0.25)
		(keepout
			(tracks not_allowed)
			(vias allowed)
			(pads allowed)
			(copperpour not_allowed)
			(footprints allowed)
		)
		(placement
			(enabled no)
			(sheetname "")
		)
		(fill yes
			(thermal_gap 0.5)
			(thermal_bridge_width 0.5)
			(island_removal_mode 0)
		)
		(polygon
			(pts
				(arc
					(start 435.330346 -293.384986)
					(mid 434.669946 -293.384986)
					(end 435.330346 -293.384986)
				)
			)
		)
	)
	(zone
		(layers "In1.Cu" "In2.Cu")
		(hatch none 0.5)
		(connect_pads
			(clearance 0)
		)
		(min_thickness 0.25)
		(keepout
			(tracks not_allowed)
			(vias allowed)
			(pads allowed)
			(copperpour not_allowed)
			(footprints allowed)
		)
		(placement
			(enabled no)
			(sheetname "")
		)
		(fill yes
			(thermal_gap 0.5)
			(thermal_bridge_width 0.5)
			(island_removal_mode 0)
		)
		(polygon
			(pts
				(arc
					(start 37.126164 -236.435392)
					(mid 36.465764 -236.435392)
					(end 37.126164 -236.435392)
				)
			)
		)
	)
	(zone
		(layers "In1.Cu" "In2.Cu")
		(hatch none 0.5)
		(connect_pads
			(clearance 0)
		)
		(min_thickness 0.25)
		(keepout
			(tracks not_allowed)
			(vias allowed)
			(pads allowed)
			(copperpour not_allowed)
			(footprints allowed)
		)
		(placement
			(enabled no)
			(sheetname "")
		)
		(fill yes
			(thermal_gap 0.5)
			(thermal_bridge_width 0.5)
			(island_removal_mode 0)
		)
		(polygon
			(pts
				(arc
					(start 300.15434 -249.185176)
					(mid 299.49394 -249.185176)
					(end 300.15434 -249.185176)
				)
			)
		)
	)
	(zone
		(layers "In1.Cu" "In2.Cu")
		(hatch none 0.5)
		(connect_pads
			(clearance 0)
		)
		(min_thickness 0.25)
		(keepout
			(tracks not_allowed)
			(vias allowed)
			(pads allowed)
			(copperpour not_allowed)
			(footprints allowed)
		)
		(placement
			(enabled no)
			(sheetname "")
		)
		(fill yes
			(thermal_gap 0.5)
			(thermal_bridge_width 0.5)
			(island_removal_mode 0)
		)
		(polygon
			(pts
				(arc
					(start 75.088496 -376.73661)
					(mid 75.07926 -376.756534)
					(end 75.07605 -376.778266)
				)
				(arc
					(start 75.07605 -376.97283)
					(mid 75.098368 -377.026712)
					(end 75.15225 -377.04903)
				)
				(arc
					(start 75.83805 -377.04903)
					(mid 75.891932 -377.026712)
					(end 75.91425 -376.97283)
				)
				(arc
					(start 75.91425 -376.778266)
					(mid 75.911082 -376.756522)
					(end 75.901804 -376.73661)
				)
				(arc
					(start 75.709018 -376.440446)
					(mid 75.696796 -376.398762)
					(end 75.709272 -376.357134)
				)
				(arc
					(start 75.901804 -376.06351)
					(mid 75.91104 -376.043586)
					(end 75.91425 -376.021854)
				)
				(arc
					(start 75.91425 -375.82729)
					(mid 75.891932 -375.773408)
					(end 75.83805 -375.75109)
				)
				(arc
					(start 75.15225 -375.75109)
					(mid 75.098368 -375.773408)
					(end 75.07605 -375.82729)
				)
				(arc
					(start 75.07605 -376.023124)
					(mid 75.079218 -376.044868)
					(end 75.088496 -376.06478)
				)
				(arc
					(start 75.281028 -376.358404)
					(mid 75.29343 -376.40006)
					(end 75.281028 -376.441716)
				)
			)
		)
	)
	(zone
		(layers "In1.Cu" "In2.Cu")
		(hatch none 0.5)
		(connect_pads
			(clearance 0)
		)
		(min_thickness 0.25)
		(keepout
			(tracks not_allowed)
			(vias allowed)
			(pads allowed)
			(copperpour not_allowed)
			(footprints allowed)
		)
		(placement
			(enabled no)
			(sheetname "")
		)
		(fill yes
			(thermal_gap 0.5)
			(thermal_bridge_width 0.5)
			(island_removal_mode 0)
		)
		(polygon
			(pts
				(arc
					(start 273.422364 -205.834996)
					(mid 272.761964 -205.834996)
					(end 273.422364 -205.834996)
				)
			)
		)
	)
	(zone
		(layers "In1.Cu" "In2.Cu")
		(hatch none 0.5)
		(connect_pads
			(clearance 0)
		)
		(min_thickness 0.25)
		(keepout
			(tracks not_allowed)
			(vias allowed)
			(pads allowed)
			(copperpour not_allowed)
			(footprints allowed)
		)
		(placement
			(enabled no)
			(sheetname "")
		)
		(fill yes
			(thermal_gap 0.5)
			(thermal_bridge_width 0.5)
			(island_removal_mode 0)
		)
		(polygon
			(pts
				(arc
					(start 273.422364 -295.085008)
					(mid 272.761964 -295.085008)
					(end 273.422364 -295.085008)
				)
			)
		)
	)
	(zone
		(layers "In1.Cu" "In2.Cu")
		(hatch none 0.5)
		(connect_pads
			(clearance 0)
		)
		(min_thickness 0.25)
		(keepout
			(tracks not_allowed)
			(vias allowed)
			(pads allowed)
			(copperpour not_allowed)
			(footprints allowed)
		)
		(placement
			(enabled no)
			(sheetname "")
		)
		(fill yes
			(thermal_gap 0.5)
			(thermal_bridge_width 0.5)
			(island_removal_mode 0)
		)
		(polygon
			(pts
				(arc
					(start 40.57015 -277.235412)
					(mid 39.90975 -277.235412)
					(end 40.57015 -277.235412)
				)
			)
		)
	)
	(zone
		(layers "In1.Cu" "In2.Cu")
		(hatch none 0.5)
		(connect_pads
			(clearance 0)
		)
		(min_thickness 0.25)
		(keepout
			(tracks not_allowed)
			(vias allowed)
			(pads allowed)
			(copperpour not_allowed)
			(footprints allowed)
		)
		(placement
			(enabled no)
			(sheetname "")
		)
		(fill yes
			(thermal_gap 0.5)
			(thermal_bridge_width 0.5)
			(island_removal_mode 0)
		)
		(polygon
			(pts
				(arc
					(start 176.402238 -278.085296)
					(mid 175.741838 -278.085296)
					(end 176.402238 -278.085296)
				)
			)
		)
	)
	(zone
		(layers "In1.Cu" "In2.Cu")
		(hatch none 0.5)
		(connect_pads
			(clearance 0)
		)
		(min_thickness 0.25)
		(keepout
			(tracks not_allowed)
			(vias allowed)
			(pads allowed)
			(copperpour not_allowed)
			(footprints allowed)
		)
		(placement
			(enabled no)
			(sheetname "")
		)
		(fill yes
			(thermal_gap 0.5)
			(thermal_bridge_width 0.5)
			(island_removal_mode 0)
		)
		(polygon
			(pts
				(arc
					(start 414.451546 -11.91768)
					(mid 414.429228 -11.971562)
					(end 414.375346 -11.99388)
				)
				(arc
					(start 413.338772 -11.99388)
					(mid 413.28489 -11.971562)
					(end 413.262572 -11.91768)
				)
				(arc
					(start 413.262572 -10.51814)
					(mid 413.28489 -10.464258)
					(end 413.338772 -10.44194)
				)
				(arc
					(start 414.375346 -10.44194)
					(mid 414.429228 -10.464258)
					(end 414.451546 -10.51814)
				)
			)
		)
	)
	(zone
		(layers "In1.Cu" "In2.Cu")
		(hatch none 0.5)
		(connect_pads
			(clearance 0)
		)
		(min_thickness 0.25)
		(keepout
			(tracks not_allowed)
			(vias allowed)
			(pads allowed)
			(copperpour not_allowed)
			(footprints allowed)
		)
		(placement
			(enabled no)
			(sheetname "")
		)
		(fill yes
			(thermal_gap 0.5)
			(thermal_bridge_width 0.5)
			(island_removal_mode 0)
		)
		(polygon
			(pts
				(arc
					(start 183.946292 -301.88535)
					(mid 183.285892 -301.88535)
					(end 183.946292 -301.88535)
				)
			)
		)
	)
	(zone
		(layers "In1.Cu" "In2.Cu")
		(hatch none 0.5)
		(connect_pads
			(clearance 0)
		)
		(min_thickness 0.25)
		(keepout
			(tracks not_allowed)
			(vias allowed)
			(pads allowed)
			(copperpour not_allowed)
			(footprints allowed)
		)
		(placement
			(enabled no)
			(sheetname "")
		)
		(fill yes
			(thermal_gap 0.5)
			(thermal_bridge_width 0.5)
			(island_removal_mode 0)
		)
		(polygon
			(pts
				(arc
					(start 269.978378 -199.035162)
					(mid 269.317978 -199.035162)
					(end 269.978378 -199.035162)
				)
			)
		)
	)
	(zone
		(layers "In1.Cu" "In2.Cu")
		(hatch none 0.5)
		(connect_pads
			(clearance 0)
		)
		(min_thickness 0.25)
		(keepout
			(tracks not_allowed)
			(vias allowed)
			(pads allowed)
			(copperpour not_allowed)
			(footprints allowed)
		)
		(placement
			(enabled no)
			(sheetname "")
		)
		(fill yes
			(thermal_gap 0.5)
			(thermal_bridge_width 0.5)
			(island_removal_mode 0)
		)
		(polygon
			(pts
				(arc
					(start 446.974468 -221.985078)
					(mid 446.314068 -221.985078)
					(end 446.974468 -221.985078)
				)
			)
		)
	)
	(zone
		(layers "In1.Cu" "In2.Cu")
		(hatch none 0.5)
		(connect_pads
			(clearance 0)
		)
		(min_thickness 0.25)
		(keepout
			(tracks not_allowed)
			(vias allowed)
			(pads allowed)
			(copperpour not_allowed)
			(footprints allowed)
		)
		(placement
			(enabled no)
			(sheetname "")
		)
		(fill yes
			(thermal_gap 0.5)
			(thermal_bridge_width 0.5)
			(island_removal_mode 0)
		)
		(polygon
			(pts
				(arc
					(start 42.560748 -376.73661)
					(mid 42.551512 -376.756534)
					(end 42.548302 -376.778266)
				)
				(arc
					(start 42.548302 -376.97283)
					(mid 42.57062 -377.026712)
					(end 42.624502 -377.04903)
				)
				(arc
					(start 43.310302 -377.04903)
					(mid 43.364184 -377.026712)
					(end 43.386502 -376.97283)
				)
				(arc
					(start 43.386502 -376.778266)
					(mid 43.383334 -376.756522)
					(end 43.374056 -376.73661)
				)
				(arc
					(start 43.18127 -376.440446)
					(mid 43.169048 -376.398762)
					(end 43.181524 -376.357134)
				)
				(arc
					(start 43.374056 -376.06351)
					(mid 43.383292 -376.043586)
					(end 43.386502 -376.021854)
				)
				(arc
					(start 43.386502 -375.82729)
					(mid 43.364184 -375.773408)
					(end 43.310302 -375.75109)
				)
				(arc
					(start 42.624502 -375.75109)
					(mid 42.57062 -375.773408)
					(end 42.548302 -375.82729)
				)
				(arc
					(start 42.548302 -376.023124)
					(mid 42.55147 -376.044868)
					(end 42.560748 -376.06478)
				)
				(arc
					(start 42.75328 -376.358404)
					(mid 42.765682 -376.40006)
					(end 42.75328 -376.441716)
				)
			)
		)
	)
	(zone
		(layers "In1.Cu" "In2.Cu")
		(hatch none 0.5)
		(connect_pads
			(clearance 0)
		)
		(min_thickness 0.25)
		(keepout
			(tracks not_allowed)
			(vias allowed)
			(pads allowed)
			(copperpour not_allowed)
			(footprints allowed)
		)
		(placement
			(enabled no)
			(sheetname "")
		)
		(fill yes
			(thermal_gap 0.5)
			(thermal_bridge_width 0.5)
			(island_removal_mode 0)
		)
		(polygon
			(pts
				(arc
					(start 431.88636 -275.535136)
					(mid 431.22596 -275.535136)
					(end 431.88636 -275.535136)
				)
			)
		)
	)
	(zone
		(layers "In1.Cu" "In2.Cu")
		(hatch none 0.5)
		(connect_pads
			(clearance 0)
		)
		(min_thickness 0.25)
		(keepout
			(tracks not_allowed)
			(vias allowed)
			(pads allowed)
			(copperpour not_allowed)
			(footprints allowed)
		)
		(placement
			(enabled no)
			(sheetname "")
		)
		(fill yes
			(thermal_gap 0.5)
			(thermal_bridge_width 0.5)
			(island_removal_mode 0)
		)
		(polygon
			(pts
				(arc
					(start 37.126164 -281.48534)
					(mid 36.465764 -281.48534)
					(end 37.126164 -281.48534)
				)
			)
		)
	)
	(zone
		(layers "In1.Cu" "In2.Cu")
		(hatch none 0.5)
		(connect_pads
			(clearance 0)
		)
		(min_thickness 0.25)
		(keepout
			(tracks not_allowed)
			(vias allowed)
			(pads allowed)
			(copperpour not_allowed)
			(footprints allowed)
		)
		(placement
			(enabled no)
			(sheetname "")
		)
		(fill yes
			(thermal_gap 0.5)
			(thermal_bridge_width 0.5)
			(island_removal_mode 0)
		)
		(polygon
			(pts
				(arc
					(start 187.390278 -230.485442)
					(mid 186.729878 -230.485442)
					(end 187.390278 -230.485442)
				)
			)
		)
	)
	(zone
		(layers "In1.Cu" "In2.Cu")
		(hatch none 0.5)
		(connect_pads
			(clearance 0)
		)
		(min_thickness 0.25)
		(keepout
			(tracks not_allowed)
			(vias allowed)
			(pads allowed)
			(copperpour not_allowed)
			(footprints allowed)
		)
		(placement
			(enabled no)
			(sheetname "")
		)
		(fill yes
			(thermal_gap 0.5)
			(thermal_bridge_width 0.5)
			(island_removal_mode 0)
		)
		(polygon
			(pts
				(arc
					(start 454.518268 -233.035094)
					(mid 453.857868 -233.035094)
					(end 454.518268 -233.035094)
				)
			)
		)
	)
	(zone
		(layers "In1.Cu" "In2.Cu")
		(hatch none 0.5)
		(connect_pads
			(clearance 0)
		)
		(min_thickness 0.25)
		(keepout
			(tracks not_allowed)
			(vias allowed)
			(pads allowed)
			(copperpour not_allowed)
			(footprints allowed)
		)
		(placement
			(enabled no)
			(sheetname "")
		)
		(fill yes
			(thermal_gap 0.5)
			(thermal_bridge_width 0.5)
			(island_removal_mode 0)
		)
		(polygon
			(pts
				(arc
					(start 17.938242 -305.285394)
					(mid 17.277842 -305.285394)
					(end 17.938242 -305.285394)
				)
			)
		)
	)
	(zone
		(layers "In1.Cu" "In2.Cu")
		(hatch none 0.5)
		(connect_pads
			(clearance 0)
		)
		(min_thickness 0.25)
		(keepout
			(tracks not_allowed)
			(vias allowed)
			(pads allowed)
			(copperpour not_allowed)
			(footprints allowed)
		)
		(placement
			(enabled no)
			(sheetname "")
		)
		(fill yes
			(thermal_gap 0.5)
			(thermal_bridge_width 0.5)
			(island_removal_mode 0)
		)
		(polygon
			(pts
				(arc
					(start 269.978378 -210.085178)
					(mid 269.317978 -210.085178)
					(end 269.978378 -210.085178)
				)
			)
		)
	)
	(zone
		(layers "In1.Cu" "In2.Cu")
		(hatch none 0.5)
		(connect_pads
			(clearance 0)
		)
		(min_thickness 0.25)
		(keepout
			(tracks not_allowed)
			(vias allowed)
			(pads allowed)
			(copperpour not_allowed)
			(footprints allowed)
		)
		(placement
			(enabled no)
			(sheetname "")
		)
		(fill yes
			(thermal_gap 0.5)
			(thermal_bridge_width 0.5)
			(island_removal_mode 0)
		)
		(polygon
			(pts
				(arc
					(start 431.88636 -242.385088)
					(mid 431.22596 -242.385088)
					(end 431.88636 -242.385088)
				)
			)
		)
	)
	(zone
		(layers "In1.Cu" "In2.Cu")
		(hatch none 0.5)
		(connect_pads
			(clearance 0)
		)
		(min_thickness 0.25)
		(keepout
			(tracks not_allowed)
			(vias allowed)
			(pads allowed)
			(copperpour not_allowed)
			(footprints allowed)
		)
		(placement
			(enabled no)
			(sheetname "")
		)
		(fill yes
			(thermal_gap 0.5)
			(thermal_bridge_width 0.5)
			(island_removal_mode 0)
		)
		(polygon
			(pts
				(arc
					(start 402.352256 -7.672324)
					(mid 402.374574 -7.618442)
					(end 402.428456 -7.596124)
				)
				(arc
					(start 403.46503 -7.596124)
					(mid 403.518912 -7.618442)
					(end 403.54123 -7.672324)
				)
				(arc
					(start 403.54123 -9.071864)
					(mid 403.518912 -9.125746)
					(end 403.46503 -9.148064)
				)
				(arc
					(start 402.428456 -9.148064)
					(mid 402.374574 -9.125746)
					(end 402.352256 -9.071864)
				)
			)
		)
	)
	(zone
		(layers "In1.Cu" "In2.Cu")
		(hatch none 0.5)
		(connect_pads
			(clearance 0)
		)
		(min_thickness 0.25)
		(keepout
			(tracks not_allowed)
			(vias allowed)
			(pads allowed)
			(copperpour not_allowed)
			(footprints allowed)
		)
		(placement
			(enabled no)
			(sheetname "")
		)
		(fill yes
			(thermal_gap 0.5)
			(thermal_bridge_width 0.5)
			(island_removal_mode 0)
		)
		(polygon
			(pts
				(arc
					(start 40.57015 -267.03528)
					(mid 39.90975 -267.03528)
					(end 40.57015 -267.03528)
				)
			)
		)
	)
	(zone
		(layers "In1.Cu" "In2.Cu")
		(hatch none 0.5)
		(connect_pads
			(clearance 0)
		)
		(min_thickness 0.25)
		(keepout
			(tracks not_allowed)
			(vias allowed)
			(pads allowed)
			(copperpour not_allowed)
			(footprints allowed)
		)
		(placement
			(enabled no)
			(sheetname "")
		)
		(fill yes
			(thermal_gap 0.5)
			(thermal_bridge_width 0.5)
			(island_removal_mode 0)
		)
		(polygon
			(pts
				(arc
					(start 44.670218 -238.985298)
					(mid 44.009818 -238.985298)
					(end 44.670218 -238.985298)
				)
			)
		)
	)
	(zone
		(layers "In1.Cu" "In2.Cu")
		(hatch none 0.5)
		(connect_pads
			(clearance 0)
		)
		(min_thickness 0.25)
		(keepout
			(tracks not_allowed)
			(vias allowed)
			(pads allowed)
			(copperpour not_allowed)
			(footprints allowed)
		)
		(placement
			(enabled no)
			(sheetname "")
		)
		(fill yes
			(thermal_gap 0.5)
			(thermal_bridge_width 0.5)
			(island_removal_mode 0)
		)
		(polygon
			(pts
				(arc
					(start 420.242238 -305.28514)
					(mid 419.581838 -305.28514)
					(end 420.242238 -305.28514)
				)
			)
		)
	)
	(zone
		(layers "In1.Cu" "In2.Cu")
		(hatch none 0.5)
		(connect_pads
			(clearance 0)
		)
		(min_thickness 0.25)
		(keepout
			(tracks not_allowed)
			(vias allowed)
			(pads allowed)
			(copperpour not_allowed)
			(footprints allowed)
		)
		(placement
			(enabled no)
			(sheetname "")
		)
		(fill yes
			(thermal_gap 0.5)
			(thermal_bridge_width 0.5)
			(island_removal_mode 0)
		)
		(polygon
			(pts
				(arc
					(start 44.670218 -298.485306)
					(mid 44.009818 -298.485306)
					(end 44.670218 -298.485306)
				)
			)
		)
	)
	(zone
		(layers "In1.Cu" "In2.Cu")
		(hatch none 0.5)
		(connect_pads
			(clearance 0)
		)
		(min_thickness 0.25)
		(keepout
			(tracks not_allowed)
			(vias allowed)
			(pads allowed)
			(copperpour not_allowed)
			(footprints allowed)
		)
		(placement
			(enabled no)
			(sheetname "")
		)
		(fill yes
			(thermal_gap 0.5)
			(thermal_bridge_width 0.5)
			(island_removal_mode 0)
		)
		(polygon
			(pts
				(arc
					(start 446.974468 -290.83508)
					(mid 446.314068 -290.83508)
					(end 446.974468 -290.83508)
				)
			)
		)
	)
	(zone
		(layers "In1.Cu" "In2.Cu")
		(hatch none 0.5)
		(connect_pads
			(clearance 0)
		)
		(min_thickness 0.25)
		(keepout
			(tracks not_allowed)
			(vias allowed)
			(pads allowed)
			(copperpour not_allowed)
			(footprints allowed)
		)
		(placement
			(enabled no)
			(sheetname "")
		)
		(fill yes
			(thermal_gap 0.5)
			(thermal_bridge_width 0.5)
			(island_removal_mode 0)
		)
		(polygon
			(pts
				(arc
					(start 427.786292 -221.13494)
					(mid 427.125892 -221.13494)
					(end 427.786292 -221.13494)
				)
			)
		)
	)
	(zone
		(layers "In1.Cu" "In2.Cu")
		(hatch none 0.5)
		(connect_pads
			(clearance 0)
		)
		(min_thickness 0.25)
		(keepout
			(tracks not_allowed)
			(vias allowed)
			(pads allowed)
			(copperpour not_allowed)
			(footprints allowed)
		)
		(placement
			(enabled no)
			(sheetname "")
		)
		(fill yes
			(thermal_gap 0.5)
			(thermal_bridge_width 0.5)
			(island_removal_mode 0)
		)
		(polygon
			(pts
				(arc
					(start 25.441656 -11.91768)
					(mid 25.419338 -11.971562)
					(end 25.365456 -11.99388)
				)
				(arc
					(start 24.328882 -11.99388)
					(mid 24.275 -11.971562)
					(end 24.252682 -11.91768)
				)
				(arc
					(start 24.252682 -10.51814)
					(mid 24.275 -10.464258)
					(end 24.328882 -10.44194)
				)
				(arc
					(start 25.365456 -10.44194)
					(mid 25.419338 -10.464258)
					(end 25.441656 -10.51814)
				)
			)
		)
	)
	(zone
		(layers "In1.Cu" "In2.Cu")
		(hatch none 0.5)
		(connect_pads
			(clearance 0)
		)
		(min_thickness 0.25)
		(keepout
			(tracks not_allowed)
			(vias allowed)
			(pads allowed)
			(copperpour not_allowed)
			(footprints allowed)
		)
		(placement
			(enabled no)
			(sheetname "")
		)
		(fill yes
			(thermal_gap 0.5)
			(thermal_bridge_width 0.5)
			(island_removal_mode 0)
		)
		(polygon
			(pts
				(arc
					(start 179.846224 -222.835216)
					(mid 179.185824 -222.835216)
					(end 179.846224 -222.835216)
				)
			)
		)
	)
	(zone
		(layers "In1.Cu" "In2.Cu")
		(hatch none 0.5)
		(connect_pads
			(clearance 0)
		)
		(min_thickness 0.25)
		(keepout
			(tracks not_allowed)
			(vias allowed)
			(pads allowed)
			(copperpour not_allowed)
			(footprints allowed)
		)
		(placement
			(enabled no)
			(sheetname "")
		)
		(fill yes
			(thermal_gap 0.5)
			(thermal_bridge_width 0.5)
			(island_removal_mode 0)
		)
		(polygon
			(pts
				(arc
					(start 431.88636 -281.485086)
					(mid 431.22596 -281.485086)
					(end 431.88636 -281.485086)
				)
			)
		)
	)
	(zone
		(layers "In1.Cu" "In2.Cu")
		(hatch none 0.5)
		(connect_pads
			(clearance 0)
		)
		(min_thickness 0.25)
		(keepout
			(tracks not_allowed)
			(vias allowed)
			(pads allowed)
			(copperpour not_allowed)
			(footprints allowed)
		)
		(placement
			(enabled no)
			(sheetname "")
		)
		(fill yes
			(thermal_gap 0.5)
			(thermal_bridge_width 0.5)
			(island_removal_mode 0)
		)
		(polygon
			(pts
				(arc
					(start 17.938242 -295.085262)
					(mid 17.277842 -295.085262)
					(end 17.938242 -295.085262)
				)
			)
		)
	)
	(zone
		(layers "In1.Cu" "In2.Cu")
		(hatch none 0.5)
		(connect_pads
			(clearance 0)
		)
		(min_thickness 0.25)
		(keepout
			(tracks not_allowed)
			(vias allowed)
			(pads allowed)
			(copperpour not_allowed)
			(footprints allowed)
		)
		(placement
			(enabled no)
			(sheetname "")
		)
		(fill yes
			(thermal_gap 0.5)
			(thermal_bridge_width 0.5)
			(island_removal_mode 0)
		)
		(polygon
			(pts
				(arc
					(start 194.934332 -216.885266)
					(mid 194.273932 -216.885266)
					(end 194.934332 -216.885266)
				)
			)
		)
	)
	(zone
		(layers "In1.Cu" "In2.Cu")
		(hatch none 0.5)
		(connect_pads
			(clearance 0)
		)
		(min_thickness 0.25)
		(keepout
			(tracks not_allowed)
			(vias allowed)
			(pads allowed)
			(copperpour not_allowed)
			(footprints allowed)
		)
		(placement
			(enabled no)
			(sheetname "")
		)
		(fill yes
			(thermal_gap 0.5)
			(thermal_bridge_width 0.5)
			(island_removal_mode 0)
		)
		(polygon
			(pts
				(arc
					(start 300.15434 -238.985044)
					(mid 299.49394 -238.985044)
					(end 300.15434 -238.985044)
				)
			)
		)
	)
	(zone
		(layers "In1.Cu" "In2.Cu")
		(hatch none 0.5)
		(connect_pads
			(clearance 0)
		)
		(min_thickness 0.25)
		(keepout
			(tracks not_allowed)
			(vias allowed)
			(pads allowed)
			(copperpour not_allowed)
			(footprints allowed)
		)
		(placement
			(enabled no)
			(sheetname "")
		)
		(fill yes
			(thermal_gap 0.5)
			(thermal_bridge_width 0.5)
			(island_removal_mode 0)
		)
		(polygon
			(pts
				(arc
					(start 288.510218 -235.585)
					(mid 287.849818 -235.585)
					(end 288.510218 -235.585)
				)
			)
		)
	)
	(zone
		(layers "In1.Cu" "In2.Cu")
		(hatch none 0.5)
		(connect_pads
			(clearance 0)
		)
		(min_thickness 0.25)
		(keepout
			(tracks not_allowed)
			(vias allowed)
			(pads allowed)
			(copperpour not_allowed)
			(footprints allowed)
		)
		(placement
			(enabled no)
			(sheetname "")
		)
		(fill yes
			(thermal_gap 0.5)
			(thermal_bridge_width 0.5)
			(island_removal_mode 0)
		)
		(polygon
			(pts
				(arc
					(start 427.786292 -205.834996)
					(mid 427.125892 -205.834996)
					(end 427.786292 -205.834996)
				)
			)
		)
	)
	(zone
		(layers "In1.Cu" "In2.Cu")
		(hatch none 0.5)
		(connect_pads
			(clearance 0)
		)
		(min_thickness 0.25)
		(keepout
			(tracks not_allowed)
			(vias allowed)
			(pads allowed)
			(copperpour not_allowed)
			(footprints allowed)
		)
		(placement
			(enabled no)
			(sheetname "")
		)
		(fill yes
			(thermal_gap 0.5)
			(thermal_bridge_width 0.5)
			(island_removal_mode 0)
		)
		(polygon
			(pts
				(arc
					(start 191.490346 -216.035382)
					(mid 190.829946 -216.035382)
					(end 191.490346 -216.035382)
				)
			)
		)
	)
	(zone
		(layers "In1.Cu" "In2.Cu")
		(hatch none 0.5)
		(connect_pads
			(clearance 0)
		)
		(min_thickness 0.25)
		(keepout
			(tracks not_allowed)
			(vias allowed)
			(pads allowed)
			(copperpour not_allowed)
			(footprints allowed)
		)
		(placement
			(enabled no)
			(sheetname "")
		)
		(fill yes
			(thermal_gap 0.5)
			(thermal_bridge_width 0.5)
			(island_removal_mode 0)
		)
		(polygon
			(pts
				(arc
					(start 29.582364 -233.035348)
					(mid 28.921964 -233.035348)
					(end 29.582364 -233.035348)
				)
			)
		)
	)
	(zone
		(layers "In1.Cu" "In2.Cu")
		(hatch none 0.5)
		(connect_pads
			(clearance 0)
		)
		(min_thickness 0.25)
		(keepout
			(tracks not_allowed)
			(vias allowed)
			(pads allowed)
			(copperpour not_allowed)
			(footprints allowed)
		)
		(placement
			(enabled no)
			(sheetname "")
		)
		(fill yes
			(thermal_gap 0.5)
			(thermal_bridge_width 0.5)
			(island_removal_mode 0)
		)
		(polygon
			(pts
				(arc
					(start 110.883446 -373.442484)
					(mid 110.90337 -373.45172)
					(end 110.925102 -373.45493)
				)
				(arc
					(start 111.119666 -373.45493)
					(mid 111.173548 -373.432612)
					(end 111.195866 -373.37873)
				)
				(arc
					(start 111.195866 -372.69293)
					(mid 111.173548 -372.639048)
					(end 111.119666 -372.61673)
				)
				(arc
					(start 110.925102 -372.61673)
					(mid 110.903358 -372.619898)
					(end 110.883446 -372.629176)
				)
				(arc
					(start 110.587282 -372.821962)
					(mid 110.545598 -372.834184)
					(end 110.50397 -372.821708)
				)
				(arc
					(start 110.210346 -372.629176)
					(mid 110.190422 -372.61994)
					(end 110.16869 -372.61673)
				)
				(arc
					(start 109.974126 -372.61673)
					(mid 109.920244 -372.639048)
					(end 109.897926 -372.69293)
				)
				(arc
					(start 109.897926 -373.37873)
					(mid 109.920244 -373.432612)
					(end 109.974126 -373.45493)
				)
				(arc
					(start 110.16996 -373.45493)
					(mid 110.191704 -373.451762)
					(end 110.211616 -373.442484)
				)
				(arc
					(start 110.50524 -373.249952)
					(mid 110.546896 -373.23755)
					(end 110.588552 -373.249952)
				)
			)
		)
	)
	(zone
		(layers "In1.Cu" "In2.Cu")
		(hatch none 0.5)
		(connect_pads
			(clearance 0)
		)
		(min_thickness 0.25)
		(keepout
			(tracks not_allowed)
			(vias allowed)
			(pads allowed)
			(copperpour not_allowed)
			(footprints allowed)
		)
		(placement
			(enabled no)
			(sheetname "")
		)
		(fill yes
			(thermal_gap 0.5)
			(thermal_bridge_width 0.5)
			(island_removal_mode 0)
		)
		(polygon
			(pts
				(arc
					(start 416.798252 -244.08511)
					(mid 416.137852 -244.08511)
					(end 416.798252 -244.08511)
				)
			)
		)
	)
	(zone
		(layers "In1.Cu" "In2.Cu")
		(hatch none 0.5)
		(connect_pads
			(clearance 0)
		)
		(min_thickness 0.25)
		(keepout
			(tracks not_allowed)
			(vias allowed)
			(pads allowed)
			(copperpour not_allowed)
			(footprints allowed)
		)
		(placement
			(enabled no)
			(sheetname "")
		)
		(fill yes
			(thermal_gap 0.5)
			(thermal_bridge_width 0.5)
			(island_removal_mode 0)
		)
		(polygon
			(pts
				(arc
					(start 69.33438 -380.265178)
					(mid 69.325144 -380.285102)
					(end 69.321934 -380.306834)
				)
				(arc
					(start 69.321934 -380.501398)
					(mid 69.344252 -380.55528)
					(end 69.398134 -380.577598)
				)
				(arc
					(start 70.083934 -380.577598)
					(mid 70.137816 -380.55528)
					(end 70.160134 -380.501398)
				)
				(arc
					(start 70.160134 -380.306834)
					(mid 70.156966 -380.28509)
					(end 70.147688 -380.265178)
				)
				(arc
					(start 69.954902 -379.969014)
					(mid 69.94268 -379.92733)
					(end 69.955156 -379.885702)
				)
				(arc
					(start 70.147688 -379.592078)
					(mid 70.156924 -379.572154)
					(end 70.160134 -379.550422)
				)
				(arc
					(start 70.160134 -379.355858)
					(mid 70.137816 -379.301976)
					(end 70.083934 -379.279658)
				)
				(arc
					(start 69.398134 -379.279658)
					(mid 69.344252 -379.301976)
					(end 69.321934 -379.355858)
				)
				(arc
					(start 69.321934 -379.551692)
					(mid 69.325102 -379.573436)
					(end 69.33438 -379.593348)
				)
				(arc
					(start 69.526912 -379.886972)
					(mid 69.539314 -379.928628)
					(end 69.526912 -379.970284)
				)
			)
		)
	)
	(zone
		(layers "In1.Cu" "In2.Cu")
		(hatch none 0.5)
		(connect_pads
			(clearance 0)
		)
		(min_thickness 0.25)
		(keepout
			(tracks not_allowed)
			(vias allowed)
			(pads allowed)
			(copperpour not_allowed)
			(footprints allowed)
		)
		(placement
			(enabled no)
			(sheetname "")
		)
		(fill yes
			(thermal_gap 0.5)
			(thermal_bridge_width 0.5)
			(island_removal_mode 0)
		)
		(polygon
			(pts
				(arc
					(start 454.518268 -225.385122)
					(mid 453.857868 -225.385122)
					(end 454.518268 -225.385122)
				)
			)
		)
	)
	(zone
		(layers "In1.Cu" "In2.Cu")
		(hatch none 0.5)
		(connect_pads
			(clearance 0)
		)
		(min_thickness 0.25)
		(keepout
			(tracks not_allowed)
			(vias allowed)
			(pads allowed)
			(copperpour not_allowed)
			(footprints allowed)
		)
		(placement
			(enabled no)
			(sheetname "")
		)
		(fill yes
			(thermal_gap 0.5)
			(thermal_bridge_width 0.5)
			(island_removal_mode 0)
		)
		(polygon
			(pts
				(arc
					(start 277.522432 -307.835046)
					(mid 276.862032 -307.835046)
					(end 277.522432 -307.835046)
				)
			)
		)
	)
	(zone
		(layers "In1.Cu" "In2.Cu")
		(hatch none 0.5)
		(connect_pads
			(clearance 0)
		)
		(min_thickness 0.25)
		(keepout
			(tracks not_allowed)
			(vias allowed)
			(pads allowed)
			(copperpour not_allowed)
			(footprints allowed)
		)
		(placement
			(enabled no)
			(sheetname "")
		)
		(fill yes
			(thermal_gap 0.5)
			(thermal_bridge_width 0.5)
			(island_removal_mode 0)
		)
		(polygon
			(pts
				(arc
					(start 187.390278 -237.285276)
					(mid 186.729878 -237.285276)
					(end 187.390278 -237.285276)
				)
			)
		)
	)
	(zone
		(layers "In1.Cu" "In2.Cu")
		(hatch none 0.5)
		(connect_pads
			(clearance 0)
		)
		(min_thickness 0.25)
		(keepout
			(tracks not_allowed)
			(vias allowed)
			(pads allowed)
			(copperpour not_allowed)
			(footprints allowed)
		)
		(placement
			(enabled no)
			(sheetname "")
		)
		(fill yes
			(thermal_gap 0.5)
			(thermal_bridge_width 0.5)
			(island_removal_mode 0)
		)
		(polygon
			(pts
				(arc
					(start 199.0344 -212.635338)
					(mid 198.374 -212.635338)
					(end 199.0344 -212.635338)
				)
			)
		)
	)
	(zone
		(layers "In1.Cu" "In2.Cu")
		(hatch none 0.5)
		(connect_pads
			(clearance 0)
		)
		(min_thickness 0.25)
		(keepout
			(tracks not_allowed)
			(vias allowed)
			(pads allowed)
			(copperpour not_allowed)
			(footprints allowed)
		)
		(placement
			(enabled no)
			(sheetname "")
		)
		(fill yes
			(thermal_gap 0.5)
			(thermal_bridge_width 0.5)
			(island_removal_mode 0)
		)
		(polygon
			(pts
				(arc
					(start 277.522432 -244.08511)
					(mid 276.862032 -244.08511)
					(end 277.522432 -244.08511)
				)
			)
		)
	)
	(zone
		(layers "In1.Cu" "In2.Cu")
		(hatch none 0.5)
		(connect_pads
			(clearance 0)
		)
		(min_thickness 0.25)
		(keepout
			(tracks not_allowed)
			(vias allowed)
			(pads allowed)
			(copperpour not_allowed)
			(footprints allowed)
		)
		(placement
			(enabled no)
			(sheetname "")
		)
		(fill yes
			(thermal_gap 0.5)
			(thermal_bridge_width 0.5)
			(island_removal_mode 0)
		)
		(polygon
			(pts
				(arc
					(start 194.934332 -289.98545)
					(mid 194.273932 -289.98545)
					(end 194.934332 -289.98545)
				)
			)
		)
	)
	(zone
		(layers "In1.Cu" "In2.Cu")
		(hatch none 0.5)
		(connect_pads
			(clearance 0)
		)
		(min_thickness 0.25)
		(keepout
			(tracks not_allowed)
			(vias allowed)
			(pads allowed)
			(copperpour not_allowed)
			(footprints allowed)
		)
		(placement
			(enabled no)
			(sheetname "")
		)
		(fill yes
			(thermal_gap 0.5)
			(thermal_bridge_width 0.5)
			(island_removal_mode 0)
		)
		(polygon
			(pts
				(arc
					(start 435.330346 -218.585034)
					(mid 434.669946 -218.585034)
					(end 435.330346 -218.585034)
				)
			)
		)
	)
	(zone
		(layers "In1.Cu" "In2.Cu")
		(hatch none 0.5)
		(connect_pads
			(clearance 0)
		)
		(min_thickness 0.25)
		(keepout
			(tracks not_allowed)
			(vias allowed)
			(pads allowed)
			(copperpour not_allowed)
			(footprints allowed)
		)
		(placement
			(enabled no)
			(sheetname "")
		)
		(fill yes
			(thermal_gap 0.5)
			(thermal_bridge_width 0.5)
			(island_removal_mode 0)
		)
		(polygon
			(pts
				(arc
					(start 446.974468 -217.73515)
					(mid 446.314068 -217.73515)
					(end 446.974468 -217.73515)
				)
			)
		)
	)
	(zone
		(layers "In1.Cu" "In2.Cu")
		(hatch none 0.5)
		(connect_pads
			(clearance 0)
		)
		(min_thickness 0.25)
		(keepout
			(tracks not_allowed)
			(vias allowed)
			(pads allowed)
			(copperpour not_allowed)
			(footprints allowed)
		)
		(placement
			(enabled no)
			(sheetname "")
		)
		(fill yes
			(thermal_gap 0.5)
			(thermal_bridge_width 0.5)
			(island_removal_mode 0)
		)
		(polygon
			(pts
				(arc
					(start 439.430414 -228.785166)
					(mid 438.770014 -228.785166)
					(end 439.430414 -228.785166)
				)
			)
		)
	)
	(zone
		(layers "In1.Cu" "In2.Cu")
		(hatch none 0.5)
		(connect_pads
			(clearance 0)
		)
		(min_thickness 0.25)
		(keepout
			(tracks not_allowed)
			(vias allowed)
			(pads allowed)
			(copperpour not_allowed)
			(footprints allowed)
		)
		(placement
			(enabled no)
			(sheetname "")
		)
		(fill yes
			(thermal_gap 0.5)
			(thermal_bridge_width 0.5)
			(island_removal_mode 0)
		)
		(polygon
			(pts
				(arc
					(start 277.522432 -238.985044)
					(mid 276.862032 -238.985044)
					(end 277.522432 -238.985044)
				)
			)
		)
	)
	(zone
		(layers "In1.Cu" "In2.Cu")
		(hatch none 0.5)
		(connect_pads
			(clearance 0)
		)
		(min_thickness 0.25)
		(keepout
			(tracks not_allowed)
			(vias allowed)
			(pads allowed)
			(copperpour not_allowed)
			(footprints allowed)
		)
		(placement
			(enabled no)
			(sheetname "")
		)
		(fill yes
			(thermal_gap 0.5)
			(thermal_bridge_width 0.5)
			(island_removal_mode 0)
		)
		(polygon
			(pts
				(arc
					(start 52.214272 -249.18543)
					(mid 51.553872 -249.18543)
					(end 52.214272 -249.18543)
				)
			)
		)
	)
	(zone
		(layers "In1.Cu" "In2.Cu")
		(hatch none 0.5)
		(connect_pads
			(clearance 0)
		)
		(min_thickness 0.25)
		(keepout
			(tracks not_allowed)
			(vias allowed)
			(pads allowed)
			(copperpour not_allowed)
			(footprints allowed)
		)
		(placement
			(enabled no)
			(sheetname "")
		)
		(fill yes
			(thermal_gap 0.5)
			(thermal_bridge_width 0.5)
			(island_removal_mode 0)
		)
		(polygon
			(pts
				(arc
					(start 78.013052 -370.978684)
					(mid 78.032976 -370.98792)
					(end 78.054708 -370.99113)
				)
				(arc
					(start 78.249272 -370.99113)
					(mid 78.303154 -370.968812)
					(end 78.325472 -370.91493)
				)
				(arc
					(start 78.325472 -370.22913)
					(mid 78.303154 -370.175248)
					(end 78.249272 -370.15293)
				)
				(arc
					(start 78.054708 -370.15293)
					(mid 78.032964 -370.156098)
					(end 78.013052 -370.165376)
				)
				(arc
					(start 77.716888 -370.358162)
					(mid 77.675204 -370.370384)
					(end 77.633576 -370.357908)
				)
				(arc
					(start 77.339952 -370.165376)
					(mid 77.320028 -370.15614)
					(end 77.298296 -370.15293)
				)
				(arc
					(start 77.103732 -370.15293)
					(mid 77.04985 -370.175248)
					(end 77.027532 -370.22913)
				)
				(arc
					(start 77.027532 -370.91493)
					(mid 77.04985 -370.968812)
					(end 77.103732 -370.99113)
				)
				(arc
					(start 77.299566 -370.99113)
					(mid 77.32131 -370.987962)
					(end 77.341222 -370.978684)
				)
				(arc
					(start 77.634846 -370.786152)
					(mid 77.676502 -370.77375)
					(end 77.718158 -370.786152)
				)
			)
		)
	)
	(zone
		(layers "In1.Cu" "In2.Cu")
		(hatch none 0.5)
		(connect_pads
			(clearance 0)
		)
		(min_thickness 0.25)
		(keepout
			(tracks not_allowed)
			(vias allowed)
			(pads allowed)
			(copperpour not_allowed)
			(footprints allowed)
		)
		(placement
			(enabled no)
			(sheetname "")
		)
		(fill yes
			(thermal_gap 0.5)
			(thermal_bridge_width 0.5)
			(island_removal_mode 0)
		)
		(polygon
			(pts
				(arc
					(start 435.330346 -221.13494)
					(mid 434.669946 -221.13494)
					(end 435.330346 -221.13494)
				)
			)
		)
	)
	(zone
		(layers "In1.Cu" "In2.Cu")
		(hatch none 0.5)
		(connect_pads
			(clearance 0)
		)
		(min_thickness 0.25)
		(keepout
			(tracks not_allowed)
			(vias allowed)
			(pads allowed)
			(copperpour not_allowed)
			(footprints allowed)
		)
		(placement
			(enabled no)
			(sheetname "")
		)
		(fill yes
			(thermal_gap 0.5)
			(thermal_bridge_width 0.5)
			(island_removal_mode 0)
		)
		(polygon
			(pts
				(arc
					(start 273.422364 -216.885012)
					(mid 272.761964 -216.885012)
					(end 273.422364 -216.885012)
				)
			)
		)
	)
	(zone
		(layers "In1.Cu" "In2.Cu")
		(hatch none 0.5)
		(connect_pads
			(clearance 0)
		)
		(min_thickness 0.25)
		(keepout
			(tracks not_allowed)
			(vias allowed)
			(pads allowed)
			(copperpour not_allowed)
			(footprints allowed)
		)
		(placement
			(enabled no)
			(sheetname "")
		)
		(fill yes
			(thermal_gap 0.5)
			(thermal_bridge_width 0.5)
			(island_removal_mode 0)
		)
		(polygon
			(pts
				(arc
					(start 300.15434 -294.235124)
					(mid 299.49394 -294.235124)
					(end 300.15434 -294.235124)
				)
			)
		)
	)
	(zone
		(layers "In1.Cu" "In2.Cu")
		(hatch none 0.5)
		(connect_pads
			(clearance 0)
		)
		(min_thickness 0.25)
		(keepout
			(tracks not_allowed)
			(vias allowed)
			(pads allowed)
			(copperpour not_allowed)
			(footprints allowed)
		)
		(placement
			(enabled no)
			(sheetname "")
		)
		(fill yes
			(thermal_gap 0.5)
			(thermal_bridge_width 0.5)
			(island_removal_mode 0)
		)
		(polygon
			(pts
				(arc
					(start 191.490346 -281.48534)
					(mid 190.829946 -281.48534)
					(end 191.490346 -281.48534)
				)
			)
		)
	)
	(zone
		(layers "In1.Cu" "In2.Cu")
		(hatch none 0.5)
		(connect_pads
			(clearance 0)
		)
		(min_thickness 0.25)
		(keepout
			(tracks not_allowed)
			(vias allowed)
			(pads allowed)
			(copperpour not_allowed)
			(footprints allowed)
		)
		(placement
			(enabled no)
			(sheetname "")
		)
		(fill yes
			(thermal_gap 0.5)
			(thermal_bridge_width 0.5)
			(island_removal_mode 0)
		)
		(polygon
			(pts
				(arc
					(start 25.482296 -267.03528)
					(mid 24.821896 -267.03528)
					(end 25.482296 -267.03528)
				)
			)
		)
	)
	(zone
		(layers "In1.Cu" "In2.Cu")
		(hatch none 0.5)
		(connect_pads
			(clearance 0)
		)
		(min_thickness 0.25)
		(keepout
			(tracks not_allowed)
			(vias allowed)
			(pads allowed)
			(copperpour not_allowed)
			(footprints allowed)
		)
		(placement
			(enabled no)
			(sheetname "")
		)
		(fill yes
			(thermal_gap 0.5)
			(thermal_bridge_width 0.5)
			(island_removal_mode 0)
		)
		(polygon
			(pts
				(arc
					(start 424.342306 -244.08511)
					(mid 423.681906 -244.08511)
					(end 424.342306 -244.08511)
				)
			)
		)
	)
	(zone
		(layers "In1.Cu" "In2.Cu")
		(hatch none 0.5)
		(connect_pads
			(clearance 0)
		)
		(min_thickness 0.25)
		(keepout
			(tracks not_allowed)
			(vias allowed)
			(pads allowed)
			(copperpour not_allowed)
			(footprints allowed)
		)
		(placement
			(enabled no)
			(sheetname "")
		)
		(fill yes
			(thermal_gap 0.5)
			(thermal_bridge_width 0.5)
			(island_removal_mode 0)
		)
		(polygon
			(pts
				(arc
					(start 442.8744 -306.985162)
					(mid 442.214 -306.985162)
					(end 442.8744 -306.985162)
				)
			)
		)
	)
	(zone
		(layers "In1.Cu" "In2.Cu")
		(hatch none 0.5)
		(connect_pads
			(clearance 0)
		)
		(min_thickness 0.25)
		(keepout
			(tracks not_allowed)
			(vias allowed)
			(pads allowed)
			(copperpour not_allowed)
			(footprints allowed)
		)
		(placement
			(enabled no)
			(sheetname "")
		)
		(fill yes
			(thermal_gap 0.5)
			(thermal_bridge_width 0.5)
			(island_removal_mode 0)
		)
		(polygon
			(pts
				(arc
					(start 280.966164 -205.834996)
					(mid 280.305764 -205.834996)
					(end 280.966164 -205.834996)
				)
			)
		)
	)
	(zone
		(layers "In1.Cu" "In2.Cu")
		(hatch none 0.5)
		(connect_pads
			(clearance 0)
		)
		(min_thickness 0.25)
		(keepout
			(tracks not_allowed)
			(vias allowed)
			(pads allowed)
			(copperpour not_allowed)
			(footprints allowed)
		)
		(placement
			(enabled no)
			(sheetname "")
		)
		(fill yes
			(thermal_gap 0.5)
			(thermal_bridge_width 0.5)
			(island_removal_mode 0)
		)
		(polygon
			(pts
				(arc
					(start 33.026096 -227.935282)
					(mid 32.365696 -227.935282)
					(end 33.026096 -227.935282)
				)
			)
		)
	)
	(zone
		(layers "In1.Cu" "In2.Cu")
		(hatch none 0.5)
		(connect_pads
			(clearance 0)
		)
		(min_thickness 0.25)
		(keepout
			(tracks not_allowed)
			(vias allowed)
			(pads allowed)
			(copperpour not_allowed)
			(footprints allowed)
		)
		(placement
			(enabled no)
			(sheetname "")
		)
		(fill yes
			(thermal_gap 0.5)
			(thermal_bridge_width 0.5)
			(island_removal_mode 0)
		)
		(polygon
			(pts
				(arc
					(start 439.430414 -273.835114)
					(mid 438.770014 -273.835114)
					(end 439.430414 -273.835114)
				)
			)
		)
	)
	(zone
		(layers "In1.Cu" "In2.Cu")
		(hatch none 0.5)
		(connect_pads
			(clearance 0)
		)
		(min_thickness 0.25)
		(keepout
			(tracks not_allowed)
			(vias allowed)
			(pads allowed)
			(copperpour not_allowed)
			(footprints allowed)
		)
		(placement
			(enabled no)
			(sheetname "")
		)
		(fill yes
			(thermal_gap 0.5)
			(thermal_bridge_width 0.5)
			(island_removal_mode 0)
		)
		(polygon
			(pts
				(arc
					(start 446.974468 -292.535102)
					(mid 446.314068 -292.535102)
					(end 446.974468 -292.535102)
				)
			)
		)
	)
	(zone
		(layers "In1.Cu" "In2.Cu")
		(hatch none 0.5)
		(connect_pads
			(clearance 0)
		)
		(min_thickness 0.25)
		(keepout
			(tracks not_allowed)
			(vias allowed)
			(pads allowed)
			(copperpour not_allowed)
			(footprints allowed)
		)
		(placement
			(enabled no)
			(sheetname "")
		)
		(fill yes
			(thermal_gap 0.5)
			(thermal_bridge_width 0.5)
			(island_removal_mode 0)
		)
		(polygon
			(pts
				(arc
					(start 280.966164 -254.284988)
					(mid 280.305764 -254.284988)
					(end 280.966164 -254.284988)
				)
			)
		)
	)
	(zone
		(layers "In1.Cu" "In2.Cu")
		(hatch none 0.5)
		(connect_pads
			(clearance 0)
		)
		(min_thickness 0.25)
		(keepout
			(tracks not_allowed)
			(vias allowed)
			(pads allowed)
			(copperpour not_allowed)
			(footprints allowed)
		)
		(placement
			(enabled no)
			(sheetname "")
		)
		(fill yes
			(thermal_gap 0.5)
			(thermal_bridge_width 0.5)
			(island_removal_mode 0)
		)
		(polygon
			(pts
				(arc
					(start 292.610286 -281.485086)
					(mid 291.949886 -281.485086)
					(end 292.610286 -281.485086)
				)
			)
		)
	)
	(zone
		(layers "In1.Cu" "In2.Cu")
		(hatch none 0.5)
		(connect_pads
			(clearance 0)
		)
		(min_thickness 0.25)
		(keepout
			(tracks not_allowed)
			(vias allowed)
			(pads allowed)
			(copperpour not_allowed)
			(footprints allowed)
		)
		(placement
			(enabled no)
			(sheetname "")
		)
		(fill yes
			(thermal_gap 0.5)
			(thermal_bridge_width 0.5)
			(island_removal_mode 0)
		)
		(polygon
			(pts
				(arc
					(start 296.054272 -288.285174)
					(mid 295.393872 -288.285174)
					(end 296.054272 -288.285174)
				)
			)
		)
	)
	(zone
		(layers "In1.Cu" "In2.Cu")
		(hatch none 0.5)
		(connect_pads
			(clearance 0)
		)
		(min_thickness 0.25)
		(keepout
			(tracks not_allowed)
			(vias allowed)
			(pads allowed)
			(copperpour not_allowed)
			(footprints allowed)
		)
		(placement
			(enabled no)
			(sheetname "")
		)
		(fill yes
			(thermal_gap 0.5)
			(thermal_bridge_width 0.5)
			(island_removal_mode 0)
		)
		(polygon
			(pts
				(arc
					(start 52.214272 -262.785352)
					(mid 51.553872 -262.785352)
					(end 52.214272 -262.785352)
				)
			)
		)
	)
	(zone
		(layers "In1.Cu" "In2.Cu")
		(hatch none 0.5)
		(connect_pads
			(clearance 0)
		)
		(min_thickness 0.25)
		(keepout
			(tracks not_allowed)
			(vias allowed)
			(pads allowed)
			(copperpour not_allowed)
			(footprints allowed)
		)
		(placement
			(enabled no)
			(sheetname "")
		)
		(fill yes
			(thermal_gap 0.5)
			(thermal_bridge_width 0.5)
			(island_removal_mode 0)
		)
		(polygon
			(pts
				(arc
					(start 439.430414 -289.135058)
					(mid 438.770014 -289.135058)
					(end 439.430414 -289.135058)
				)
			)
		)
	)
	(zone
		(layers "In1.Cu" "In2.Cu")
		(hatch none 0.5)
		(connect_pads
			(clearance 0)
		)
		(min_thickness 0.25)
		(keepout
			(tracks not_allowed)
			(vias allowed)
			(pads allowed)
			(copperpour not_allowed)
			(footprints allowed)
		)
		(placement
			(enabled no)
			(sheetname "")
		)
		(fill yes
			(thermal_gap 0.5)
			(thermal_bridge_width 0.5)
			(island_removal_mode 0)
		)
		(polygon
			(pts
				(arc
					(start 404.51659 -384.288284)
					(mid 404.536514 -384.29752)
					(end 404.558246 -384.30073)
				)
				(arc
					(start 404.75281 -384.30073)
					(mid 404.806692 -384.278412)
					(end 404.82901 -384.22453)
				)
				(arc
					(start 404.82901 -383.53873)
					(mid 404.806692 -383.484848)
					(end 404.75281 -383.46253)
				)
				(arc
					(start 404.558246 -383.46253)
					(mid 404.536502 -383.465698)
					(end 404.51659 -383.474976)
				)
				(arc
					(start 404.220426 -383.667762)
					(mid 404.178742 -383.679984)
					(end 404.137114 -383.667508)
				)
				(arc
					(start 403.84349 -383.474976)
					(mid 403.823566 -383.46574)
					(end 403.801834 -383.46253)
				)
				(arc
					(start 403.60727 -383.46253)
					(mid 403.553388 -383.484848)
					(end 403.53107 -383.53873)
				)
				(arc
					(start 403.53107 -384.22453)
					(mid 403.553388 -384.278412)
					(end 403.60727 -384.30073)
				)
				(arc
					(start 403.803104 -384.30073)
					(mid 403.824848 -384.297562)
					(end 403.84476 -384.288284)
				)
				(arc
					(start 404.138384 -384.095752)
					(mid 404.18004 -384.08335)
					(end 404.221696 -384.095752)
				)
			)
		)
	)
	(zone
		(layers "In1.Cu" "In2.Cu")
		(hatch none 0.5)
		(connect_pads
			(clearance 0)
		)
		(min_thickness 0.25)
		(keepout
			(tracks not_allowed)
			(vias allowed)
			(pads allowed)
			(copperpour not_allowed)
			(footprints allowed)
		)
		(placement
			(enabled no)
			(sheetname "")
		)
		(fill yes
			(thermal_gap 0.5)
			(thermal_bridge_width 0.5)
			(island_removal_mode 0)
		)
		(polygon
			(pts
				(arc
					(start 179.846224 -226.23526)
					(mid 179.185824 -226.23526)
					(end 179.846224 -226.23526)
				)
			)
		)
	)
	(zone
		(layers "In1.Cu" "In2.Cu")
		(hatch none 0.5)
		(connect_pads
			(clearance 0)
		)
		(min_thickness 0.25)
		(keepout
			(tracks not_allowed)
			(vias allowed)
			(pads allowed)
			(copperpour not_allowed)
			(footprints allowed)
		)
		(placement
			(enabled no)
			(sheetname "")
		)
		(fill yes
			(thermal_gap 0.5)
			(thermal_bridge_width 0.5)
			(island_removal_mode 0)
		)
		(polygon
			(pts
				(arc
					(start 238.74603 -54.615588)
					(mid 238.736794 -54.635512)
					(end 238.733584 -54.657244)
				)
				(arc
					(start 238.733584 -54.851808)
					(mid 238.755902 -54.90569)
					(end 238.809784 -54.928008)
				)
				(arc
					(start 239.495584 -54.928008)
					(mid 239.549466 -54.90569)
					(end 239.571784 -54.851808)
				)
				(arc
					(start 239.571784 -54.657244)
					(mid 239.568616 -54.6355)
					(end 239.559338 -54.615588)
				)
				(arc
					(start 239.366552 -54.319424)
					(mid 239.35433 -54.27774)
					(end 239.366806 -54.236112)
				)
				(arc
					(start 239.559338 -53.942488)
					(mid 239.568574 -53.922564)
					(end 239.571784 -53.900832)
				)
				(arc
					(start 239.571784 -53.706268)
					(mid 239.549466 -53.652386)
					(end 239.495584 -53.630068)
				)
				(arc
					(start 238.809784 -53.630068)
					(mid 238.755902 -53.652386)
					(end 238.733584 -53.706268)
				)
				(arc
					(start 238.733584 -53.902102)
					(mid 238.736752 -53.923846)
					(end 238.74603 -53.943758)
				)
				(arc
					(start 238.938562 -54.237382)
					(mid 238.950964 -54.279038)
					(end 238.938562 -54.320694)
				)
			)
		)
	)
	(zone
		(layers "In1.Cu" "In2.Cu")
		(hatch none 0.5)
		(connect_pads
			(clearance 0)
		)
		(min_thickness 0.25)
		(keepout
			(tracks not_allowed)
			(vias allowed)
			(pads allowed)
			(copperpour not_allowed)
			(footprints allowed)
		)
		(placement
			(enabled no)
			(sheetname "")
		)
		(fill yes
			(thermal_gap 0.5)
			(thermal_bridge_width 0.5)
			(island_removal_mode 0)
		)
		(polygon
			(pts
				(arc
					(start 269.978378 -309.535068)
					(mid 269.317978 -309.535068)
					(end 269.978378 -309.535068)
				)
			)
		)
	)
	(zone
		(layers "In1.Cu" "In2.Cu")
		(hatch none 0.5)
		(connect_pads
			(clearance 0)
		)
		(min_thickness 0.25)
		(keepout
			(tracks not_allowed)
			(vias allowed)
			(pads allowed)
			(copperpour not_allowed)
			(footprints allowed)
		)
		(placement
			(enabled no)
			(sheetname "")
		)
		(fill yes
			(thermal_gap 0.5)
			(thermal_bridge_width 0.5)
			(island_removal_mode 0)
		)
		(polygon
			(pts
				(arc
					(start 296.054272 -306.985162)
					(mid 295.393872 -306.985162)
					(end 296.054272 -306.985162)
				)
			)
		)
	)
	(zone
		(layers "In1.Cu" "In2.Cu")
		(hatch none 0.5)
		(connect_pads
			(clearance 0)
		)
		(min_thickness 0.25)
		(keepout
			(tracks not_allowed)
			(vias allowed)
			(pads allowed)
			(copperpour not_allowed)
			(footprints allowed)
		)
		(placement
			(enabled no)
			(sheetname "")
		)
		(fill yes
			(thermal_gap 0.5)
			(thermal_bridge_width 0.5)
			(island_removal_mode 0)
		)
		(polygon
			(pts
				(arc
					(start 424.342306 -261.085076)
					(mid 423.681906 -261.085076)
					(end 424.342306 -261.085076)
				)
			)
		)
	)
	(zone
		(layers "In1.Cu" "In2.Cu")
		(hatch none 0.5)
		(connect_pads
			(clearance 0)
		)
		(min_thickness 0.25)
		(keepout
			(tracks not_allowed)
			(vias allowed)
			(pads allowed)
			(copperpour not_allowed)
			(footprints allowed)
		)
		(placement
			(enabled no)
			(sheetname "")
		)
		(fill yes
			(thermal_gap 0.5)
			(thermal_bridge_width 0.5)
			(island_removal_mode 0)
		)
		(polygon
			(pts
				(arc
					(start 435.330346 -239.835182)
					(mid 434.669946 -239.835182)
					(end 435.330346 -239.835182)
				)
			)
		)
	)
	(zone
		(layers "In1.Cu" "In2.Cu")
		(hatch none 0.5)
		(connect_pads
			(clearance 0)
		)
		(min_thickness 0.25)
		(keepout
			(tracks not_allowed)
			(vias allowed)
			(pads allowed)
			(copperpour not_allowed)
			(footprints allowed)
		)
		(placement
			(enabled no)
			(sheetname "")
		)
		(fill yes
			(thermal_gap 0.5)
			(thermal_bridge_width 0.5)
			(island_removal_mode 0)
		)
		(polygon
			(pts
				(arc
					(start 187.390278 -209.235294)
					(mid 186.729878 -209.235294)
					(end 187.390278 -209.235294)
				)
			)
		)
	)
	(zone
		(layers "In1.Cu" "In2.Cu")
		(hatch none 0.5)
		(connect_pads
			(clearance 0)
		)
		(min_thickness 0.25)
		(keepout
			(tracks not_allowed)
			(vias allowed)
			(pads allowed)
			(copperpour not_allowed)
			(footprints allowed)
		)
		(placement
			(enabled no)
			(sheetname "")
		)
		(fill yes
			(thermal_gap 0.5)
			(thermal_bridge_width 0.5)
			(island_removal_mode 0)
		)
		(polygon
			(pts
				(arc
					(start 280.966164 -243.234972)
					(mid 280.305764 -243.234972)
					(end 280.966164 -243.234972)
				)
			)
		)
	)
	(zone
		(layers "In1.Cu" "In2.Cu")
		(hatch none 0.5)
		(connect_pads
			(clearance 0)
		)
		(min_thickness 0.25)
		(keepout
			(tracks not_allowed)
			(vias allowed)
			(pads allowed)
			(copperpour not_allowed)
			(footprints allowed)
		)
		(placement
			(enabled no)
			(sheetname "")
		)
		(fill yes
			(thermal_gap 0.5)
			(thermal_bridge_width 0.5)
			(island_removal_mode 0)
		)
		(polygon
			(pts
				(arc
					(start 38.890194 -422.20007)
					(mid 38.905073 -422.235991)
					(end 38.940994 -422.25087)
				)
				(arc
					(start 40.210994 -422.25087)
					(mid 40.246915 -422.235991)
					(end 40.261794 -422.20007)
				)
				(arc
					(start 40.261794 -421.92067)
					(mid 40.246915 -421.884749)
					(end 40.210994 -421.86987)
				)
				(arc
					(start 38.940994 -421.86987)
					(mid 38.905073 -421.884749)
					(end 38.890194 -421.92067)
				)
			)
		)
	)
	(zone
		(layers "In1.Cu" "In2.Cu")
		(hatch none 0.5)
		(connect_pads
			(clearance 0)
		)
		(min_thickness 0.25)
		(keepout
			(tracks not_allowed)
			(vias allowed)
			(pads allowed)
			(copperpour not_allowed)
			(footprints allowed)
		)
		(placement
			(enabled no)
			(sheetname "")
		)
		(fill yes
			(thermal_gap 0.5)
			(thermal_bridge_width 0.5)
			(island_removal_mode 0)
		)
		(polygon
			(pts
				(arc
					(start 17.938242 -210.935316)
					(mid 17.277842 -210.935316)
					(end 17.938242 -210.935316)
				)
			)
		)
	)
	(zone
		(layers "In1.Cu" "In2.Cu")
		(hatch none 0.5)
		(connect_pads
			(clearance 0)
		)
		(min_thickness 0.25)
		(keepout
			(tracks not_allowed)
			(vias allowed)
			(pads allowed)
			(copperpour not_allowed)
			(footprints allowed)
		)
		(placement
			(enabled no)
			(sheetname "")
		)
		(fill yes
			(thermal_gap 0.5)
			(thermal_bridge_width 0.5)
			(island_removal_mode 0)
		)
		(polygon
			(pts
				(arc
					(start 300.15434 -214.335106)
					(mid 299.49394 -214.335106)
					(end 300.15434 -214.335106)
				)
			)
		)
	)
	(zone
		(layers "In1.Cu" "In2.Cu")
		(hatch none 0.5)
		(connect_pads
			(clearance 0)
		)
		(min_thickness 0.25)
		(keepout
			(tracks not_allowed)
			(vias allowed)
			(pads allowed)
			(copperpour not_allowed)
			(footprints allowed)
		)
		(placement
			(enabled no)
			(sheetname "")
		)
		(fill yes
			(thermal_gap 0.5)
			(thermal_bridge_width 0.5)
			(island_removal_mode 0)
		)
		(polygon
			(pts
				(arc
					(start 199.0344 -219.435426)
					(mid 198.374 -219.435426)
					(end 199.0344 -219.435426)
				)
			)
		)
	)
	(zone
		(layers "In1.Cu" "In2.Cu")
		(hatch none 0.5)
		(connect_pads
			(clearance 0)
		)
		(min_thickness 0.25)
		(keepout
			(tracks not_allowed)
			(vias allowed)
			(pads allowed)
			(copperpour not_allowed)
			(footprints allowed)
		)
		(placement
			(enabled no)
			(sheetname "")
		)
		(fill yes
			(thermal_gap 0.5)
			(thermal_bridge_width 0.5)
			(island_removal_mode 0)
		)
		(polygon
			(pts
				(arc
					(start 25.482296 -313.78525)
					(mid 24.821896 -313.78525)
					(end 25.482296 -313.78525)
				)
			)
		)
	)
	(zone
		(layers "In1.Cu" "In2.Cu")
		(hatch none 0.5)
		(connect_pads
			(clearance 0)
		)
		(min_thickness 0.25)
		(keepout
			(tracks not_allowed)
			(vias allowed)
			(pads allowed)
			(copperpour not_allowed)
			(footprints allowed)
		)
		(placement
			(enabled no)
			(sheetname "")
		)
		(fill yes
			(thermal_gap 0.5)
			(thermal_bridge_width 0.5)
			(island_removal_mode 0)
		)
		(polygon
			(pts
				(arc
					(start 454.518268 -306.135024)
					(mid 453.857868 -306.135024)
					(end 454.518268 -306.135024)
				)
			)
		)
	)
	(zone
		(layers "In1.Cu" "In2.Cu")
		(hatch none 0.5)
		(connect_pads
			(clearance 0)
		)
		(min_thickness 0.25)
		(keepout
			(tracks not_allowed)
			(vias allowed)
			(pads allowed)
			(copperpour not_allowed)
			(footprints allowed)
		)
		(placement
			(enabled no)
			(sheetname "")
		)
		(fill yes
			(thermal_gap 0.5)
			(thermal_bridge_width 0.5)
			(island_removal_mode 0)
		)
		(polygon
			(pts
				(arc
					(start 331.145896 -417.242244)
					(mid 331.168214 -417.296126)
					(end 331.222096 -417.318444)
				)
				(arc
					(start 331.417676 -417.318444)
					(mid 331.439552 -417.315312)
					(end 331.459586 -417.305998)
				)
				(arc
					(start 331.75321 -417.113466)
					(mid 331.794866 -417.101064)
					(end 331.836522 -417.113466)
				)
				(arc
					(start 332.131416 -417.305998)
					(mid 332.15134 -417.315234)
					(end 332.173072 -417.318444)
				)
				(arc
					(start 332.367636 -417.318444)
					(mid 332.421518 -417.296126)
					(end 332.443836 -417.242244)
				)
				(arc
					(start 332.443836 -416.556444)
					(mid 332.421518 -416.502562)
					(end 332.367636 -416.480244)
				)
				(arc
					(start 332.173072 -416.480244)
					(mid 332.151328 -416.483412)
					(end 332.131416 -416.49269)
				)
				(arc
					(start 331.835252 -416.685476)
					(mid 331.793568 -416.697698)
					(end 331.75194 -416.685222)
				)
				(arc
					(start 331.458316 -416.49269)
					(mid 331.438392 -416.483454)
					(end 331.41666 -416.480244)
				)
				(arc
					(start 331.222096 -416.480244)
					(mid 331.168214 -416.502562)
					(end 331.145896 -416.556444)
				)
			)
		)
	)
	(zone
		(layers "In1.Cu" "In2.Cu")
		(hatch none 0.5)
		(connect_pads
			(clearance 0)
		)
		(min_thickness 0.25)
		(keepout
			(tracks not_allowed)
			(vias allowed)
			(pads allowed)
			(copperpour not_allowed)
			(footprints allowed)
		)
		(placement
			(enabled no)
			(sheetname "")
		)
		(fill yes
			(thermal_gap 0.5)
			(thermal_bridge_width 0.5)
			(island_removal_mode 0)
		)
		(polygon
			(pts
				(arc
					(start 277.522432 -283.185108)
					(mid 276.862032 -283.185108)
					(end 277.522432 -283.185108)
				)
			)
		)
	)
	(zone
		(layers "In1.Cu" "In2.Cu")
		(hatch none 0.5)
		(connect_pads
			(clearance 0)
		)
		(min_thickness 0.25)
		(keepout
			(tracks not_allowed)
			(vias allowed)
			(pads allowed)
			(copperpour not_allowed)
			(footprints allowed)
		)
		(placement
			(enabled no)
			(sheetname "")
		)
		(fill yes
			(thermal_gap 0.5)
			(thermal_bridge_width 0.5)
			(island_removal_mode 0)
		)
		(polygon
			(pts
				(arc
					(start 431.88636 -206.685134)
					(mid 431.22596 -206.685134)
					(end 431.88636 -206.685134)
				)
			)
		)
	)
	(zone
		(layers "In1.Cu" "In2.Cu")
		(hatch none 0.5)
		(connect_pads
			(clearance 0)
		)
		(min_thickness 0.25)
		(keepout
			(tracks not_allowed)
			(vias allowed)
			(pads allowed)
			(copperpour not_allowed)
			(footprints allowed)
		)
		(placement
			(enabled no)
			(sheetname "")
		)
		(fill yes
			(thermal_gap 0.5)
			(thermal_bridge_width 0.5)
			(island_removal_mode 0)
		)
		(polygon
			(pts
				(arc
					(start 442.8744 -211.784946)
					(mid 442.214 -211.784946)
					(end 442.8744 -211.784946)
				)
			)
		)
	)
	(zone
		(layers "In1.Cu" "In2.Cu")
		(hatch none 0.5)
		(connect_pads
			(clearance 0)
		)
		(min_thickness 0.25)
		(keepout
			(tracks not_allowed)
			(vias allowed)
			(pads allowed)
			(copperpour not_allowed)
			(footprints allowed)
		)
		(placement
			(enabled no)
			(sheetname "")
		)
		(fill yes
			(thermal_gap 0.5)
			(thermal_bridge_width 0.5)
			(island_removal_mode 0)
		)
		(polygon
			(pts
				(arc
					(start 280.966164 -210.935062)
					(mid 280.305764 -210.935062)
					(end 280.966164 -210.935062)
				)
			)
		)
	)
	(zone
		(layers "In1.Cu" "In2.Cu")
		(hatch none 0.5)
		(connect_pads
			(clearance 0)
		)
		(min_thickness 0.25)
		(keepout
			(tracks not_allowed)
			(vias allowed)
			(pads allowed)
			(copperpour not_allowed)
			(footprints allowed)
		)
		(placement
			(enabled no)
			(sheetname "")
		)
		(fill yes
			(thermal_gap 0.5)
			(thermal_bridge_width 0.5)
			(island_removal_mode 0)
		)
		(polygon
			(pts
				(arc
					(start 435.330346 -318.035178)
					(mid 434.669946 -318.035178)
					(end 435.330346 -318.035178)
				)
			)
		)
	)
	(zone
		(layers "In1.Cu" "In2.Cu")
		(hatch none 0.5)
		(connect_pads
			(clearance 0)
		)
		(min_thickness 0.25)
		(keepout
			(tracks not_allowed)
			(vias allowed)
			(pads allowed)
			(copperpour not_allowed)
			(footprints allowed)
		)
		(placement
			(enabled no)
			(sheetname "")
		)
		(fill yes
			(thermal_gap 0.5)
			(thermal_bridge_width 0.5)
			(island_removal_mode 0)
		)
		(polygon
			(pts
				(arc
					(start 52.214272 -315.485272)
					(mid 51.553872 -315.485272)
					(end 52.214272 -315.485272)
				)
			)
		)
	)
	(zone
		(layers "In1.Cu" "In2.Cu")
		(hatch none 0.5)
		(connect_pads
			(clearance 0)
		)
		(min_thickness 0.25)
		(keepout
			(tracks not_allowed)
			(vias allowed)
			(pads allowed)
			(copperpour not_allowed)
			(footprints allowed)
		)
		(placement
			(enabled no)
			(sheetname "")
		)
		(fill yes
			(thermal_gap 0.5)
			(thermal_bridge_width 0.5)
			(island_removal_mode 0)
		)
		(polygon
			(pts
				(arc
					(start 454.518268 -287.435036)
					(mid 453.857868 -287.435036)
					(end 454.518268 -287.435036)
				)
			)
		)
	)
	(zone
		(layers "In1.Cu" "In2.Cu")
		(hatch none 0.5)
		(connect_pads
			(clearance 0)
		)
		(min_thickness 0.25)
		(keepout
			(tracks not_allowed)
			(vias allowed)
			(pads allowed)
			(copperpour not_allowed)
			(footprints allowed)
		)
		(placement
			(enabled no)
			(sheetname "")
		)
		(fill yes
			(thermal_gap 0.5)
			(thermal_bridge_width 0.5)
			(island_removal_mode 0)
		)
		(polygon
			(pts
				(arc
					(start 446.974468 -219.435172)
					(mid 446.314068 -219.435172)
					(end 446.974468 -219.435172)
				)
			)
		)
	)
	(zone
		(layers "In1.Cu" "In2.Cu")
		(hatch none 0.5)
		(connect_pads
			(clearance 0)
		)
		(min_thickness 0.25)
		(keepout
			(tracks not_allowed)
			(vias allowed)
			(pads allowed)
			(copperpour not_allowed)
			(footprints allowed)
		)
		(placement
			(enabled no)
			(sheetname "")
		)
		(fill yes
			(thermal_gap 0.5)
			(thermal_bridge_width 0.5)
			(island_removal_mode 0)
		)
		(polygon
			(pts
				(arc
					(start 187.390278 -285.735268)
					(mid 186.729878 -285.735268)
					(end 187.390278 -285.735268)
				)
			)
		)
	)
	(zone
		(layers "In1.Cu" "In2.Cu")
		(hatch none 0.5)
		(connect_pads
			(clearance 0)
		)
		(min_thickness 0.25)
		(keepout
			(tracks not_allowed)
			(vias allowed)
			(pads allowed)
			(copperpour not_allowed)
			(footprints allowed)
		)
		(placement
			(enabled no)
			(sheetname "")
		)
		(fill yes
			(thermal_gap 0.5)
			(thermal_bridge_width 0.5)
			(island_removal_mode 0)
		)
		(polygon
			(pts
				(arc
					(start 269.978378 -249.185176)
					(mid 269.317978 -249.185176)
					(end 269.978378 -249.185176)
				)
			)
		)
	)
	(zone
		(layers "In1.Cu" "In2.Cu")
		(hatch none 0.5)
		(connect_pads
			(clearance 0)
		)
		(min_thickness 0.25)
		(keepout
			(tracks not_allowed)
			(vias allowed)
			(pads allowed)
			(copperpour not_allowed)
			(footprints allowed)
		)
		(placement
			(enabled no)
			(sheetname "")
		)
		(fill yes
			(thermal_gap 0.5)
			(thermal_bridge_width 0.5)
			(island_removal_mode 0)
		)
		(polygon
			(pts
				(arc
					(start 172.30217 -241.535204)
					(mid 171.64177 -241.535204)
					(end 172.30217 -241.535204)
				)
			)
		)
	)
	(zone
		(layers "In1.Cu" "In2.Cu")
		(hatch none 0.5)
		(connect_pads
			(clearance 0)
		)
		(min_thickness 0.25)
		(keepout
			(tracks not_allowed)
			(vias allowed)
			(pads allowed)
			(copperpour not_allowed)
			(footprints allowed)
		)
		(placement
			(enabled no)
			(sheetname "")
		)
		(fill yes
			(thermal_gap 0.5)
			(thermal_bridge_width 0.5)
			(island_removal_mode 0)
		)
		(polygon
			(pts
				(arc
					(start 191.490346 -208.38541)
					(mid 190.829946 -208.38541)
					(end 191.490346 -208.38541)
				)
			)
		)
	)
	(zone
		(layers "In1.Cu" "In2.Cu")
		(hatch none 0.5)
		(connect_pads
			(clearance 0)
		)
		(min_thickness 0.25)
		(keepout
			(tracks not_allowed)
			(vias allowed)
			(pads allowed)
			(copperpour not_allowed)
			(footprints allowed)
		)
		(placement
			(enabled no)
			(sheetname "")
		)
		(fill yes
			(thermal_gap 0.5)
			(thermal_bridge_width 0.5)
			(island_removal_mode 0)
		)
		(polygon
			(pts
				(arc
					(start 183.946292 -201.585322)
					(mid 183.285892 -201.585322)
					(end 183.946292 -201.585322)
				)
			)
		)
	)
	(zone
		(layers "In1.Cu" "In2.Cu")
		(hatch none 0.5)
		(connect_pads
			(clearance 0)
		)
		(min_thickness 0.25)
		(keepout
			(tracks not_allowed)
			(vias allowed)
			(pads allowed)
			(copperpour not_allowed)
			(footprints allowed)
		)
		(placement
			(enabled no)
			(sheetname "")
		)
		(fill yes
			(thermal_gap 0.5)
			(thermal_bridge_width 0.5)
			(island_removal_mode 0)
		)
		(polygon
			(pts
				(arc
					(start 439.430414 -315.485018)
					(mid 438.770014 -315.485018)
					(end 439.430414 -315.485018)
				)
			)
		)
	)
	(zone
		(layers "In1.Cu" "In2.Cu")
		(hatch none 0.5)
		(connect_pads
			(clearance 0)
		)
		(min_thickness 0.25)
		(keepout
			(tracks not_allowed)
			(vias allowed)
			(pads allowed)
			(copperpour not_allowed)
			(footprints allowed)
		)
		(placement
			(enabled no)
			(sheetname "")
		)
		(fill yes
			(thermal_gap 0.5)
			(thermal_bridge_width 0.5)
			(island_removal_mode 0)
		)
		(polygon
			(pts
				(arc
					(start 365.660686 -385.11861)
					(mid 365.65145 -385.138534)
					(end 365.64824 -385.160266)
				)
				(arc
					(start 365.64824 -385.35483)
					(mid 365.670558 -385.408712)
					(end 365.72444 -385.43103)
				)
				(arc
					(start 366.41024 -385.43103)
					(mid 366.464122 -385.408712)
					(end 366.48644 -385.35483)
				)
				(arc
					(start 366.48644 -385.160266)
					(mid 366.483272 -385.138522)
					(end 366.473994 -385.11861)
				)
				(arc
					(start 366.281208 -384.822446)
					(mid 366.268986 -384.780762)
					(end 366.281462 -384.739134)
				)
				(arc
					(start 366.473994 -384.44551)
					(mid 366.48323 -384.425586)
					(end 366.48644 -384.403854)
				)
				(arc
					(start 366.48644 -384.20929)
					(mid 366.464122 -384.155408)
					(end 366.41024 -384.13309)
				)
				(arc
					(start 365.72444 -384.13309)
					(mid 365.670558 -384.155408)
					(end 365.64824 -384.20929)
				)
				(arc
					(start 365.64824 -384.405124)
					(mid 365.651408 -384.426868)
					(end 365.660686 -384.44678)
				)
				(arc
					(start 365.853218 -384.740404)
					(mid 365.86562 -384.78206)
					(end 365.853218 -384.823716)
				)
			)
		)
	)
	(zone
		(layers "In1.Cu" "In2.Cu")
		(hatch none 0.5)
		(connect_pads
			(clearance 0)
		)
		(min_thickness 0.25)
		(keepout
			(tracks not_allowed)
			(vias allowed)
			(pads allowed)
			(copperpour not_allowed)
			(footprints allowed)
		)
		(placement
			(enabled no)
			(sheetname "")
		)
		(fill yes
			(thermal_gap 0.5)
			(thermal_bridge_width 0.5)
			(island_removal_mode 0)
		)
		(polygon
			(pts
				(arc
					(start 454.518268 -217.73515)
					(mid 453.857868 -217.73515)
					(end 454.518268 -217.73515)
				)
			)
		)
	)
	(zone
		(layers "In1.Cu" "In2.Cu")
		(hatch none 0.5)
		(connect_pads
			(clearance 0)
		)
		(min_thickness 0.25)
		(keepout
			(tracks not_allowed)
			(vias allowed)
			(pads allowed)
			(copperpour not_allowed)
			(footprints allowed)
		)
		(placement
			(enabled no)
			(sheetname "")
		)
		(fill yes
			(thermal_gap 0.5)
			(thermal_bridge_width 0.5)
			(island_removal_mode 0)
		)
		(polygon
			(pts
				(arc
					(start 407.141426 -11.91768)
					(mid 407.119108 -11.971562)
					(end 407.065226 -11.99388)
				)
				(arc
					(start 406.028652 -11.99388)
					(mid 405.97477 -11.971562)
					(end 405.952452 -11.91768)
				)
				(arc
					(start 405.952452 -10.51814)
					(mid 405.97477 -10.464258)
					(end 406.028652 -10.44194)
				)
				(arc
					(start 407.065226 -10.44194)
					(mid 407.119108 -10.464258)
					(end 407.141426 -10.51814)
				)
			)
		)
	)
	(zone
		(layers "In1.Cu" "In2.Cu")
		(hatch none 0.5)
		(connect_pads
			(clearance 0)
		)
		(min_thickness 0.25)
		(keepout
			(tracks not_allowed)
			(vias allowed)
			(pads allowed)
			(copperpour not_allowed)
			(footprints allowed)
		)
		(placement
			(enabled no)
			(sheetname "")
		)
		(fill yes
			(thermal_gap 0.5)
			(thermal_bridge_width 0.5)
			(island_removal_mode 0)
		)
		(polygon
			(pts
				(arc
					(start 187.390278 -278.935434)
					(mid 186.729878 -278.935434)
					(end 187.390278 -278.935434)
				)
			)
		)
	)
	(zone
		(layers "In1.Cu" "In2.Cu")
		(hatch none 0.5)
		(connect_pads
			(clearance 0)
		)
		(min_thickness 0.25)
		(keepout
			(tracks not_allowed)
			(vias allowed)
			(pads allowed)
			(copperpour not_allowed)
			(footprints allowed)
		)
		(placement
			(enabled no)
			(sheetname "")
		)
		(fill yes
			(thermal_gap 0.5)
			(thermal_bridge_width 0.5)
			(island_removal_mode 0)
		)
		(polygon
			(pts
				(arc
					(start 48.114204 -202.435206)
					(mid 47.453804 -202.435206)
					(end 48.114204 -202.435206)
				)
			)
		)
	)
	(zone
		(layers "In1.Cu" "In2.Cu")
		(hatch none 0.5)
		(connect_pads
			(clearance 0)
		)
		(min_thickness 0.25)
		(keepout
			(tracks not_allowed)
			(vias allowed)
			(pads allowed)
			(copperpour not_allowed)
			(footprints allowed)
		)
		(placement
			(enabled no)
			(sheetname "")
		)
		(fill yes
			(thermal_gap 0.5)
			(thermal_bridge_width 0.5)
			(island_removal_mode 0)
		)
		(polygon
			(pts
				(arc
					(start 300.15434 -300.185074)
					(mid 299.49394 -300.185074)
					(end 300.15434 -300.185074)
				)
			)
		)
	)
	(zone
		(layers "In1.Cu" "In2.Cu")
		(hatch none 0.5)
		(connect_pads
			(clearance 0)
		)
		(min_thickness 0.25)
		(keepout
			(tracks not_allowed)
			(vias allowed)
			(pads allowed)
			(copperpour not_allowed)
			(footprints allowed)
		)
		(placement
			(enabled no)
			(sheetname "")
		)
		(fill yes
			(thermal_gap 0.5)
			(thermal_bridge_width 0.5)
			(island_removal_mode 0)
		)
		(polygon
			(pts
				(arc
					(start 194.934332 -227.935282)
					(mid 194.273932 -227.935282)
					(end 194.934332 -227.935282)
				)
			)
		)
	)
	(zone
		(layers "In1.Cu" "In2.Cu")
		(hatch none 0.5)
		(connect_pads
			(clearance 0)
		)
		(min_thickness 0.25)
		(keepout
			(tracks not_allowed)
			(vias allowed)
			(pads allowed)
			(copperpour not_allowed)
			(footprints allowed)
		)
		(placement
			(enabled no)
			(sheetname "")
		)
		(fill yes
			(thermal_gap 0.5)
			(thermal_bridge_width 0.5)
			(island_removal_mode 0)
		)
		(polygon
			(pts
				(arc
					(start 431.88636 -267.885164)
					(mid 431.22596 -267.885164)
					(end 431.88636 -267.885164)
				)
			)
		)
	)
	(zone
		(layers "In1.Cu" "In2.Cu")
		(hatch none 0.5)
		(connect_pads
			(clearance 0)
		)
		(min_thickness 0.25)
		(keepout
			(tracks not_allowed)
			(vias allowed)
			(pads allowed)
			(copperpour not_allowed)
			(footprints allowed)
		)
		(placement
			(enabled no)
			(sheetname "")
		)
		(fill yes
			(thermal_gap 0.5)
			(thermal_bridge_width 0.5)
			(island_removal_mode 0)
		)
		(polygon
			(pts
				(arc
					(start 29.582364 -262.785352)
					(mid 28.921964 -262.785352)
					(end 29.582364 -262.785352)
				)
			)
		)
	)
	(zone
		(layers "In1.Cu" "In2.Cu")
		(hatch none 0.5)
		(connect_pads
			(clearance 0)
		)
		(min_thickness 0.25)
		(keepout
			(tracks not_allowed)
			(vias allowed)
			(pads allowed)
			(copperpour not_allowed)
			(footprints allowed)
		)
		(placement
			(enabled no)
			(sheetname "")
		)
		(fill yes
			(thermal_gap 0.5)
			(thermal_bridge_width 0.5)
			(island_removal_mode 0)
		)
		(polygon
			(pts
				(arc
					(start 18.218404 -423.80535)
					(mid 18.233283 -423.769429)
					(end 18.269204 -423.75455)
				)
				(arc
					(start 18.777204 -423.75455)
					(mid 18.813125 -423.769429)
					(end 18.828004 -423.80535)
				)
				(arc
					(start 18.828004 -424.461686)
					(mid 18.813125 -424.497607)
					(end 18.777204 -424.512486)
				)
				(arc
					(start 18.269204 -424.512486)
					(mid 18.233283 -424.497607)
					(end 18.218404 -424.461686)
				)
			)
		)
	)
	(zone
		(layers "In1.Cu" "In2.Cu")
		(hatch none 0.5)
		(connect_pads
			(clearance 0)
		)
		(min_thickness 0.25)
		(keepout
			(tracks not_allowed)
			(vias allowed)
			(pads allowed)
			(copperpour not_allowed)
			(footprints allowed)
		)
		(placement
			(enabled no)
			(sheetname "")
		)
		(fill yes
			(thermal_gap 0.5)
			(thermal_bridge_width 0.5)
			(island_removal_mode 0)
		)
		(polygon
			(pts
				(arc
					(start 280.966164 -278.93518)
					(mid 280.305764 -278.93518)
					(end 280.966164 -278.93518)
				)
			)
		)
	)
	(zone
		(layers "In1.Cu" "In2.Cu")
		(hatch none 0.5)
		(connect_pads
			(clearance 0)
		)
		(min_thickness 0.25)
		(keepout
			(tracks not_allowed)
			(vias allowed)
			(pads allowed)
			(copperpour not_allowed)
			(footprints allowed)
		)
		(placement
			(enabled no)
			(sheetname "")
		)
		(fill yes
			(thermal_gap 0.5)
			(thermal_bridge_width 0.5)
			(island_removal_mode 0)
		)
		(polygon
			(pts
				(arc
					(start 292.610286 -313.784996)
					(mid 291.949886 -313.784996)
					(end 292.610286 -313.784996)
				)
			)
		)
	)
	(zone
		(layers "In1.Cu" "In2.Cu")
		(hatch none 0.5)
		(connect_pads
			(clearance 0)
		)
		(min_thickness 0.25)
		(keepout
			(tracks not_allowed)
			(vias allowed)
			(pads allowed)
			(copperpour not_allowed)
			(footprints allowed)
		)
		(placement
			(enabled no)
			(sheetname "")
		)
		(fill yes
			(thermal_gap 0.5)
			(thermal_bridge_width 0.5)
			(island_removal_mode 0)
		)
		(polygon
			(pts
				(arc
					(start 413.562292 -417.242244)
					(mid 413.58461 -417.296126)
					(end 413.638492 -417.318444)
				)
				(arc
					(start 413.834072 -417.318444)
					(mid 413.855948 -417.315312)
					(end 413.875982 -417.305998)
				)
				(arc
					(start 414.169606 -417.113466)
					(mid 414.211262 -417.101064)
					(end 414.252918 -417.113466)
				)
				(arc
					(start 414.547812 -417.305998)
					(mid 414.567736 -417.315234)
					(end 414.589468 -417.318444)
				)
				(arc
					(start 414.784032 -417.318444)
					(mid 414.837914 -417.296126)
					(end 414.860232 -417.242244)
				)
				(arc
					(start 414.860232 -416.556444)
					(mid 414.837914 -416.502562)
					(end 414.784032 -416.480244)
				)
				(arc
					(start 414.589468 -416.480244)
					(mid 414.567724 -416.483412)
					(end 414.547812 -416.49269)
				)
				(arc
					(start 414.251648 -416.685476)
					(mid 414.209964 -416.697698)
					(end 414.168336 -416.685222)
				)
				(arc
					(start 413.874712 -416.49269)
					(mid 413.854788 -416.483454)
					(end 413.833056 -416.480244)
				)
				(arc
					(start 413.638492 -416.480244)
					(mid 413.58461 -416.502562)
					(end 413.562292 -416.556444)
				)
			)
		)
	)
	(zone
		(layers "In1.Cu" "In2.Cu")
		(hatch none 0.5)
		(connect_pads
			(clearance 0)
		)
		(min_thickness 0.25)
		(keepout
			(tracks not_allowed)
			(vias allowed)
			(pads allowed)
			(copperpour not_allowed)
			(footprints allowed)
		)
		(placement
			(enabled no)
			(sheetname "")
		)
		(fill yes
			(thermal_gap 0.5)
			(thermal_bridge_width 0.5)
			(island_removal_mode 0)
		)
		(polygon
			(pts
				(arc
					(start 446.974468 -275.535136)
					(mid 446.314068 -275.535136)
					(end 446.974468 -275.535136)
				)
			)
		)
	)
	(zone
		(layers "In1.Cu" "In2.Cu")
		(hatch none 0.5)
		(connect_pads
			(clearance 0)
		)
		(min_thickness 0.25)
		(keepout
			(tracks not_allowed)
			(vias allowed)
			(pads allowed)
			(copperpour not_allowed)
			(footprints allowed)
		)
		(placement
			(enabled no)
			(sheetname "")
		)
		(fill yes
			(thermal_gap 0.5)
			(thermal_bridge_width 0.5)
			(island_removal_mode 0)
		)
		(polygon
			(pts
				(arc
					(start 199.0344 -200.735438)
					(mid 198.374 -200.735438)
					(end 199.0344 -200.735438)
				)
			)
		)
	)
	(zone
		(layers "In1.Cu" "In2.Cu")
		(hatch none 0.5)
		(connect_pads
			(clearance 0)
		)
		(min_thickness 0.25)
		(keepout
			(tracks not_allowed)
			(vias allowed)
			(pads allowed)
			(copperpour not_allowed)
			(footprints allowed)
		)
		(placement
			(enabled no)
			(sheetname "")
		)
		(fill yes
			(thermal_gap 0.5)
			(thermal_bridge_width 0.5)
			(island_removal_mode 0)
		)
		(polygon
			(pts
				(arc
					(start 288.510218 -221.13494)
					(mid 287.849818 -221.13494)
					(end 288.510218 -221.13494)
				)
			)
		)
	)
	(zone
		(layers "In1.Cu" "In2.Cu")
		(hatch none 0.5)
		(connect_pads
			(clearance 0)
		)
		(min_thickness 0.25)
		(keepout
			(tracks not_allowed)
			(vias allowed)
			(pads allowed)
			(copperpour not_allowed)
			(footprints allowed)
		)
		(placement
			(enabled no)
			(sheetname "")
		)
		(fill yes
			(thermal_gap 0.5)
			(thermal_bridge_width 0.5)
			(island_removal_mode 0)
		)
		(polygon
			(pts
				(arc
					(start 172.30217 -291.685218)
					(mid 171.64177 -291.685218)
					(end 172.30217 -291.685218)
				)
			)
		)
	)
	(zone
		(layers "In1.Cu" "In2.Cu")
		(hatch none 0.5)
		(connect_pads
			(clearance 0)
		)
		(min_thickness 0.25)
		(keepout
			(tracks not_allowed)
			(vias allowed)
			(pads allowed)
			(copperpour not_allowed)
			(footprints allowed)
		)
		(placement
			(enabled no)
			(sheetname "")
		)
		(fill yes
			(thermal_gap 0.5)
			(thermal_bridge_width 0.5)
			(island_removal_mode 0)
		)
		(polygon
			(pts
				(arc
					(start 44.670218 -206.685388)
					(mid 44.009818 -206.685388)
					(end 44.670218 -206.685388)
				)
			)
		)
	)
	(zone
		(layers "In1.Cu" "In2.Cu")
		(hatch none 0.5)
		(connect_pads
			(clearance 0)
		)
		(min_thickness 0.25)
		(keepout
			(tracks not_allowed)
			(vias allowed)
			(pads allowed)
			(copperpour not_allowed)
			(footprints allowed)
		)
		(placement
			(enabled no)
			(sheetname "")
		)
		(fill yes
			(thermal_gap 0.5)
			(thermal_bridge_width 0.5)
			(island_removal_mode 0)
		)
		(polygon
			(pts
				(arc
					(start 199.0344 -295.085262)
					(mid 198.374 -295.085262)
					(end 199.0344 -295.085262)
				)
			)
		)
	)
	(zone
		(layers "In1.Cu" "In2.Cu")
		(hatch none 0.5)
		(connect_pads
			(clearance 0)
		)
		(min_thickness 0.25)
		(keepout
			(tracks not_allowed)
			(vias allowed)
			(pads allowed)
			(copperpour not_allowed)
			(footprints allowed)
		)
		(placement
			(enabled no)
			(sheetname "")
		)
		(fill yes
			(thermal_gap 0.5)
			(thermal_bridge_width 0.5)
			(island_removal_mode 0)
		)
		(polygon
			(pts
				(arc
					(start 37.126164 -273.835368)
					(mid 36.465764 -273.835368)
					(end 37.126164 -273.835368)
				)
			)
		)
	)
	(zone
		(layers "In1.Cu" "In2.Cu")
		(hatch none 0.5)
		(connect_pads
			(clearance 0)
		)
		(min_thickness 0.25)
		(keepout
			(tracks not_allowed)
			(vias allowed)
			(pads allowed)
			(copperpour not_allowed)
			(footprints allowed)
		)
		(placement
			(enabled no)
			(sheetname "")
		)
		(fill yes
			(thermal_gap 0.5)
			(thermal_bridge_width 0.5)
			(island_removal_mode 0)
		)
		(polygon
			(pts
				(arc
					(start 296.054272 -218.585034)
					(mid 295.393872 -218.585034)
					(end 296.054272 -218.585034)
				)
			)
		)
	)
	(zone
		(layers "In1.Cu" "In2.Cu")
		(hatch none 0.5)
		(connect_pads
			(clearance 0)
		)
		(min_thickness 0.25)
		(keepout
			(tracks not_allowed)
			(vias allowed)
			(pads allowed)
			(copperpour not_allowed)
			(footprints allowed)
		)
		(placement
			(enabled no)
			(sheetname "")
		)
		(fill yes
			(thermal_gap 0.5)
			(thermal_bridge_width 0.5)
			(island_removal_mode 0)
		)
		(polygon
			(pts
				(arc
					(start 25.482296 -204.135228)
					(mid 24.821896 -204.135228)
					(end 25.482296 -204.135228)
				)
			)
		)
	)
	(zone
		(layers "In1.Cu" "In2.Cu")
		(hatch none 0.5)
		(connect_pads
			(clearance 0)
		)
		(min_thickness 0.25)
		(keepout
			(tracks not_allowed)
			(vias allowed)
			(pads allowed)
			(copperpour not_allowed)
			(footprints allowed)
		)
		(placement
			(enabled no)
			(sheetname "")
		)
		(fill yes
			(thermal_gap 0.5)
			(thermal_bridge_width 0.5)
			(island_removal_mode 0)
		)
		(polygon
			(pts
				(arc
					(start 431.88636 -311.23509)
					(mid 431.22596 -311.23509)
					(end 431.88636 -311.23509)
				)
			)
		)
	)
	(zone
		(layers "In1.Cu" "In2.Cu")
		(hatch none 0.5)
		(connect_pads
			(clearance 0)
		)
		(min_thickness 0.25)
		(keepout
			(tracks not_allowed)
			(vias allowed)
			(pads allowed)
			(copperpour not_allowed)
			(footprints allowed)
		)
		(placement
			(enabled no)
			(sheetname "")
		)
		(fill yes
			(thermal_gap 0.5)
			(thermal_bridge_width 0.5)
			(island_removal_mode 0)
		)
		(polygon
			(pts
				(arc
					(start 48.114204 -224.535238)
					(mid 47.453804 -224.535238)
					(end 48.114204 -224.535238)
				)
			)
		)
	)
	(zone
		(layers "In1.Cu" "In2.Cu")
		(hatch none 0.5)
		(connect_pads
			(clearance 0)
		)
		(min_thickness 0.25)
		(keepout
			(tracks not_allowed)
			(vias allowed)
			(pads allowed)
			(copperpour not_allowed)
			(footprints allowed)
		)
		(placement
			(enabled no)
			(sheetname "")
		)
		(fill yes
			(thermal_gap 0.5)
			(thermal_bridge_width 0.5)
			(island_removal_mode 0)
		)
		(polygon
			(pts
				(arc
					(start 33.026096 -239.835436)
					(mid 32.365696 -239.835436)
					(end 33.026096 -239.835436)
				)
			)
		)
	)
	(zone
		(layers "In1.Cu" "In2.Cu")
		(hatch none 0.5)
		(connect_pads
			(clearance 0)
		)
		(min_thickness 0.25)
		(keepout
			(tracks not_allowed)
			(vias allowed)
			(pads allowed)
			(copperpour not_allowed)
			(footprints allowed)
		)
		(placement
			(enabled no)
			(sheetname "")
		)
		(fill yes
			(thermal_gap 0.5)
			(thermal_bridge_width 0.5)
			(island_removal_mode 0)
		)
		(polygon
			(pts
				(arc
					(start 179.846224 -289.98545)
					(mid 179.185824 -289.98545)
					(end 179.846224 -289.98545)
				)
			)
		)
	)
	(zone
		(layers "In1.Cu" "In2.Cu")
		(hatch none 0.5)
		(connect_pads
			(clearance 0)
		)
		(min_thickness 0.25)
		(keepout
			(tracks not_allowed)
			(vias allowed)
			(pads allowed)
			(copperpour not_allowed)
			(footprints allowed)
		)
		(placement
			(enabled no)
			(sheetname "")
		)
		(fill yes
			(thermal_gap 0.5)
			(thermal_bridge_width 0.5)
			(island_removal_mode 0)
		)
		(polygon
			(pts
				(arc
					(start 191.490346 -210.085432)
					(mid 190.829946 -210.085432)
					(end 191.490346 -210.085432)
				)
			)
		)
	)
	(zone
		(layers "In1.Cu" "In2.Cu")
		(hatch none 0.5)
		(connect_pads
			(clearance 0)
		)
		(min_thickness 0.25)
		(keepout
			(tracks not_allowed)
			(vias allowed)
			(pads allowed)
			(copperpour not_allowed)
			(footprints allowed)
		)
		(placement
			(enabled no)
			(sheetname "")
		)
		(fill yes
			(thermal_gap 0.5)
			(thermal_bridge_width 0.5)
			(island_removal_mode 0)
		)
		(polygon
			(pts
				(arc
					(start 183.946292 -214.33536)
					(mid 183.285892 -214.33536)
					(end 183.946292 -214.33536)
				)
			)
		)
	)
	(zone
		(layers "In1.Cu" "In2.Cu")
		(hatch none 0.5)
		(connect_pads
			(clearance 0)
		)
		(min_thickness 0.25)
		(keepout
			(tracks not_allowed)
			(vias allowed)
			(pads allowed)
			(copperpour not_allowed)
			(footprints allowed)
		)
		(placement
			(enabled no)
			(sheetname "")
		)
		(fill yes
			(thermal_gap 0.5)
			(thermal_bridge_width 0.5)
			(island_removal_mode 0)
		)
		(polygon
			(pts
				(arc
					(start 273.422364 -215.18499)
					(mid 272.761964 -215.18499)
					(end 273.422364 -215.18499)
				)
			)
		)
	)
	(zone
		(layers "In1.Cu" "In2.Cu")
		(hatch none 0.5)
		(connect_pads
			(clearance 0)
		)
		(min_thickness 0.25)
		(keepout
			(tracks not_allowed)
			(vias allowed)
			(pads allowed)
			(copperpour not_allowed)
			(footprints allowed)
		)
		(placement
			(enabled no)
			(sheetname "")
		)
		(fill yes
			(thermal_gap 0.5)
			(thermal_bridge_width 0.5)
			(island_removal_mode 0)
		)
		(polygon
			(pts
				(arc
					(start 420.242238 -286.585152)
					(mid 419.581838 -286.585152)
					(end 420.242238 -286.585152)
				)
			)
		)
	)
	(zone
		(layers "In1.Cu" "In2.Cu")
		(hatch none 0.5)
		(connect_pads
			(clearance 0)
		)
		(min_thickness 0.25)
		(keepout
			(tracks not_allowed)
			(vias allowed)
			(pads allowed)
			(copperpour not_allowed)
			(footprints allowed)
		)
		(placement
			(enabled no)
			(sheetname "")
		)
		(fill yes
			(thermal_gap 0.5)
			(thermal_bridge_width 0.5)
			(island_removal_mode 0)
		)
		(polygon
			(pts
				(arc
					(start 179.846224 -246.63527)
					(mid 179.185824 -246.63527)
					(end 179.846224 -246.63527)
				)
			)
		)
	)
	(zone
		(layers "In1.Cu" "In2.Cu")
		(hatch none 0.5)
		(connect_pads
			(clearance 0)
		)
		(min_thickness 0.25)
		(keepout
			(tracks not_allowed)
			(vias allowed)
			(pads allowed)
			(copperpour not_allowed)
			(footprints allowed)
		)
		(placement
			(enabled no)
			(sheetname "")
		)
		(fill yes
			(thermal_gap 0.5)
			(thermal_bridge_width 0.5)
			(island_removal_mode 0)
		)
		(polygon
			(pts
				(arc
					(start 202.478132 -207.535272)
					(mid 201.817732 -207.535272)
					(end 202.478132 -207.535272)
				)
			)
		)
	)
	(zone
		(layers "In1.Cu" "In2.Cu")
		(hatch none 0.5)
		(connect_pads
			(clearance 0)
		)
		(min_thickness 0.25)
		(keepout
			(tracks not_allowed)
			(vias allowed)
			(pads allowed)
			(copperpour not_allowed)
			(footprints allowed)
		)
		(placement
			(enabled no)
			(sheetname "")
		)
		(fill yes
			(thermal_gap 0.5)
			(thermal_bridge_width 0.5)
			(island_removal_mode 0)
		)
		(polygon
			(pts
				(arc
					(start 183.946292 -317.185294)
					(mid 183.285892 -317.185294)
					(end 183.946292 -317.185294)
				)
			)
		)
	)
	(zone
		(layers "In1.Cu" "In2.Cu")
		(hatch none 0.5)
		(connect_pads
			(clearance 0)
		)
		(min_thickness 0.25)
		(keepout
			(tracks not_allowed)
			(vias allowed)
			(pads allowed)
			(copperpour not_allowed)
			(footprints allowed)
		)
		(placement
			(enabled no)
			(sheetname "")
		)
		(fill yes
			(thermal_gap 0.5)
			(thermal_bridge_width 0.5)
			(island_removal_mode 0)
		)
		(polygon
			(pts
				(arc
					(start 52.214272 -210.085432)
					(mid 51.553872 -210.085432)
					(end 52.214272 -210.085432)
				)
			)
		)
	)
	(zone
		(layers "In1.Cu" "In2.Cu")
		(hatch none 0.5)
		(connect_pads
			(clearance 0)
		)
		(min_thickness 0.25)
		(keepout
			(tracks not_allowed)
			(vias allowed)
			(pads allowed)
			(copperpour not_allowed)
			(footprints allowed)
		)
		(placement
			(enabled no)
			(sheetname "")
		)
		(fill yes
			(thermal_gap 0.5)
			(thermal_bridge_width 0.5)
			(island_removal_mode 0)
		)
		(polygon
			(pts
				(arc
					(start 300.15434 -290.83508)
					(mid 299.49394 -290.83508)
					(end 300.15434 -290.83508)
				)
			)
		)
	)
	(zone
		(layers "In1.Cu" "In2.Cu")
		(hatch none 0.5)
		(connect_pads
			(clearance 0)
		)
		(min_thickness 0.25)
		(keepout
			(tracks not_allowed)
			(vias allowed)
			(pads allowed)
			(copperpour not_allowed)
			(footprints allowed)
		)
		(placement
			(enabled no)
			(sheetname "")
		)
		(fill yes
			(thermal_gap 0.5)
			(thermal_bridge_width 0.5)
			(island_removal_mode 0)
		)
		(polygon
			(pts
				(arc
					(start 292.610286 -303.585118)
					(mid 291.949886 -303.585118)
					(end 292.610286 -303.585118)
				)
			)
		)
	)
	(zone
		(layers "In1.Cu" "In2.Cu")
		(hatch none 0.5)
		(connect_pads
			(clearance 0)
		)
		(min_thickness 0.25)
		(keepout
			(tracks not_allowed)
			(vias allowed)
			(pads allowed)
			(copperpour not_allowed)
			(footprints allowed)
		)
		(placement
			(enabled no)
			(sheetname "")
		)
		(fill yes
			(thermal_gap 0.5)
			(thermal_bridge_width 0.5)
			(island_removal_mode 0)
		)
		(polygon
			(pts
				(arc
					(start 300.15434 -261.085076)
					(mid 299.49394 -261.085076)
					(end 300.15434 -261.085076)
				)
			)
		)
	)
	(zone
		(layers "In1.Cu" "In2.Cu")
		(hatch none 0.5)
		(connect_pads
			(clearance 0)
		)
		(min_thickness 0.25)
		(keepout
			(tracks not_allowed)
			(vias allowed)
			(pads allowed)
			(copperpour not_allowed)
			(footprints allowed)
		)
		(placement
			(enabled no)
			(sheetname "")
		)
		(fill yes
			(thermal_gap 0.5)
			(thermal_bridge_width 0.5)
			(island_removal_mode 0)
		)
		(polygon
			(pts
				(arc
					(start 280.966164 -282.33497)
					(mid 280.305764 -282.33497)
					(end 280.966164 -282.33497)
				)
			)
		)
	)
	(zone
		(layers "In1.Cu" "In2.Cu")
		(hatch none 0.5)
		(connect_pads
			(clearance 0)
		)
		(min_thickness 0.25)
		(keepout
			(tracks not_allowed)
			(vias allowed)
			(pads allowed)
			(copperpour not_allowed)
			(footprints allowed)
		)
		(placement
			(enabled no)
			(sheetname "")
		)
		(fill yes
			(thermal_gap 0.5)
			(thermal_bridge_width 0.5)
			(island_removal_mode 0)
		)
		(polygon
			(pts
				(arc
					(start 424.342306 -313.784996)
					(mid 423.681906 -313.784996)
					(end 424.342306 -313.784996)
				)
			)
		)
	)
	(zone
		(layers "In1.Cu" "In2.Cu")
		(hatch none 0.5)
		(connect_pads
			(clearance 0)
		)
		(min_thickness 0.25)
		(keepout
			(tracks not_allowed)
			(vias allowed)
			(pads allowed)
			(copperpour not_allowed)
			(footprints allowed)
		)
		(placement
			(enabled no)
			(sheetname "")
		)
		(fill yes
			(thermal_gap 0.5)
			(thermal_bridge_width 0.5)
			(island_removal_mode 0)
		)
		(polygon
			(pts
				(arc
					(start 172.30217 -301.035212)
					(mid 171.64177 -301.035212)
					(end 172.30217 -301.035212)
				)
			)
		)
	)
	(zone
		(layers "In1.Cu" "In2.Cu")
		(hatch none 0.5)
		(connect_pads
			(clearance 0)
		)
		(min_thickness 0.25)
		(keepout
			(tracks not_allowed)
			(vias allowed)
			(pads allowed)
			(copperpour not_allowed)
			(footprints allowed)
		)
		(placement
			(enabled no)
			(sheetname "")
		)
		(fill yes
			(thermal_gap 0.5)
			(thermal_bridge_width 0.5)
			(island_removal_mode 0)
		)
		(polygon
			(pts
				(arc
					(start 22.03831 -245.785386)
					(mid 21.37791 -245.785386)
					(end 22.03831 -245.785386)
				)
			)
		)
	)
	(zone
		(layers "In1.Cu" "In2.Cu")
		(hatch none 0.5)
		(connect_pads
			(clearance 0)
		)
		(min_thickness 0.25)
		(keepout
			(tracks not_allowed)
			(vias allowed)
			(pads allowed)
			(copperpour not_allowed)
			(footprints allowed)
		)
		(placement
			(enabled no)
			(sheetname "")
		)
		(fill yes
			(thermal_gap 0.5)
			(thermal_bridge_width 0.5)
			(island_removal_mode 0)
		)
		(polygon
			(pts
				(arc
					(start 431.88636 -261.085076)
					(mid 431.22596 -261.085076)
					(end 431.88636 -261.085076)
				)
			)
		)
	)
	(zone
		(layers "In1.Cu" "In2.Cu")
		(hatch none 0.5)
		(connect_pads
			(clearance 0)
		)
		(min_thickness 0.25)
		(keepout
			(tracks not_allowed)
			(vias allowed)
			(pads allowed)
			(copperpour not_allowed)
			(footprints allowed)
		)
		(placement
			(enabled no)
			(sheetname "")
		)
		(fill yes
			(thermal_gap 0.5)
			(thermal_bridge_width 0.5)
			(island_removal_mode 0)
		)
		(polygon
			(pts
				(arc
					(start 176.402238 -275.53539)
					(mid 175.741838 -275.53539)
					(end 176.402238 -275.53539)
				)
			)
		)
	)
	(zone
		(layers "In1.Cu" "In2.Cu")
		(hatch none 0.5)
		(connect_pads
			(clearance 0)
		)
		(min_thickness 0.25)
		(keepout
			(tracks not_allowed)
			(vias allowed)
			(pads allowed)
			(copperpour not_allowed)
			(footprints allowed)
		)
		(placement
			(enabled no)
			(sheetname "")
		)
		(fill yes
			(thermal_gap 0.5)
			(thermal_bridge_width 0.5)
			(island_removal_mode 0)
		)
		(polygon
			(pts
				(arc
					(start 454.518268 -201.585068)
					(mid 453.857868 -201.585068)
					(end 454.518268 -201.585068)
				)
			)
		)
	)
	(zone
		(layers "In1.Cu" "In2.Cu")
		(hatch none 0.5)
		(connect_pads
			(clearance 0)
		)
		(min_thickness 0.25)
		(keepout
			(tracks not_allowed)
			(vias allowed)
			(pads allowed)
			(copperpour not_allowed)
			(footprints allowed)
		)
		(placement
			(enabled no)
			(sheetname "")
		)
		(fill yes
			(thermal_gap 0.5)
			(thermal_bridge_width 0.5)
			(island_removal_mode 0)
		)
		(polygon
			(pts
				(arc
					(start 25.482296 -274.685252)
					(mid 24.821896 -274.685252)
					(end 25.482296 -274.685252)
				)
			)
		)
	)
	(zone
		(layers "In1.Cu" "In2.Cu")
		(hatch none 0.5)
		(connect_pads
			(clearance 0)
		)
		(min_thickness 0.25)
		(keepout
			(tracks not_allowed)
			(vias allowed)
			(pads allowed)
			(copperpour not_allowed)
			(footprints allowed)
		)
		(placement
			(enabled no)
			(sheetname "")
		)
		(fill yes
			(thermal_gap 0.5)
			(thermal_bridge_width 0.5)
			(island_removal_mode 0)
		)
		(polygon
			(pts
				(arc
					(start 431.88636 -285.735014)
					(mid 431.22596 -285.735014)
					(end 431.88636 -285.735014)
				)
			)
		)
	)
	(zone
		(layers "In1.Cu" "In2.Cu")
		(hatch none 0.5)
		(connect_pads
			(clearance 0)
		)
		(min_thickness 0.25)
		(keepout
			(tracks not_allowed)
			(vias allowed)
			(pads allowed)
			(copperpour not_allowed)
			(footprints allowed)
		)
		(placement
			(enabled no)
			(sheetname "")
		)
		(fill yes
			(thermal_gap 0.5)
			(thermal_bridge_width 0.5)
			(island_removal_mode 0)
		)
		(polygon
			(pts
				(arc
					(start 288.510218 -241.53495)
					(mid 287.849818 -241.53495)
					(end 288.510218 -241.53495)
				)
			)
		)
	)
	(zone
		(layers "In1.Cu" "In2.Cu")
		(hatch none 0.5)
		(connect_pads
			(clearance 0)
		)
		(min_thickness 0.25)
		(keepout
			(tracks not_allowed)
			(vias allowed)
			(pads allowed)
			(copperpour not_allowed)
			(footprints allowed)
		)
		(placement
			(enabled no)
			(sheetname "")
		)
		(fill yes
			(thermal_gap 0.5)
			(thermal_bridge_width 0.5)
			(island_removal_mode 0)
		)
		(polygon
			(pts
				(arc
					(start 285.066232 -208.385156)
					(mid 284.405832 -208.385156)
					(end 285.066232 -208.385156)
				)
			)
		)
	)
	(zone
		(layers "In1.Cu" "In2.Cu")
		(hatch none 0.5)
		(connect_pads
			(clearance 0)
		)
		(min_thickness 0.25)
		(keepout
			(tracks not_allowed)
			(vias allowed)
			(pads allowed)
			(copperpour not_allowed)
			(footprints allowed)
		)
		(placement
			(enabled no)
			(sheetname "")
		)
		(fill yes
			(thermal_gap 0.5)
			(thermal_bridge_width 0.5)
			(island_removal_mode 0)
		)
		(polygon
			(pts
				(arc
					(start 17.938242 -229.635304)
					(mid 17.277842 -229.635304)
					(end 17.938242 -229.635304)
				)
			)
		)
	)
	(zone
		(layers "In1.Cu" "In2.Cu")
		(hatch none 0.5)
		(connect_pads
			(clearance 0)
		)
		(min_thickness 0.25)
		(keepout
			(tracks not_allowed)
			(vias allowed)
			(pads allowed)
			(copperpour not_allowed)
			(footprints allowed)
		)
		(placement
			(enabled no)
			(sheetname "")
		)
		(fill yes
			(thermal_gap 0.5)
			(thermal_bridge_width 0.5)
			(island_removal_mode 0)
		)
		(polygon
			(pts
				(arc
					(start 280.966164 -237.285022)
					(mid 280.305764 -237.285022)
					(end 280.966164 -237.285022)
				)
			)
		)
	)
	(zone
		(layers "In1.Cu" "In2.Cu")
		(hatch none 0.5)
		(connect_pads
			(clearance 0)
		)
		(min_thickness 0.25)
		(keepout
			(tracks not_allowed)
			(vias allowed)
			(pads allowed)
			(copperpour not_allowed)
			(footprints allowed)
		)
		(placement
			(enabled no)
			(sheetname "")
		)
		(fill yes
			(thermal_gap 0.5)
			(thermal_bridge_width 0.5)
			(island_removal_mode 0)
		)
		(polygon
			(pts
				(arc
					(start 439.430414 -298.485052)
					(mid 438.770014 -298.485052)
					(end 439.430414 -298.485052)
				)
			)
		)
	)
	(zone
		(layers "In1.Cu" "In2.Cu")
		(hatch none 0.5)
		(connect_pads
			(clearance 0)
		)
		(min_thickness 0.25)
		(keepout
			(tracks not_allowed)
			(vias allowed)
			(pads allowed)
			(copperpour not_allowed)
			(footprints allowed)
		)
		(placement
			(enabled no)
			(sheetname "")
		)
		(fill yes
			(thermal_gap 0.5)
			(thermal_bridge_width 0.5)
			(island_removal_mode 0)
		)
		(polygon
			(pts
				(arc
					(start 427.786292 -280.634948)
					(mid 427.125892 -280.634948)
					(end 427.786292 -280.634948)
				)
			)
		)
	)
	(zone
		(layers "In1.Cu" "In2.Cu")
		(hatch none 0.5)
		(connect_pads
			(clearance 0)
		)
		(min_thickness 0.25)
		(keepout
			(tracks not_allowed)
			(vias allowed)
			(pads allowed)
			(copperpour not_allowed)
			(footprints allowed)
		)
		(placement
			(enabled no)
			(sheetname "")
		)
		(fill yes
			(thermal_gap 0.5)
			(thermal_bridge_width 0.5)
			(island_removal_mode 0)
		)
		(polygon
			(pts
				(arc
					(start 40.57015 -295.9354)
					(mid 39.90975 -295.9354)
					(end 40.57015 -295.9354)
				)
			)
		)
	)
	(zone
		(layers "In1.Cu" "In2.Cu")
		(hatch none 0.5)
		(connect_pads
			(clearance 0)
		)
		(min_thickness 0.25)
		(keepout
			(tracks not_allowed)
			(vias allowed)
			(pads allowed)
			(copperpour not_allowed)
			(footprints allowed)
		)
		(placement
			(enabled no)
			(sheetname "")
		)
		(fill yes
			(thermal_gap 0.5)
			(thermal_bridge_width 0.5)
			(island_removal_mode 0)
		)
		(polygon
			(pts
				(arc
					(start 202.478132 -211.7852)
					(mid 201.817732 -211.7852)
					(end 202.478132 -211.7852)
				)
			)
		)
	)
	(zone
		(layers "In1.Cu" "In2.Cu")
		(hatch none 0.5)
		(connect_pads
			(clearance 0)
		)
		(min_thickness 0.25)
		(keepout
			(tracks not_allowed)
			(vias allowed)
			(pads allowed)
			(copperpour not_allowed)
			(footprints allowed)
		)
		(placement
			(enabled no)
			(sheetname "")
		)
		(fill yes
			(thermal_gap 0.5)
			(thermal_bridge_width 0.5)
			(island_removal_mode 0)
		)
		(polygon
			(pts
				(arc
					(start 273.422364 -263.634982)
					(mid 272.761964 -263.634982)
					(end 273.422364 -263.634982)
				)
			)
		)
	)
	(zone
		(layers "In1.Cu" "In2.Cu")
		(hatch none 0.5)
		(connect_pads
			(clearance 0)
		)
		(min_thickness 0.25)
		(keepout
			(tracks not_allowed)
			(vias allowed)
			(pads allowed)
			(copperpour not_allowed)
			(footprints allowed)
		)
		(placement
			(enabled no)
			(sheetname "")
		)
		(fill yes
			(thermal_gap 0.5)
			(thermal_bridge_width 0.5)
			(island_removal_mode 0)
		)
		(polygon
			(pts
				(arc
					(start 48.114204 -282.335224)
					(mid 47.453804 -282.335224)
					(end 48.114204 -282.335224)
				)
			)
		)
	)
	(zone
		(layers "In1.Cu" "In2.Cu")
		(hatch none 0.5)
		(connect_pads
			(clearance 0)
		)
		(min_thickness 0.25)
		(keepout
			(tracks not_allowed)
			(vias allowed)
			(pads allowed)
			(copperpour not_allowed)
			(footprints allowed)
		)
		(placement
			(enabled no)
			(sheetname "")
		)
		(fill yes
			(thermal_gap 0.5)
			(thermal_bridge_width 0.5)
			(island_removal_mode 0)
		)
		(polygon
			(pts
				(arc
					(start 420.242238 -295.085008)
					(mid 419.581838 -295.085008)
					(end 420.242238 -295.085008)
				)
			)
		)
	)
	(zone
		(layers "In1.Cu" "In2.Cu")
		(hatch none 0.5)
		(connect_pads
			(clearance 0)
		)
		(min_thickness 0.25)
		(keepout
			(tracks not_allowed)
			(vias allowed)
			(pads allowed)
			(copperpour not_allowed)
			(footprints allowed)
		)
		(placement
			(enabled no)
			(sheetname "")
		)
		(fill yes
			(thermal_gap 0.5)
			(thermal_bridge_width 0.5)
			(island_removal_mode 0)
		)
		(polygon
			(pts
				(arc
					(start 40.57015 -314.635388)
					(mid 39.90975 -314.635388)
					(end 40.57015 -314.635388)
				)
			)
		)
	)
	(zone
		(layers "In1.Cu" "In2.Cu")
		(hatch none 0.5)
		(connect_pads
			(clearance 0)
		)
		(min_thickness 0.25)
		(keepout
			(tracks not_allowed)
			(vias allowed)
			(pads allowed)
			(copperpour not_allowed)
			(footprints allowed)
		)
		(placement
			(enabled no)
			(sheetname "")
		)
		(fill yes
			(thermal_gap 0.5)
			(thermal_bridge_width 0.5)
			(island_removal_mode 0)
		)
		(polygon
			(pts
				(arc
					(start 202.478132 -285.735268)
					(mid 201.817732 -285.735268)
					(end 202.478132 -285.735268)
				)
			)
		)
	)
	(zone
		(layers "In1.Cu" "In2.Cu")
		(hatch none 0.5)
		(connect_pads
			(clearance 0)
		)
		(min_thickness 0.25)
		(keepout
			(tracks not_allowed)
			(vias allowed)
			(pads allowed)
			(copperpour not_allowed)
			(footprints allowed)
		)
		(placement
			(enabled no)
			(sheetname "")
		)
		(fill yes
			(thermal_gap 0.5)
			(thermal_bridge_width 0.5)
			(island_removal_mode 0)
		)
		(polygon
			(pts
				(arc
					(start 300.15434 -252.584966)
					(mid 299.49394 -252.584966)
					(end 300.15434 -252.584966)
				)
			)
		)
	)
	(zone
		(layers "In1.Cu" "In2.Cu")
		(hatch none 0.5)
		(connect_pads
			(clearance 0)
		)
		(min_thickness 0.25)
		(keepout
			(tracks not_allowed)
			(vias allowed)
			(pads allowed)
			(copperpour not_allowed)
			(footprints allowed)
		)
		(placement
			(enabled no)
			(sheetname "")
		)
		(fill yes
			(thermal_gap 0.5)
			(thermal_bridge_width 0.5)
			(island_removal_mode 0)
		)
		(polygon
			(pts
				(arc
					(start 44.670218 -210.935316)
					(mid 44.009818 -210.935316)
					(end 44.670218 -210.935316)
				)
			)
		)
	)
	(zone
		(layers "In1.Cu" "In2.Cu")
		(hatch none 0.5)
		(connect_pads
			(clearance 0)
		)
		(min_thickness 0.25)
		(keepout
			(tracks not_allowed)
			(vias allowed)
			(pads allowed)
			(copperpour not_allowed)
			(footprints allowed)
		)
		(placement
			(enabled no)
			(sheetname "")
		)
		(fill yes
			(thermal_gap 0.5)
			(thermal_bridge_width 0.5)
			(island_removal_mode 0)
		)
		(polygon
			(pts
				(arc
					(start 427.786292 -310.384952)
					(mid 427.125892 -310.384952)
					(end 427.786292 -310.384952)
				)
			)
		)
	)
	(zone
		(layers "In1.Cu" "In2.Cu")
		(hatch none 0.5)
		(connect_pads
			(clearance 0)
		)
		(min_thickness 0.25)
		(keepout
			(tracks not_allowed)
			(vias allowed)
			(pads allowed)
			(copperpour not_allowed)
			(footprints allowed)
		)
		(placement
			(enabled no)
			(sheetname "")
		)
		(fill yes
			(thermal_gap 0.5)
			(thermal_bridge_width 0.5)
			(island_removal_mode 0)
		)
		(polygon
			(pts
				(arc
					(start 415.062416 -7.672324)
					(mid 415.084734 -7.618442)
					(end 415.138616 -7.596124)
				)
				(arc
					(start 416.17519 -7.596124)
					(mid 416.229072 -7.618442)
					(end 416.25139 -7.672324)
				)
				(arc
					(start 416.25139 -9.071864)
					(mid 416.229072 -9.125746)
					(end 416.17519 -9.148064)
				)
				(arc
					(start 415.138616 -9.148064)
					(mid 415.084734 -9.125746)
					(end 415.062416 -9.071864)
				)
			)
		)
	)
	(zone
		(layers "In1.Cu" "In2.Cu")
		(hatch none 0.5)
		(connect_pads
			(clearance 0)
		)
		(min_thickness 0.25)
		(keepout
			(tracks not_allowed)
			(vias allowed)
			(pads allowed)
			(copperpour not_allowed)
			(footprints allowed)
		)
		(placement
			(enabled no)
			(sheetname "")
		)
		(fill yes
			(thermal_gap 0.5)
			(thermal_bridge_width 0.5)
			(island_removal_mode 0)
		)
		(polygon
			(pts
				(arc
					(start 446.974468 -238.985044)
					(mid 446.314068 -238.985044)
					(end 446.974468 -238.985044)
				)
			)
		)
	)
	(zone
		(layers "In1.Cu" "In2.Cu")
		(hatch none 0.5)
		(connect_pads
			(clearance 0)
		)
		(min_thickness 0.25)
		(keepout
			(tracks not_allowed)
			(vias allowed)
			(pads allowed)
			(copperpour not_allowed)
			(footprints allowed)
		)
		(placement
			(enabled no)
			(sheetname "")
		)
		(fill yes
			(thermal_gap 0.5)
			(thermal_bridge_width 0.5)
			(island_removal_mode 0)
		)
		(polygon
			(pts
				(arc
					(start 22.03831 -298.485306)
					(mid 21.37791 -298.485306)
					(end 22.03831 -298.485306)
				)
			)
		)
	)
	(zone
		(layers "In1.Cu" "In2.Cu")
		(hatch none 0.5)
		(connect_pads
			(clearance 0)
		)
		(min_thickness 0.25)
		(keepout
			(tracks not_allowed)
			(vias allowed)
			(pads allowed)
			(copperpour not_allowed)
			(footprints allowed)
		)
		(placement
			(enabled no)
			(sheetname "")
		)
		(fill yes
			(thermal_gap 0.5)
			(thermal_bridge_width 0.5)
			(island_removal_mode 0)
		)
		(polygon
			(pts
				(arc
					(start 446.974468 -227.085144)
					(mid 446.314068 -227.085144)
					(end 446.974468 -227.085144)
				)
			)
		)
	)
	(zone
		(layers "In1.Cu" "In2.Cu")
		(hatch none 0.5)
		(connect_pads
			(clearance 0)
		)
		(min_thickness 0.25)
		(keepout
			(tracks not_allowed)
			(vias allowed)
			(pads allowed)
			(copperpour not_allowed)
			(footprints allowed)
		)
		(placement
			(enabled no)
			(sheetname "")
		)
		(fill yes
			(thermal_gap 0.5)
			(thermal_bridge_width 0.5)
			(island_removal_mode 0)
		)
		(polygon
			(pts
				(arc
					(start 419.851586 -11.91768)
					(mid 419.829268 -11.971562)
					(end 419.775386 -11.99388)
				)
				(arc
					(start 418.738812 -11.99388)
					(mid 418.68493 -11.971562)
					(end 418.662612 -11.91768)
				)
				(arc
					(start 418.662612 -10.51814)
					(mid 418.68493 -10.464258)
					(end 418.738812 -10.44194)
				)
				(arc
					(start 419.775386 -10.44194)
					(mid 419.829268 -10.464258)
					(end 419.851586 -10.51814)
				)
			)
		)
	)
	(zone
		(layers "In1.Cu" "In2.Cu")
		(hatch none 0.5)
		(connect_pads
			(clearance 0)
		)
		(min_thickness 0.25)
		(keepout
			(tracks not_allowed)
			(vias allowed)
			(pads allowed)
			(copperpour not_allowed)
			(footprints allowed)
		)
		(placement
			(enabled no)
			(sheetname "")
		)
		(fill yes
			(thermal_gap 0.5)
			(thermal_bridge_width 0.5)
			(island_removal_mode 0)
		)
		(polygon
			(pts
				(arc
					(start 191.490346 -199.035416)
					(mid 190.829946 -199.035416)
					(end 191.490346 -199.035416)
				)
			)
		)
	)
	(zone
		(layers "In1.Cu" "In2.Cu")
		(hatch none 0.5)
		(connect_pads
			(clearance 0)
		)
		(min_thickness 0.25)
		(keepout
			(tracks not_allowed)
			(vias allowed)
			(pads allowed)
			(copperpour not_allowed)
			(footprints allowed)
		)
		(placement
			(enabled no)
			(sheetname "")
		)
		(fill yes
			(thermal_gap 0.5)
			(thermal_bridge_width 0.5)
			(island_removal_mode 0)
		)
		(polygon
			(pts
				(arc
					(start 424.342306 -223.6851)
					(mid 423.681906 -223.6851)
					(end 424.342306 -223.6851)
				)
			)
		)
	)
	(zone
		(layers "In1.Cu" "In2.Cu")
		(hatch none 0.5)
		(connect_pads
			(clearance 0)
		)
		(min_thickness 0.25)
		(keepout
			(tracks not_allowed)
			(vias allowed)
			(pads allowed)
			(copperpour not_allowed)
			(footprints allowed)
		)
		(placement
			(enabled no)
			(sheetname "")
		)
		(fill yes
			(thermal_gap 0.5)
			(thermal_bridge_width 0.5)
			(island_removal_mode 0)
		)
		(polygon
			(pts
				(arc
					(start 40.57015 -282.335224)
					(mid 39.90975 -282.335224)
					(end 40.57015 -282.335224)
				)
			)
		)
	)
	(zone
		(layers "In1.Cu" "In2.Cu")
		(hatch none 0.5)
		(connect_pads
			(clearance 0)
		)
		(min_thickness 0.25)
		(keepout
			(tracks not_allowed)
			(vias allowed)
			(pads allowed)
			(copperpour not_allowed)
			(footprints allowed)
		)
		(placement
			(enabled no)
			(sheetname "")
		)
		(fill yes
			(thermal_gap 0.5)
			(thermal_bridge_width 0.5)
			(island_removal_mode 0)
		)
		(polygon
			(pts
				(arc
					(start 450.4182 -293.384986)
					(mid 449.7578 -293.384986)
					(end 450.4182 -293.384986)
				)
			)
		)
	)
	(zone
		(layers "In1.Cu" "In2.Cu")
		(hatch none 0.5)
		(connect_pads
			(clearance 0)
		)
		(min_thickness 0.25)
		(keepout
			(tracks not_allowed)
			(vias allowed)
			(pads allowed)
			(copperpour not_allowed)
			(footprints allowed)
		)
		(placement
			(enabled no)
			(sheetname "")
		)
		(fill yes
			(thermal_gap 0.5)
			(thermal_bridge_width 0.5)
			(island_removal_mode 0)
		)
		(polygon
			(pts
				(arc
					(start 442.8744 -304.435002)
					(mid 442.214 -304.435002)
					(end 442.8744 -304.435002)
				)
			)
		)
	)
	(zone
		(layers "In1.Cu" "In2.Cu")
		(hatch none 0.5)
		(connect_pads
			(clearance 0)
		)
		(min_thickness 0.25)
		(keepout
			(tracks not_allowed)
			(vias allowed)
			(pads allowed)
			(copperpour not_allowed)
			(footprints allowed)
		)
		(placement
			(enabled no)
			(sheetname "")
		)
		(fill yes
			(thermal_gap 0.5)
			(thermal_bridge_width 0.5)
			(island_removal_mode 0)
		)
		(polygon
			(pts
				(arc
					(start 22.03831 -212.635338)
					(mid 21.37791 -212.635338)
					(end 22.03831 -212.635338)
				)
			)
		)
	)
	(zone
		(layers "In1.Cu" "In2.Cu")
		(hatch none 0.5)
		(connect_pads
			(clearance 0)
		)
		(min_thickness 0.25)
		(keepout
			(tracks not_allowed)
			(vias allowed)
			(pads allowed)
			(copperpour not_allowed)
			(footprints allowed)
		)
		(placement
			(enabled no)
			(sheetname "")
		)
		(fill yes
			(thermal_gap 0.5)
			(thermal_bridge_width 0.5)
			(island_removal_mode 0)
		)
		(polygon
			(pts
				(arc
					(start 424.342306 -281.485086)
					(mid 423.681906 -281.485086)
					(end 424.342306 -281.485086)
				)
			)
		)
	)
	(zone
		(layers "In1.Cu" "In2.Cu")
		(hatch none 0.5)
		(connect_pads
			(clearance 0)
		)
		(min_thickness 0.25)
		(keepout
			(tracks not_allowed)
			(vias allowed)
			(pads allowed)
			(copperpour not_allowed)
			(footprints allowed)
		)
		(placement
			(enabled no)
			(sheetname "")
		)
		(fill yes
			(thermal_gap 0.5)
			(thermal_bridge_width 0.5)
			(island_removal_mode 0)
		)
		(polygon
			(pts
				(arc
					(start 17.938242 -230.485442)
					(mid 17.277842 -230.485442)
					(end 17.938242 -230.485442)
				)
			)
		)
	)
	(zone
		(layers "In1.Cu" "In2.Cu")
		(hatch none 0.5)
		(connect_pads
			(clearance 0)
		)
		(min_thickness 0.25)
		(keepout
			(tracks not_allowed)
			(vias allowed)
			(pads allowed)
			(copperpour not_allowed)
			(footprints allowed)
		)
		(placement
			(enabled no)
			(sheetname "")
		)
		(fill yes
			(thermal_gap 0.5)
			(thermal_bridge_width 0.5)
			(island_removal_mode 0)
		)
		(polygon
			(pts
				(arc
					(start 420.855394 -17.967198)
					(mid 420.877712 -18.02108)
					(end 420.931594 -18.043398)
				)
				(arc
					(start 421.127174 -18.043398)
					(mid 421.14905 -18.040266)
					(end 421.169084 -18.030952)
				)
				(arc
					(start 421.462708 -17.83842)
					(mid 421.504364 -17.826018)
					(end 421.54602 -17.83842)
				)
				(arc
					(start 421.840914 -18.030952)
					(mid 421.860838 -18.040188)
					(end 421.88257 -18.043398)
				)
				(arc
					(start 422.077134 -18.043398)
					(mid 422.131016 -18.02108)
					(end 422.153334 -17.967198)
				)
				(arc
					(start 422.153334 -17.281398)
					(mid 422.131016 -17.227516)
					(end 422.077134 -17.205198)
				)
				(arc
					(start 421.88257 -17.205198)
					(mid 421.860826 -17.208366)
					(end 421.840914 -17.217644)
				)
				(arc
					(start 421.54475 -17.41043)
					(mid 421.503066 -17.422652)
					(end 421.461438 -17.410176)
				)
				(arc
					(start 421.167814 -17.217644)
					(mid 421.14789 -17.208408)
					(end 421.126158 -17.205198)
				)
				(arc
					(start 420.931594 -17.205198)
					(mid 420.877712 -17.227516)
					(end 420.855394 -17.281398)
				)
			)
		)
	)
	(zone
		(layers "In1.Cu" "In2.Cu")
		(hatch none 0.5)
		(connect_pads
			(clearance 0)
		)
		(min_thickness 0.25)
		(keepout
			(tracks not_allowed)
			(vias allowed)
			(pads allowed)
			(copperpour not_allowed)
			(footprints allowed)
		)
		(placement
			(enabled no)
			(sheetname "")
		)
		(fill yes
			(thermal_gap 0.5)
			(thermal_bridge_width 0.5)
			(island_removal_mode 0)
		)
		(polygon
			(pts
				(arc
					(start 442.8744 -272.984976)
					(mid 442.214 -272.984976)
					(end 442.8744 -272.984976)
				)
			)
		)
	)
	(zone
		(layers "In1.Cu" "In2.Cu")
		(hatch none 0.5)
		(connect_pads
			(clearance 0)
		)
		(min_thickness 0.25)
		(keepout
			(tracks not_allowed)
			(vias allowed)
			(pads allowed)
			(copperpour not_allowed)
			(footprints allowed)
		)
		(placement
			(enabled no)
			(sheetname "")
		)
		(fill yes
			(thermal_gap 0.5)
			(thermal_bridge_width 0.5)
			(island_removal_mode 0)
		)
		(polygon
			(pts
				(arc
					(start 431.88636 -315.485018)
					(mid 431.22596 -315.485018)
					(end 431.88636 -315.485018)
				)
			)
		)
	)
	(zone
		(layers "In1.Cu" "In2.Cu")
		(hatch none 0.5)
		(connect_pads
			(clearance 0)
		)
		(min_thickness 0.25)
		(keepout
			(tracks not_allowed)
			(vias allowed)
			(pads allowed)
			(copperpour not_allowed)
			(footprints allowed)
		)
		(placement
			(enabled no)
			(sheetname "")
		)
		(fill yes
			(thermal_gap 0.5)
			(thermal_bridge_width 0.5)
			(island_removal_mode 0)
		)
		(polygon
			(pts
				(arc
					(start 424.342306 -250.884944)
					(mid 423.681906 -250.884944)
					(end 424.342306 -250.884944)
				)
			)
		)
	)
	(zone
		(layers "In1.Cu" "In2.Cu")
		(hatch none 0.5)
		(connect_pads
			(clearance 0)
		)
		(min_thickness 0.25)
		(keepout
			(tracks not_allowed)
			(vias allowed)
			(pads allowed)
			(copperpour not_allowed)
			(footprints allowed)
		)
		(placement
			(enabled no)
			(sheetname "")
		)
		(fill yes
			(thermal_gap 0.5)
			(thermal_bridge_width 0.5)
			(island_removal_mode 0)
		)
		(polygon
			(pts
				(arc
					(start 454.518268 -298.485052)
					(mid 453.857868 -298.485052)
					(end 454.518268 -298.485052)
				)
			)
		)
	)
	(zone
		(layers "In1.Cu" "In2.Cu")
		(hatch none 0.5)
		(connect_pads
			(clearance 0)
		)
		(min_thickness 0.25)
		(keepout
			(tracks not_allowed)
			(vias allowed)
			(pads allowed)
			(copperpour not_allowed)
			(footprints allowed)
		)
		(placement
			(enabled no)
			(sheetname "")
		)
		(fill yes
			(thermal_gap 0.5)
			(thermal_bridge_width 0.5)
			(island_removal_mode 0)
		)
		(polygon
			(pts
				(arc
					(start 292.610286 -272.135092)
					(mid 291.949886 -272.135092)
					(end 292.610286 -272.135092)
				)
			)
		)
	)
	(zone
		(layers "In1.Cu" "In2.Cu")
		(hatch none 0.5)
		(connect_pads
			(clearance 0)
		)
		(min_thickness 0.25)
		(keepout
			(tracks not_allowed)
			(vias allowed)
			(pads allowed)
			(copperpour not_allowed)
			(footprints allowed)
		)
		(placement
			(enabled no)
			(sheetname "")
		)
		(fill yes
			(thermal_gap 0.5)
			(thermal_bridge_width 0.5)
			(island_removal_mode 0)
		)
		(polygon
			(pts
				(arc
					(start 48.114204 -295.085262)
					(mid 47.453804 -295.085262)
					(end 48.114204 -295.085262)
				)
			)
		)
	)
	(zone
		(layers "In1.Cu" "In2.Cu")
		(hatch none 0.5)
		(connect_pads
			(clearance 0)
		)
		(min_thickness 0.25)
		(keepout
			(tracks not_allowed)
			(vias allowed)
			(pads allowed)
			(copperpour not_allowed)
			(footprints allowed)
		)
		(placement
			(enabled no)
			(sheetname "")
		)
		(fill yes
			(thermal_gap 0.5)
			(thermal_bridge_width 0.5)
			(island_removal_mode 0)
		)
		(polygon
			(pts
				(arc
					(start 442.8744 -282.33497)
					(mid 442.214 -282.33497)
					(end 442.8744 -282.33497)
				)
			)
		)
	)
	(zone
		(layers "In1.Cu" "In2.Cu")
		(hatch none 0.5)
		(connect_pads
			(clearance 0)
		)
		(min_thickness 0.25)
		(keepout
			(tracks not_allowed)
			(vias allowed)
			(pads allowed)
			(copperpour not_allowed)
			(footprints allowed)
		)
		(placement
			(enabled no)
			(sheetname "")
		)
		(fill yes
			(thermal_gap 0.5)
			(thermal_bridge_width 0.5)
			(island_removal_mode 0)
		)
		(polygon
			(pts
				(arc
					(start 165.534594 -370.978684)
					(mid 165.554518 -370.98792)
					(end 165.57625 -370.99113)
				)
				(arc
					(start 165.770814 -370.99113)
					(mid 165.824696 -370.968812)
					(end 165.847014 -370.91493)
				)
				(arc
					(start 165.847014 -370.22913)
					(mid 165.824696 -370.175248)
					(end 165.770814 -370.15293)
				)
				(arc
					(start 165.57625 -370.15293)
					(mid 165.554506 -370.156098)
					(end 165.534594 -370.165376)
				)
				(arc
					(start 165.23843 -370.358162)
					(mid 165.196746 -370.370384)
					(end 165.155118 -370.357908)
				)
				(arc
					(start 164.861494 -370.165376)
					(mid 164.84157 -370.15614)
					(end 164.819838 -370.15293)
				)
				(arc
					(start 164.625274 -370.15293)
					(mid 164.571392 -370.175248)
					(end 164.549074 -370.22913)
				)
				(arc
					(start 164.549074 -370.91493)
					(mid 164.571392 -370.968812)
					(end 164.625274 -370.99113)
				)
				(arc
					(start 164.821108 -370.99113)
					(mid 164.842852 -370.987962)
					(end 164.862764 -370.978684)
				)
				(arc
					(start 165.156388 -370.786152)
					(mid 165.198044 -370.77375)
					(end 165.2397 -370.786152)
				)
			)
		)
	)
	(zone
		(layers "In1.Cu" "In2.Cu")
		(hatch none 0.5)
		(connect_pads
			(clearance 0)
		)
		(min_thickness 0.25)
		(keepout
			(tracks not_allowed)
			(vias allowed)
			(pads allowed)
			(copperpour not_allowed)
			(footprints allowed)
		)
		(placement
			(enabled no)
			(sheetname "")
		)
		(fill yes
			(thermal_gap 0.5)
			(thermal_bridge_width 0.5)
			(island_removal_mode 0)
		)
		(polygon
			(pts
				(arc
					(start 44.670218 -221.985332)
					(mid 44.009818 -221.985332)
					(end 44.670218 -221.985332)
				)
			)
		)
	)
	(zone
		(layers "In1.Cu" "In2.Cu")
		(hatch none 0.5)
		(connect_pads
			(clearance 0)
		)
		(min_thickness 0.25)
		(keepout
			(tracks not_allowed)
			(vias allowed)
			(pads allowed)
			(copperpour not_allowed)
			(footprints allowed)
		)
		(placement
			(enabled no)
			(sheetname "")
		)
		(fill yes
			(thermal_gap 0.5)
			(thermal_bridge_width 0.5)
			(island_removal_mode 0)
		)
		(polygon
			(pts
				(arc
					(start 424.342306 -307.835046)
					(mid 423.681906 -307.835046)
					(end 424.342306 -307.835046)
				)
			)
		)
	)
	(zone
		(layers "In1.Cu" "In2.Cu")
		(hatch none 0.5)
		(connect_pads
			(clearance 0)
		)
		(min_thickness 0.25)
		(keepout
			(tracks not_allowed)
			(vias allowed)
			(pads allowed)
			(copperpour not_allowed)
			(footprints allowed)
		)
		(placement
			(enabled no)
			(sheetname "")
		)
		(fill yes
			(thermal_gap 0.5)
			(thermal_bridge_width 0.5)
			(island_removal_mode 0)
		)
		(polygon
			(pts
				(arc
					(start 288.510218 -218.585034)
					(mid 287.849818 -218.585034)
					(end 288.510218 -218.585034)
				)
			)
		)
	)
	(zone
		(layers "In1.Cu" "In2.Cu")
		(hatch none 0.5)
		(connect_pads
			(clearance 0)
		)
		(min_thickness 0.25)
		(keepout
			(tracks not_allowed)
			(vias allowed)
			(pads allowed)
			(copperpour not_allowed)
			(footprints allowed)
		)
		(placement
			(enabled no)
			(sheetname "")
		)
		(fill yes
			(thermal_gap 0.5)
			(thermal_bridge_width 0.5)
			(island_removal_mode 0)
		)
		(polygon
			(pts
				(arc
					(start 183.946292 -264.485374)
					(mid 183.285892 -264.485374)
					(end 183.946292 -264.485374)
				)
			)
		)
	)
	(zone
		(layers "In1.Cu" "In2.Cu")
		(hatch none 0.5)
		(connect_pads
			(clearance 0)
		)
		(min_thickness 0.25)
		(keepout
			(tracks not_allowed)
			(vias allowed)
			(pads allowed)
			(copperpour not_allowed)
			(footprints allowed)
		)
		(placement
			(enabled no)
			(sheetname "")
		)
		(fill yes
			(thermal_gap 0.5)
			(thermal_bridge_width 0.5)
			(island_removal_mode 0)
		)
		(polygon
			(pts
				(arc
					(start 446.974468 -238.13516)
					(mid 446.314068 -238.13516)
					(end 446.974468 -238.13516)
				)
			)
		)
	)
	(zone
		(layers "In1.Cu" "In2.Cu")
		(hatch none 0.5)
		(connect_pads
			(clearance 0)
		)
		(min_thickness 0.25)
		(keepout
			(tracks not_allowed)
			(vias allowed)
			(pads allowed)
			(copperpour not_allowed)
			(footprints allowed)
		)
		(placement
			(enabled no)
			(sheetname "")
		)
		(fill yes
			(thermal_gap 0.5)
			(thermal_bridge_width 0.5)
			(island_removal_mode 0)
		)
		(polygon
			(pts
				(arc
					(start 202.478132 -201.585322)
					(mid 201.817732 -201.585322)
					(end 202.478132 -201.585322)
				)
			)
		)
	)
	(zone
		(layers "In1.Cu" "In2.Cu")
		(hatch none 0.5)
		(connect_pads
			(clearance 0)
		)
		(min_thickness 0.25)
		(keepout
			(tracks not_allowed)
			(vias allowed)
			(pads allowed)
			(copperpour not_allowed)
			(footprints allowed)
		)
		(placement
			(enabled no)
			(sheetname "")
		)
		(fill yes
			(thermal_gap 0.5)
			(thermal_bridge_width 0.5)
			(island_removal_mode 0)
		)
		(polygon
			(pts
				(arc
					(start 292.610286 -199.035162)
					(mid 291.949886 -199.035162)
					(end 292.610286 -199.035162)
				)
			)
		)
	)
	(zone
		(layers "In1.Cu" "In2.Cu")
		(hatch none 0.5)
		(connect_pads
			(clearance 0)
		)
		(min_thickness 0.25)
		(keepout
			(tracks not_allowed)
			(vias allowed)
			(pads allowed)
			(copperpour not_allowed)
			(footprints allowed)
		)
		(placement
			(enabled no)
			(sheetname "")
		)
		(fill yes
			(thermal_gap 0.5)
			(thermal_bridge_width 0.5)
			(island_removal_mode 0)
		)
		(polygon
			(pts
				(arc
					(start 277.522432 -270.43507)
					(mid 276.862032 -270.43507)
					(end 277.522432 -270.43507)
				)
			)
		)
	)
	(zone
		(layers "In1.Cu" "In2.Cu")
		(hatch none 0.5)
		(connect_pads
			(clearance 0)
		)
		(min_thickness 0.25)
		(keepout
			(tracks not_allowed)
			(vias allowed)
			(pads allowed)
			(copperpour not_allowed)
			(footprints allowed)
		)
		(placement
			(enabled no)
			(sheetname "")
		)
		(fill yes
			(thermal_gap 0.5)
			(thermal_bridge_width 0.5)
			(island_removal_mode 0)
		)
		(polygon
			(pts
				(arc
					(start 439.430414 -275.535136)
					(mid 438.770014 -275.535136)
					(end 439.430414 -275.535136)
				)
			)
		)
	)
	(zone
		(layers "In1.Cu" "In2.Cu")
		(hatch none 0.5)
		(connect_pads
			(clearance 0)
		)
		(min_thickness 0.25)
		(keepout
			(tracks not_allowed)
			(vias allowed)
			(pads allowed)
			(copperpour not_allowed)
			(footprints allowed)
		)
		(placement
			(enabled no)
			(sheetname "")
		)
		(fill yes
			(thermal_gap 0.5)
			(thermal_bridge_width 0.5)
			(island_removal_mode 0)
		)
		(polygon
			(pts
				(arc
					(start 22.03831 -283.185362)
					(mid 21.37791 -283.185362)
					(end 22.03831 -283.185362)
				)
			)
		)
	)
	(zone
		(layers "In1.Cu" "In2.Cu")
		(hatch none 0.5)
		(connect_pads
			(clearance 0)
		)
		(min_thickness 0.25)
		(keepout
			(tracks not_allowed)
			(vias allowed)
			(pads allowed)
			(copperpour not_allowed)
			(footprints allowed)
		)
		(placement
			(enabled no)
			(sheetname "")
		)
		(fill yes
			(thermal_gap 0.5)
			(thermal_bridge_width 0.5)
			(island_removal_mode 0)
		)
		(polygon
			(pts
				(arc
					(start 199.0344 -214.33536)
					(mid 198.374 -214.33536)
					(end 199.0344 -214.33536)
				)
			)
		)
	)
	(zone
		(layers "In1.Cu" "In2.Cu")
		(hatch none 0.5)
		(connect_pads
			(clearance 0)
		)
		(min_thickness 0.25)
		(keepout
			(tracks not_allowed)
			(vias allowed)
			(pads allowed)
			(copperpour not_allowed)
			(footprints allowed)
		)
		(placement
			(enabled no)
			(sheetname "")
		)
		(fill yes
			(thermal_gap 0.5)
			(thermal_bridge_width 0.5)
			(island_removal_mode 0)
		)
		(polygon
			(pts
				(arc
					(start 446.974468 -242.385088)
					(mid 446.314068 -242.385088)
					(end 446.974468 -242.385088)
				)
			)
		)
	)
	(zone
		(layers "In1.Cu" "In2.Cu")
		(hatch none 0.5)
		(connect_pads
			(clearance 0)
		)
		(min_thickness 0.25)
		(keepout
			(tracks not_allowed)
			(vias allowed)
			(pads allowed)
			(copperpour not_allowed)
			(footprints allowed)
		)
		(placement
			(enabled no)
			(sheetname "")
		)
		(fill yes
			(thermal_gap 0.5)
			(thermal_bridge_width 0.5)
			(island_removal_mode 0)
		)
		(polygon
			(pts
				(arc
					(start 273.422364 -314.635134)
					(mid 272.761964 -314.635134)
					(end 273.422364 -314.635134)
				)
			)
		)
	)
	(zone
		(layers "In1.Cu" "In2.Cu")
		(hatch none 0.5)
		(connect_pads
			(clearance 0)
		)
		(min_thickness 0.25)
		(keepout
			(tracks not_allowed)
			(vias allowed)
			(pads allowed)
			(copperpour not_allowed)
			(footprints allowed)
		)
		(placement
			(enabled no)
			(sheetname "")
		)
		(fill yes
			(thermal_gap 0.5)
			(thermal_bridge_width 0.5)
			(island_removal_mode 0)
		)
		(polygon
			(pts
				(arc
					(start 168.372282 -12.952222)
					(mid 168.3946 -12.89834)
					(end 168.448482 -12.876022)
				)
				(arc
					(start 169.485056 -12.876022)
					(mid 169.538938 -12.89834)
					(end 169.561256 -12.952222)
				)
				(arc
					(start 169.561256 -14.351762)
					(mid 169.538938 -14.405644)
					(end 169.485056 -14.427962)
				)
				(arc
					(start 168.448482 -14.427962)
					(mid 168.3946 -14.405644)
					(end 168.372282 -14.351762)
				)
			)
		)
	)
	(zone
		(layers "In1.Cu" "In2.Cu")
		(hatch none 0.5)
		(connect_pads
			(clearance 0)
		)
		(min_thickness 0.25)
		(keepout
			(tracks not_allowed)
			(vias allowed)
			(pads allowed)
			(copperpour not_allowed)
			(footprints allowed)
		)
		(placement
			(enabled no)
			(sheetname "")
		)
		(fill yes
			(thermal_gap 0.5)
			(thermal_bridge_width 0.5)
			(island_removal_mode 0)
		)
		(polygon
			(pts
				(arc
					(start 25.482296 -205.83525)
					(mid 24.821896 -205.83525)
					(end 25.482296 -205.83525)
				)
			)
		)
	)
	(zone
		(layers "In1.Cu" "In2.Cu")
		(hatch none 0.5)
		(connect_pads
			(clearance 0)
		)
		(min_thickness 0.25)
		(keepout
			(tracks not_allowed)
			(vias allowed)
			(pads allowed)
			(copperpour not_allowed)
			(footprints allowed)
		)
		(placement
			(enabled no)
			(sheetname "")
		)
		(fill yes
			(thermal_gap 0.5)
			(thermal_bridge_width 0.5)
			(island_removal_mode 0)
		)
		(polygon
			(pts
				(arc
					(start 296.054272 -235.585)
					(mid 295.393872 -235.585)
					(end 296.054272 -235.585)
				)
			)
		)
	)
	(zone
		(layers "In1.Cu" "In2.Cu")
		(hatch none 0.5)
		(connect_pads
			(clearance 0)
		)
		(min_thickness 0.25)
		(keepout
			(tracks not_allowed)
			(vias allowed)
			(pads allowed)
			(copperpour not_allowed)
			(footprints allowed)
		)
		(placement
			(enabled no)
			(sheetname "")
		)
		(fill yes
			(thermal_gap 0.5)
			(thermal_bridge_width 0.5)
			(island_removal_mode 0)
		)
		(polygon
			(pts
				(arc
					(start 48.114204 -301.035212)
					(mid 47.453804 -301.035212)
					(end 48.114204 -301.035212)
				)
			)
		)
	)
	(zone
		(layers "In1.Cu" "In2.Cu")
		(hatch none 0.5)
		(connect_pads
			(clearance 0)
		)
		(min_thickness 0.25)
		(keepout
			(tracks not_allowed)
			(vias allowed)
			(pads allowed)
			(copperpour not_allowed)
			(footprints allowed)
		)
		(placement
			(enabled no)
			(sheetname "")
		)
		(fill yes
			(thermal_gap 0.5)
			(thermal_bridge_width 0.5)
			(island_removal_mode 0)
		)
		(polygon
			(pts
				(arc
					(start 177.832258 -54.558692)
					(mid 177.88614 -54.58101)
					(end 177.908458 -54.634892)
				)
				(arc
					(start 177.908458 -55.464964)
					(mid 177.88614 -55.518846)
					(end 177.832258 -55.541164)
				)
				(arc
					(start 176.384458 -55.541164)
					(mid 176.330576 -55.518846)
					(end 176.308258 -55.464964)
				)
				(arc
					(start 176.308258 -54.634892)
					(mid 176.330576 -54.58101)
					(end 176.384458 -54.558692)
				)
			)
		)
	)
	(zone
		(layers "In1.Cu" "In2.Cu")
		(hatch none 0.5)
		(connect_pads
			(clearance 0)
		)
		(min_thickness 0.25)
		(keepout
			(tracks not_allowed)
			(vias allowed)
			(pads allowed)
			(copperpour not_allowed)
			(footprints allowed)
		)
		(placement
			(enabled no)
			(sheetname "")
		)
		(fill yes
			(thermal_gap 0.5)
			(thermal_bridge_width 0.5)
			(island_removal_mode 0)
		)
		(polygon
			(pts
				(arc
					(start 202.478132 -218.585288)
					(mid 201.817732 -218.585288)
					(end 202.478132 -218.585288)
				)
			)
		)
	)
	(zone
		(layers "In1.Cu" "In2.Cu")
		(hatch none 0.5)
		(connect_pads
			(clearance 0)
		)
		(min_thickness 0.25)
		(keepout
			(tracks not_allowed)
			(vias allowed)
			(pads allowed)
			(copperpour not_allowed)
			(footprints allowed)
		)
		(placement
			(enabled no)
			(sheetname "")
		)
		(fill yes
			(thermal_gap 0.5)
			(thermal_bridge_width 0.5)
			(island_removal_mode 0)
		)
		(polygon
			(pts
				(arc
					(start 431.88636 -199.035162)
					(mid 431.22596 -199.035162)
					(end 431.88636 -199.035162)
				)
			)
		)
	)
	(zone
		(layers "In1.Cu" "In2.Cu")
		(hatch none 0.5)
		(connect_pads
			(clearance 0)
		)
		(min_thickness 0.25)
		(keepout
			(tracks not_allowed)
			(vias allowed)
			(pads allowed)
			(copperpour not_allowed)
			(footprints allowed)
		)
		(placement
			(enabled no)
			(sheetname "")
		)
		(fill yes
			(thermal_gap 0.5)
			(thermal_bridge_width 0.5)
			(island_removal_mode 0)
		)
		(polygon
			(pts
				(arc
					(start 179.846224 -232.18521)
					(mid 179.185824 -232.18521)
					(end 179.846224 -232.18521)
				)
			)
		)
	)
	(zone
		(layers "In1.Cu" "In2.Cu")
		(hatch none 0.5)
		(connect_pads
			(clearance 0)
		)
		(min_thickness 0.25)
		(keepout
			(tracks not_allowed)
			(vias allowed)
			(pads allowed)
			(copperpour not_allowed)
			(footprints allowed)
		)
		(placement
			(enabled no)
			(sheetname "")
		)
		(fill yes
			(thermal_gap 0.5)
			(thermal_bridge_width 0.5)
			(island_removal_mode 0)
		)
		(polygon
			(pts
				(arc
					(start 424.342306 -214.335106)
					(mid 423.681906 -214.335106)
					(end 424.342306 -214.335106)
				)
			)
		)
	)
	(zone
		(layers "In1.Cu" "In2.Cu")
		(hatch none 0.5)
		(connect_pads
			(clearance 0)
		)
		(min_thickness 0.25)
		(keepout
			(tracks not_allowed)
			(vias allowed)
			(pads allowed)
			(copperpour not_allowed)
			(footprints allowed)
		)
		(placement
			(enabled no)
			(sheetname "")
		)
		(fill yes
			(thermal_gap 0.5)
			(thermal_bridge_width 0.5)
			(island_removal_mode 0)
		)
		(polygon
			(pts
				(arc
					(start 427.786292 -202.434952)
					(mid 427.125892 -202.434952)
					(end 427.786292 -202.434952)
				)
			)
		)
	)
	(zone
		(layers "In1.Cu" "In2.Cu")
		(hatch none 0.5)
		(connect_pads
			(clearance 0)
		)
		(min_thickness 0.25)
		(keepout
			(tracks not_allowed)
			(vias allowed)
			(pads allowed)
			(copperpour not_allowed)
			(footprints allowed)
		)
		(placement
			(enabled no)
			(sheetname "")
		)
		(fill yes
			(thermal_gap 0.5)
			(thermal_bridge_width 0.5)
			(island_removal_mode 0)
		)
		(polygon
			(pts
				(arc
					(start 435.330346 -199.885046)
					(mid 434.669946 -199.885046)
					(end 435.330346 -199.885046)
				)
			)
		)
	)
	(zone
		(layers "In1.Cu" "In2.Cu")
		(hatch none 0.5)
		(connect_pads
			(clearance 0)
		)
		(min_thickness 0.25)
		(keepout
			(tracks not_allowed)
			(vias allowed)
			(pads allowed)
			(copperpour not_allowed)
			(footprints allowed)
		)
		(placement
			(enabled no)
			(sheetname "")
		)
		(fill yes
			(thermal_gap 0.5)
			(thermal_bridge_width 0.5)
			(island_removal_mode 0)
		)
		(polygon
			(pts
				(arc
					(start 179.846224 -210.935316)
					(mid 179.185824 -210.935316)
					(end 179.846224 -210.935316)
				)
			)
		)
	)
	(zone
		(layers "In1.Cu" "In2.Cu")
		(hatch none 0.5)
		(connect_pads
			(clearance 0)
		)
		(min_thickness 0.25)
		(keepout
			(tracks not_allowed)
			(vias allowed)
			(pads allowed)
			(copperpour not_allowed)
			(footprints allowed)
		)
		(placement
			(enabled no)
			(sheetname "")
		)
		(fill yes
			(thermal_gap 0.5)
			(thermal_bridge_width 0.5)
			(island_removal_mode 0)
		)
		(polygon
			(pts
				(arc
					(start 292.610286 -276.38502)
					(mid 291.949886 -276.38502)
					(end 292.610286 -276.38502)
				)
			)
		)
	)
	(zone
		(layers "In1.Cu" "In2.Cu")
		(hatch none 0.5)
		(connect_pads
			(clearance 0)
		)
		(min_thickness 0.25)
		(keepout
			(tracks not_allowed)
			(vias allowed)
			(pads allowed)
			(copperpour not_allowed)
			(footprints allowed)
		)
		(placement
			(enabled no)
			(sheetname "")
		)
		(fill yes
			(thermal_gap 0.5)
			(thermal_bridge_width 0.5)
			(island_removal_mode 0)
		)
		(polygon
			(pts
				(arc
					(start 288.510218 -268.735048)
					(mid 287.849818 -268.735048)
					(end 288.510218 -268.735048)
				)
			)
		)
	)
	(zone
		(layers "In1.Cu" "In2.Cu")
		(hatch none 0.5)
		(connect_pads
			(clearance 0)
		)
		(min_thickness 0.25)
		(keepout
			(tracks not_allowed)
			(vias allowed)
			(pads allowed)
			(copperpour not_allowed)
			(footprints allowed)
		)
		(placement
			(enabled no)
			(sheetname "")
		)
		(fill yes
			(thermal_gap 0.5)
			(thermal_bridge_width 0.5)
			(island_removal_mode 0)
		)
		(polygon
			(pts
				(arc
					(start 450.4182 -220.285056)
					(mid 449.7578 -220.285056)
					(end 450.4182 -220.285056)
				)
			)
		)
	)
	(zone
		(layers "In1.Cu" "In2.Cu")
		(hatch none 0.5)
		(connect_pads
			(clearance 0)
		)
		(min_thickness 0.25)
		(keepout
			(tracks not_allowed)
			(vias allowed)
			(pads allowed)
			(copperpour not_allowed)
			(footprints allowed)
		)
		(placement
			(enabled no)
			(sheetname "")
		)
		(fill yes
			(thermal_gap 0.5)
			(thermal_bridge_width 0.5)
			(island_removal_mode 0)
		)
		(polygon
			(pts
				(arc
					(start 285.066232 -283.185108)
					(mid 284.405832 -283.185108)
					(end 285.066232 -283.185108)
				)
			)
		)
	)
	(zone
		(layers "In1.Cu" "In2.Cu")
		(hatch none 0.5)
		(connect_pads
			(clearance 0)
		)
		(min_thickness 0.25)
		(keepout
			(tracks not_allowed)
			(vias allowed)
			(pads allowed)
			(copperpour not_allowed)
			(footprints allowed)
		)
		(placement
			(enabled no)
			(sheetname "")
		)
		(fill yes
			(thermal_gap 0.5)
			(thermal_bridge_width 0.5)
			(island_removal_mode 0)
		)
		(polygon
			(pts
				(arc
					(start 191.490346 -296.785284)
					(mid 190.829946 -296.785284)
					(end 191.490346 -296.785284)
				)
			)
		)
	)
	(zone
		(layers "In1.Cu" "In2.Cu")
		(hatch none 0.5)
		(connect_pads
			(clearance 0)
		)
		(min_thickness 0.25)
		(keepout
			(tracks not_allowed)
			(vias allowed)
			(pads allowed)
			(copperpour not_allowed)
			(footprints allowed)
		)
		(placement
			(enabled no)
			(sheetname "")
		)
		(fill yes
			(thermal_gap 0.5)
			(thermal_bridge_width 0.5)
			(island_removal_mode 0)
		)
		(polygon
			(pts
				(arc
					(start 296.054272 -220.285056)
					(mid 295.393872 -220.285056)
					(end 296.054272 -220.285056)
				)
			)
		)
	)
	(zone
		(layers "In1.Cu" "In2.Cu")
		(hatch none 0.5)
		(connect_pads
			(clearance 0)
		)
		(min_thickness 0.25)
		(keepout
			(tracks not_allowed)
			(vias allowed)
			(pads allowed)
			(copperpour not_allowed)
			(footprints allowed)
		)
		(placement
			(enabled no)
			(sheetname "")
		)
		(fill yes
			(thermal_gap 0.5)
			(thermal_bridge_width 0.5)
			(island_removal_mode 0)
		)
		(polygon
			(pts
				(arc
					(start 29.582364 -313.78525)
					(mid 28.921964 -313.78525)
					(end 29.582364 -313.78525)
				)
			)
		)
	)
	(zone
		(layers "In1.Cu" "In2.Cu")
		(hatch none 0.5)
		(connect_pads
			(clearance 0)
		)
		(min_thickness 0.25)
		(keepout
			(tracks not_allowed)
			(vias allowed)
			(pads allowed)
			(copperpour not_allowed)
			(footprints allowed)
		)
		(placement
			(enabled no)
			(sheetname "")
		)
		(fill yes
			(thermal_gap 0.5)
			(thermal_bridge_width 0.5)
			(island_removal_mode 0)
		)
		(polygon
			(pts
				(arc
					(start 318.892936 -417.242244)
					(mid 318.915254 -417.296126)
					(end 318.969136 -417.318444)
				)
				(arc
					(start 319.164716 -417.318444)
					(mid 319.186592 -417.315312)
					(end 319.206626 -417.305998)
				)
				(arc
					(start 319.50025 -417.113466)
					(mid 319.541906 -417.101064)
					(end 319.583562 -417.113466)
				)
				(arc
					(start 319.878456 -417.305998)
					(mid 319.89838 -417.315234)
					(end 319.920112 -417.318444)
				)
				(arc
					(start 320.114676 -417.318444)
					(mid 320.168558 -417.296126)
					(end 320.190876 -417.242244)
				)
				(arc
					(start 320.190876 -416.556444)
					(mid 320.168558 -416.502562)
					(end 320.114676 -416.480244)
				)
				(arc
					(start 319.920112 -416.480244)
					(mid 319.898368 -416.483412)
					(end 319.878456 -416.49269)
				)
				(arc
					(start 319.582292 -416.685476)
					(mid 319.540608 -416.697698)
					(end 319.49898 -416.685222)
				)
				(arc
					(start 319.205356 -416.49269)
					(mid 319.185432 -416.483454)
					(end 319.1637 -416.480244)
				)
				(arc
					(start 318.969136 -416.480244)
					(mid 318.915254 -416.502562)
					(end 318.892936 -416.556444)
				)
			)
		)
	)
	(zone
		(layers "In1.Cu" "In2.Cu")
		(hatch none 0.5)
		(connect_pads
			(clearance 0)
		)
		(min_thickness 0.25)
		(keepout
			(tracks not_allowed)
			(vias allowed)
			(pads allowed)
			(copperpour not_allowed)
			(footprints allowed)
		)
		(placement
			(enabled no)
			(sheetname "")
		)
		(fill yes
			(thermal_gap 0.5)
			(thermal_bridge_width 0.5)
			(island_removal_mode 0)
		)
		(polygon
			(pts
				(arc
					(start 385.993132 -417.242244)
					(mid 386.01545 -417.296126)
					(end 386.069332 -417.318444)
				)
				(arc
					(start 386.264912 -417.318444)
					(mid 386.286788 -417.315312)
					(end 386.306822 -417.305998)
				)
				(arc
					(start 386.600446 -417.113466)
					(mid 386.642102 -417.101064)
					(end 386.683758 -417.113466)
				)
				(arc
					(start 386.978652 -417.305998)
					(mid 386.998576 -417.315234)
					(end 387.020308 -417.318444)
				)
				(arc
					(start 387.214872 -417.318444)
					(mid 387.268754 -417.296126)
					(end 387.291072 -417.242244)
				)
				(arc
					(start 387.291072 -416.556444)
					(mid 387.268754 -416.502562)
					(end 387.214872 -416.480244)
				)
				(arc
					(start 387.020308 -416.480244)
					(mid 386.998564 -416.483412)
					(end 386.978652 -416.49269)
				)
				(arc
					(start 386.682488 -416.685476)
					(mid 386.640804 -416.697698)
					(end 386.599176 -416.685222)
				)
				(arc
					(start 386.305552 -416.49269)
					(mid 386.285628 -416.483454)
					(end 386.263896 -416.480244)
				)
				(arc
					(start 386.069332 -416.480244)
					(mid 386.01545 -416.502562)
					(end 385.993132 -416.556444)
				)
			)
		)
	)
	(zone
		(layers "In1.Cu" "In2.Cu")
		(hatch none 0.5)
		(connect_pads
			(clearance 0)
		)
		(min_thickness 0.25)
		(keepout
			(tracks not_allowed)
			(vias allowed)
			(pads allowed)
			(copperpour not_allowed)
			(footprints allowed)
		)
		(placement
			(enabled no)
			(sheetname "")
		)
		(fill yes
			(thermal_gap 0.5)
			(thermal_bridge_width 0.5)
			(island_removal_mode 0)
		)
		(polygon
			(pts
				(arc
					(start 25.482296 -265.335258)
					(mid 24.821896 -265.335258)
					(end 25.482296 -265.335258)
				)
			)
		)
	)
	(zone
		(layers "In1.Cu" "In2.Cu")
		(hatch none 0.5)
		(connect_pads
			(clearance 0)
		)
		(min_thickness 0.25)
		(keepout
			(tracks not_allowed)
			(vias allowed)
			(pads allowed)
			(copperpour not_allowed)
			(footprints allowed)
		)
		(placement
			(enabled no)
			(sheetname "")
		)
		(fill yes
			(thermal_gap 0.5)
			(thermal_bridge_width 0.5)
			(island_removal_mode 0)
		)
		(polygon
			(pts
				(arc
					(start 406.21839 -381.824484)
					(mid 406.238314 -381.83372)
					(end 406.260046 -381.83693)
				)
				(arc
					(start 406.45461 -381.83693)
					(mid 406.508492 -381.814612)
					(end 406.53081 -381.76073)
				)
				(arc
					(start 406.53081 -381.07493)
					(mid 406.508492 -381.021048)
					(end 406.45461 -380.99873)
				)
				(arc
					(start 406.260046 -380.99873)
					(mid 406.238302 -381.001898)
					(end 406.21839 -381.011176)
				)
				(arc
					(start 405.922226 -381.203962)
					(mid 405.880542 -381.216184)
					(end 405.838914 -381.203708)
				)
				(arc
					(start 405.54529 -381.011176)
					(mid 405.525366 -381.00194)
					(end 405.503634 -380.99873)
				)
				(arc
					(start 405.30907 -380.99873)
					(mid 405.255188 -381.021048)
					(end 405.23287 -381.07493)
				)
				(arc
					(start 405.23287 -381.76073)
					(mid 405.255188 -381.814612)
					(end 405.30907 -381.83693)
				)
				(arc
					(start 405.504904 -381.83693)
					(mid 405.526648 -381.833762)
					(end 405.54656 -381.824484)
				)
				(arc
					(start 405.840184 -381.631952)
					(mid 405.88184 -381.61955)
					(end 405.923496 -381.631952)
				)
			)
		)
	)
	(zone
		(layers "In1.Cu" "In2.Cu")
		(hatch none 0.5)
		(connect_pads
			(clearance 0)
		)
		(min_thickness 0.25)
		(keepout
			(tracks not_allowed)
			(vias allowed)
			(pads allowed)
			(copperpour not_allowed)
			(footprints allowed)
		)
		(placement
			(enabled no)
			(sheetname "")
		)
		(fill yes
			(thermal_gap 0.5)
			(thermal_bridge_width 0.5)
			(island_removal_mode 0)
		)
		(polygon
			(pts
				(arc
					(start 136.434322 -380.265178)
					(mid 136.425086 -380.285102)
					(end 136.421876 -380.306834)
				)
				(arc
					(start 136.421876 -380.501398)
					(mid 136.444194 -380.55528)
					(end 136.498076 -380.577598)
				)
				(arc
					(start 137.183876 -380.577598)
					(mid 137.237758 -380.55528)
					(end 137.260076 -380.501398)
				)
				(arc
					(start 137.260076 -380.306834)
					(mid 137.256908 -380.28509)
					(end 137.24763 -380.265178)
				)
				(arc
					(start 137.054844 -379.969014)
					(mid 137.042622 -379.92733)
					(end 137.055098 -379.885702)
				)
				(arc
					(start 137.24763 -379.592078)
					(mid 137.256866 -379.572154)
					(end 137.260076 -379.550422)
				)
				(arc
					(start 137.260076 -379.355858)
					(mid 137.237758 -379.301976)
					(end 137.183876 -379.279658)
				)
				(arc
					(start 136.498076 -379.279658)
					(mid 136.444194 -379.301976)
					(end 136.421876 -379.355858)
				)
				(arc
					(start 136.421876 -379.551692)
					(mid 136.425044 -379.573436)
					(end 136.434322 -379.593348)
				)
				(arc
					(start 136.626854 -379.886972)
					(mid 136.639256 -379.928628)
					(end 136.626854 -379.970284)
				)
			)
		)
	)
	(zone
		(layers "In1.Cu" "In2.Cu")
		(hatch none 0.5)
		(connect_pads
			(clearance 0)
		)
		(min_thickness 0.25)
		(keepout
			(tracks not_allowed)
			(vias allowed)
			(pads allowed)
			(copperpour not_allowed)
			(footprints allowed)
		)
		(placement
			(enabled no)
			(sheetname "")
		)
		(fill yes
			(thermal_gap 0.5)
			(thermal_bridge_width 0.5)
			(island_removal_mode 0)
		)
		(polygon
			(pts
				(arc
					(start 450.4182 -241.53495)
					(mid 449.7578 -241.53495)
					(end 450.4182 -241.53495)
				)
			)
		)
	)
	(zone
		(layers "In1.Cu" "In2.Cu")
		(hatch none 0.5)
		(connect_pads
			(clearance 0)
		)
		(min_thickness 0.25)
		(keepout
			(tracks not_allowed)
			(vias allowed)
			(pads allowed)
			(copperpour not_allowed)
			(footprints allowed)
		)
		(placement
			(enabled no)
			(sheetname "")
		)
		(fill yes
			(thermal_gap 0.5)
			(thermal_bridge_width 0.5)
			(island_removal_mode 0)
		)
		(polygon
			(pts
				(arc
					(start 446.974468 -276.38502)
					(mid 446.314068 -276.38502)
					(end 446.974468 -276.38502)
				)
			)
		)
	)
	(zone
		(layers "In1.Cu" "In2.Cu")
		(hatch none 0.5)
		(connect_pads
			(clearance 0)
		)
		(min_thickness 0.25)
		(keepout
			(tracks not_allowed)
			(vias allowed)
			(pads allowed)
			(copperpour not_allowed)
			(footprints allowed)
		)
		(placement
			(enabled no)
			(sheetname "")
		)
		(fill yes
			(thermal_gap 0.5)
			(thermal_bridge_width 0.5)
			(island_removal_mode 0)
		)
		(polygon
			(pts
				(arc
					(start 25.482296 -210.935316)
					(mid 24.821896 -210.935316)
					(end 25.482296 -210.935316)
				)
			)
		)
	)
	(zone
		(layers "In1.Cu" "In2.Cu")
		(hatch none 0.5)
		(connect_pads
			(clearance 0)
		)
		(min_thickness 0.25)
		(keepout
			(tracks not_allowed)
			(vias allowed)
			(pads allowed)
			(copperpour not_allowed)
			(footprints allowed)
		)
		(placement
			(enabled no)
			(sheetname "")
		)
		(fill yes
			(thermal_gap 0.5)
			(thermal_bridge_width 0.5)
			(island_removal_mode 0)
		)
		(polygon
			(pts
				(arc
					(start 439.430414 -245.785132)
					(mid 438.770014 -245.785132)
					(end 439.430414 -245.785132)
				)
			)
		)
	)
	(zone
		(layers "In1.Cu" "In2.Cu")
		(hatch none 0.5)
		(connect_pads
			(clearance 0)
		)
		(min_thickness 0.25)
		(keepout
			(tracks not_allowed)
			(vias allowed)
			(pads allowed)
			(copperpour not_allowed)
			(footprints allowed)
		)
		(placement
			(enabled no)
			(sheetname "")
		)
		(fill yes
			(thermal_gap 0.5)
			(thermal_bridge_width 0.5)
			(island_removal_mode 0)
		)
		(polygon
			(pts
				(arc
					(start 33.026096 -304.435256)
					(mid 32.365696 -304.435256)
					(end 33.026096 -304.435256)
				)
			)
		)
	)
	(zone
		(layers "In1.Cu" "In2.Cu")
		(hatch none 0.5)
		(connect_pads
			(clearance 0)
		)
		(min_thickness 0.25)
		(keepout
			(tracks not_allowed)
			(vias allowed)
			(pads allowed)
			(copperpour not_allowed)
			(footprints allowed)
		)
		(placement
			(enabled no)
			(sheetname "")
		)
		(fill yes
			(thermal_gap 0.5)
			(thermal_bridge_width 0.5)
			(island_removal_mode 0)
		)
		(polygon
			(pts
				(arc
					(start 22.03831 -210.935316)
					(mid 21.37791 -210.935316)
					(end 22.03831 -210.935316)
				)
			)
		)
	)
	(zone
		(layers "In1.Cu" "In2.Cu")
		(hatch none 0.5)
		(connect_pads
			(clearance 0)
		)
		(min_thickness 0.25)
		(keepout
			(tracks not_allowed)
			(vias allowed)
			(pads allowed)
			(copperpour not_allowed)
			(footprints allowed)
		)
		(placement
			(enabled no)
			(sheetname "")
		)
		(fill yes
			(thermal_gap 0.5)
			(thermal_bridge_width 0.5)
			(island_removal_mode 0)
		)
		(polygon
			(pts
				(arc
					(start 48.114204 -289.98545)
					(mid 47.453804 -289.98545)
					(end 48.114204 -289.98545)
				)
			)
		)
	)
	(zone
		(layers "In1.Cu" "In2.Cu")
		(hatch none 0.5)
		(connect_pads
			(clearance 0)
		)
		(min_thickness 0.25)
		(keepout
			(tracks not_allowed)
			(vias allowed)
			(pads allowed)
			(copperpour not_allowed)
			(footprints allowed)
		)
		(placement
			(enabled no)
			(sheetname "")
		)
		(fill yes
			(thermal_gap 0.5)
			(thermal_bridge_width 0.5)
			(island_removal_mode 0)
		)
		(polygon
			(pts
				(arc
					(start 285.066232 -273.835114)
					(mid 284.405832 -273.835114)
					(end 285.066232 -273.835114)
				)
			)
		)
	)
	(zone
		(layers "In1.Cu" "In2.Cu")
		(hatch none 0.5)
		(connect_pads
			(clearance 0)
		)
		(min_thickness 0.25)
		(keepout
			(tracks not_allowed)
			(vias allowed)
			(pads allowed)
			(copperpour not_allowed)
			(footprints allowed)
		)
		(placement
			(enabled no)
			(sheetname "")
		)
		(fill yes
			(thermal_gap 0.5)
			(thermal_bridge_width 0.5)
			(island_removal_mode 0)
		)
		(polygon
			(pts
				(arc
					(start 296.054272 -316.335156)
					(mid 295.393872 -316.335156)
					(end 296.054272 -316.335156)
				)
			)
		)
	)
	(zone
		(layers "In1.Cu" "In2.Cu")
		(hatch none 0.5)
		(connect_pads
			(clearance 0)
		)
		(min_thickness 0.25)
		(keepout
			(tracks not_allowed)
			(vias allowed)
			(pads allowed)
			(copperpour not_allowed)
			(footprints allowed)
		)
		(placement
			(enabled no)
			(sheetname "")
		)
		(fill yes
			(thermal_gap 0.5)
			(thermal_bridge_width 0.5)
			(island_removal_mode 0)
		)
		(polygon
			(pts
				(arc
					(start 40.57015 -265.335258)
					(mid 39.90975 -265.335258)
					(end 40.57015 -265.335258)
				)
			)
		)
	)
	(zone
		(layers "In1.Cu" "In2.Cu")
		(hatch none 0.5)
		(connect_pads
			(clearance 0)
		)
		(min_thickness 0.25)
		(keepout
			(tracks not_allowed)
			(vias allowed)
			(pads allowed)
			(copperpour not_allowed)
			(footprints allowed)
		)
		(placement
			(enabled no)
			(sheetname "")
		)
		(fill yes
			(thermal_gap 0.5)
			(thermal_bridge_width 0.5)
			(island_removal_mode 0)
		)
		(polygon
			(pts
				(arc
					(start 179.846224 -277.235412)
					(mid 179.185824 -277.235412)
					(end 179.846224 -277.235412)
				)
			)
		)
	)
	(zone
		(layers "In1.Cu" "In2.Cu")
		(hatch none 0.5)
		(connect_pads
			(clearance 0)
		)
		(min_thickness 0.25)
		(keepout
			(tracks not_allowed)
			(vias allowed)
			(pads allowed)
			(copperpour not_allowed)
			(footprints allowed)
		)
		(placement
			(enabled no)
			(sheetname "")
		)
		(fill yes
			(thermal_gap 0.5)
			(thermal_bridge_width 0.5)
			(island_removal_mode 0)
		)
		(polygon
			(pts
				(arc
					(start 454.518268 -290.83508)
					(mid 453.857868 -290.83508)
					(end 454.518268 -290.83508)
				)
			)
		)
	)
	(zone
		(layers "In1.Cu" "In2.Cu")
		(hatch none 0.5)
		(connect_pads
			(clearance 0)
		)
		(min_thickness 0.25)
		(keepout
			(tracks not_allowed)
			(vias allowed)
			(pads allowed)
			(copperpour not_allowed)
			(footprints allowed)
		)
		(placement
			(enabled no)
			(sheetname "")
		)
		(fill yes
			(thermal_gap 0.5)
			(thermal_bridge_width 0.5)
			(island_removal_mode 0)
		)
		(polygon
			(pts
				(arc
					(start 446.974468 -313.784996)
					(mid 446.314068 -313.784996)
					(end 446.974468 -313.784996)
				)
			)
		)
	)
	(zone
		(layers "In1.Cu" "In2.Cu")
		(hatch none 0.5)
		(connect_pads
			(clearance 0)
		)
		(min_thickness 0.25)
		(keepout
			(tracks not_allowed)
			(vias allowed)
			(pads allowed)
			(copperpour not_allowed)
			(footprints allowed)
		)
		(placement
			(enabled no)
			(sheetname "")
		)
		(fill yes
			(thermal_gap 0.5)
			(thermal_bridge_width 0.5)
			(island_removal_mode 0)
		)
		(polygon
			(pts
				(arc
					(start 194.934332 -261.935214)
					(mid 194.273932 -261.935214)
					(end 194.934332 -261.935214)
				)
			)
		)
	)
	(zone
		(layers "In1.Cu" "In2.Cu")
		(hatch none 0.5)
		(connect_pads
			(clearance 0)
		)
		(min_thickness 0.25)
		(keepout
			(tracks not_allowed)
			(vias allowed)
			(pads allowed)
			(copperpour not_allowed)
			(footprints allowed)
		)
		(placement
			(enabled no)
			(sheetname "")
		)
		(fill yes
			(thermal_gap 0.5)
			(thermal_bridge_width 0.5)
			(island_removal_mode 0)
		)
		(polygon
			(pts
				(arc
					(start 176.402238 -203.285344)
					(mid 175.741838 -203.285344)
					(end 176.402238 -203.285344)
				)
			)
		)
	)
	(zone
		(layers "In1.Cu" "In2.Cu")
		(hatch none 0.5)
		(connect_pads
			(clearance 0)
		)
		(min_thickness 0.25)
		(keepout
			(tracks not_allowed)
			(vias allowed)
			(pads allowed)
			(copperpour not_allowed)
			(footprints allowed)
		)
		(placement
			(enabled no)
			(sheetname "")
		)
		(fill yes
			(thermal_gap 0.5)
			(thermal_bridge_width 0.5)
			(island_removal_mode 0)
		)
		(polygon
			(pts
				(arc
					(start 25.482296 -230.485442)
					(mid 24.821896 -230.485442)
					(end 25.482296 -230.485442)
				)
			)
		)
	)
	(zone
		(layers "In1.Cu" "In2.Cu")
		(hatch none 0.5)
		(connect_pads
			(clearance 0)
		)
		(min_thickness 0.25)
		(keepout
			(tracks not_allowed)
			(vias allowed)
			(pads allowed)
			(copperpour not_allowed)
			(footprints allowed)
		)
		(placement
			(enabled no)
			(sheetname "")
		)
		(fill yes
			(thermal_gap 0.5)
			(thermal_bridge_width 0.5)
			(island_removal_mode 0)
		)
		(polygon
			(pts
				(arc
					(start 183.946292 -303.585372)
					(mid 183.285892 -303.585372)
					(end 183.946292 -303.585372)
				)
			)
		)
	)
	(zone
		(layers "In1.Cu" "In2.Cu")
		(hatch none 0.5)
		(connect_pads
			(clearance 0)
		)
		(min_thickness 0.25)
		(keepout
			(tracks not_allowed)
			(vias allowed)
			(pads allowed)
			(copperpour not_allowed)
			(footprints allowed)
		)
		(placement
			(enabled no)
			(sheetname "")
		)
		(fill yes
			(thermal_gap 0.5)
			(thermal_bridge_width 0.5)
			(island_removal_mode 0)
		)
		(polygon
			(pts
				(arc
					(start 52.214272 -219.435426)
					(mid 51.553872 -219.435426)
					(end 52.214272 -219.435426)
				)
			)
		)
	)
	(zone
		(layers "In1.Cu" "In2.Cu")
		(hatch none 0.5)
		(connect_pads
			(clearance 0)
		)
		(min_thickness 0.25)
		(keepout
			(tracks not_allowed)
			(vias allowed)
			(pads allowed)
			(copperpour not_allowed)
			(footprints allowed)
		)
		(placement
			(enabled no)
			(sheetname "")
		)
		(fill yes
			(thermal_gap 0.5)
			(thermal_bridge_width 0.5)
			(island_removal_mode 0)
		)
		(polygon
			(pts
				(arc
					(start 446.974468 -208.385156)
					(mid 446.314068 -208.385156)
					(end 446.974468 -208.385156)
				)
			)
		)
	)
	(zone
		(layers "In1.Cu" "In2.Cu")
		(hatch none 0.5)
		(connect_pads
			(clearance 0)
		)
		(min_thickness 0.25)
		(keepout
			(tracks not_allowed)
			(vias allowed)
			(pads allowed)
			(copperpour not_allowed)
			(footprints allowed)
		)
		(placement
			(enabled no)
			(sheetname "")
		)
		(fill yes
			(thermal_gap 0.5)
			(thermal_bridge_width 0.5)
			(island_removal_mode 0)
		)
		(polygon
			(pts
				(arc
					(start 277.522432 -285.735014)
					(mid 276.862032 -285.735014)
					(end 277.522432 -285.735014)
				)
			)
		)
	)
	(zone
		(layers "In1.Cu" "In2.Cu")
		(hatch none 0.5)
		(connect_pads
			(clearance 0)
		)
		(min_thickness 0.25)
		(keepout
			(tracks not_allowed)
			(vias allowed)
			(pads allowed)
			(copperpour not_allowed)
			(footprints allowed)
		)
		(placement
			(enabled no)
			(sheetname "")
		)
		(fill yes
			(thermal_gap 0.5)
			(thermal_bridge_width 0.5)
			(island_removal_mode 0)
		)
		(polygon
			(pts
				(arc
					(start 17.938242 -302.735234)
					(mid 17.277842 -302.735234)
					(end 17.938242 -302.735234)
				)
			)
		)
	)
	(zone
		(layers "In1.Cu" "In2.Cu")
		(hatch none 0.5)
		(connect_pads
			(clearance 0)
		)
		(min_thickness 0.25)
		(keepout
			(tracks not_allowed)
			(vias allowed)
			(pads allowed)
			(copperpour not_allowed)
			(footprints allowed)
		)
		(placement
			(enabled no)
			(sheetname "")
		)
		(fill yes
			(thermal_gap 0.5)
			(thermal_bridge_width 0.5)
			(island_removal_mode 0)
		)
		(polygon
			(pts
				(arc
					(start 179.846224 -318.035432)
					(mid 179.185824 -318.035432)
					(end 179.846224 -318.035432)
				)
			)
		)
	)
	(zone
		(layers "In1.Cu" "In2.Cu")
		(hatch none 0.5)
		(connect_pads
			(clearance 0)
		)
		(min_thickness 0.25)
		(keepout
			(tracks not_allowed)
			(vias allowed)
			(pads allowed)
			(copperpour not_allowed)
			(footprints allowed)
		)
		(placement
			(enabled no)
			(sheetname "")
		)
		(fill yes
			(thermal_gap 0.5)
			(thermal_bridge_width 0.5)
			(island_removal_mode 0)
		)
		(polygon
			(pts
				(arc
					(start 199.034146 -244.08511)
					(mid 198.373746 -244.08511)
					(end 199.034146 -244.08511)
				)
			)
		)
	)
	(zone
		(layers "In1.Cu" "In2.Cu")
		(hatch none 0.5)
		(connect_pads
			(clearance 0)
		)
		(min_thickness 0.25)
		(keepout
			(tracks not_allowed)
			(vias allowed)
			(pads allowed)
			(copperpour not_allowed)
			(footprints allowed)
		)
		(placement
			(enabled no)
			(sheetname "")
		)
		(fill yes
			(thermal_gap 0.5)
			(thermal_bridge_width 0.5)
			(island_removal_mode 0)
		)
		(polygon
			(pts
				(arc
					(start 280.966164 -312.084974)
					(mid 280.305764 -312.084974)
					(end 280.966164 -312.084974)
				)
			)
		)
	)
	(zone
		(layers "In1.Cu" "In2.Cu")
		(hatch none 0.5)
		(connect_pads
			(clearance 0)
		)
		(min_thickness 0.25)
		(keepout
			(tracks not_allowed)
			(vias allowed)
			(pads allowed)
			(copperpour not_allowed)
			(footprints allowed)
		)
		(placement
			(enabled no)
			(sheetname "")
		)
		(fill yes
			(thermal_gap 0.5)
			(thermal_bridge_width 0.5)
			(island_removal_mode 0)
		)
		(polygon
			(pts
				(arc
					(start 292.610286 -309.535068)
					(mid 291.949886 -309.535068)
					(end 292.610286 -309.535068)
				)
			)
		)
	)
	(zone
		(layers "In1.Cu" "In2.Cu")
		(hatch none 0.5)
		(connect_pads
			(clearance 0)
		)
		(min_thickness 0.25)
		(keepout
			(tracks not_allowed)
			(vias allowed)
			(pads allowed)
			(copperpour not_allowed)
			(footprints allowed)
		)
		(placement
			(enabled no)
			(sheetname "")
		)
		(fill yes
			(thermal_gap 0.5)
			(thermal_bridge_width 0.5)
			(island_removal_mode 0)
		)
		(polygon
			(pts
				(arc
					(start 277.522432 -228.785166)
					(mid 276.862032 -228.785166)
					(end 277.522432 -228.785166)
				)
			)
		)
	)
	(zone
		(layers "In1.Cu" "In2.Cu")
		(hatch none 0.5)
		(connect_pads
			(clearance 0)
		)
		(min_thickness 0.25)
		(keepout
			(tracks not_allowed)
			(vias allowed)
			(pads allowed)
			(copperpour not_allowed)
			(footprints allowed)
		)
		(placement
			(enabled no)
			(sheetname "")
		)
		(fill yes
			(thermal_gap 0.5)
			(thermal_bridge_width 0.5)
			(island_removal_mode 0)
		)
		(polygon
			(pts
				(arc
					(start 52.214272 -216.035382)
					(mid 51.553872 -216.035382)
					(end 52.214272 -216.035382)
				)
			)
		)
	)
	(zone
		(layers "In1.Cu" "In2.Cu")
		(hatch none 0.5)
		(connect_pads
			(clearance 0)
		)
		(min_thickness 0.25)
		(keepout
			(tracks not_allowed)
			(vias allowed)
			(pads allowed)
			(copperpour not_allowed)
			(footprints allowed)
		)
		(placement
			(enabled no)
			(sheetname "")
		)
		(fill yes
			(thermal_gap 0.5)
			(thermal_bridge_width 0.5)
			(island_removal_mode 0)
		)
		(polygon
			(pts
				(arc
					(start 424.342306 -242.385088)
					(mid 423.681906 -242.385088)
					(end 424.342306 -242.385088)
				)
			)
		)
	)
	(zone
		(layers "In1.Cu" "In2.Cu")
		(hatch none 0.5)
		(connect_pads
			(clearance 0)
		)
		(min_thickness 0.25)
		(keepout
			(tracks not_allowed)
			(vias allowed)
			(pads allowed)
			(copperpour not_allowed)
			(footprints allowed)
		)
		(placement
			(enabled no)
			(sheetname "")
		)
		(fill yes
			(thermal_gap 0.5)
			(thermal_bridge_width 0.5)
			(island_removal_mode 0)
		)
		(polygon
			(pts
				(arc
					(start 44.670218 -307.8353)
					(mid 44.009818 -307.8353)
					(end 44.670218 -307.8353)
				)
			)
		)
	)
	(zone
		(layers "In1.Cu" "In2.Cu")
		(hatch none 0.5)
		(connect_pads
			(clearance 0)
		)
		(min_thickness 0.25)
		(keepout
			(tracks not_allowed)
			(vias allowed)
			(pads allowed)
			(copperpour not_allowed)
			(footprints allowed)
		)
		(placement
			(enabled no)
			(sheetname "")
		)
		(fill yes
			(thermal_gap 0.5)
			(thermal_bridge_width 0.5)
			(island_removal_mode 0)
		)
		(polygon
			(pts
				(arc
					(start 446.974468 -278.085042)
					(mid 446.314068 -278.085042)
					(end 446.974468 -278.085042)
				)
			)
		)
	)
	(zone
		(layers "In1.Cu" "In2.Cu")
		(hatch none 0.5)
		(connect_pads
			(clearance 0)
		)
		(min_thickness 0.25)
		(keepout
			(tracks not_allowed)
			(vias allowed)
			(pads allowed)
			(copperpour not_allowed)
			(footprints allowed)
		)
		(placement
			(enabled no)
			(sheetname "")
		)
		(fill yes
			(thermal_gap 0.5)
			(thermal_bridge_width 0.5)
			(island_removal_mode 0)
		)
		(polygon
			(pts
				(arc
					(start 168.96207 -380.265178)
					(mid 168.952834 -380.285102)
					(end 168.949624 -380.306834)
				)
				(arc
					(start 168.949624 -380.501398)
					(mid 168.971942 -380.55528)
					(end 169.025824 -380.577598)
				)
				(arc
					(start 169.711624 -380.577598)
					(mid 169.765506 -380.55528)
					(end 169.787824 -380.501398)
				)
				(arc
					(start 169.787824 -380.306834)
					(mid 169.784656 -380.28509)
					(end 169.775378 -380.265178)
				)
				(arc
					(start 169.582592 -379.969014)
					(mid 169.57037 -379.92733)
					(end 169.582846 -379.885702)
				)
				(arc
					(start 169.775378 -379.592078)
					(mid 169.784614 -379.572154)
					(end 169.787824 -379.550422)
				)
				(arc
					(start 169.787824 -379.355858)
					(mid 169.765506 -379.301976)
					(end 169.711624 -379.279658)
				)
				(arc
					(start 169.025824 -379.279658)
					(mid 168.971942 -379.301976)
					(end 168.949624 -379.355858)
				)
				(arc
					(start 168.949624 -379.551692)
					(mid 168.952792 -379.573436)
					(end 168.96207 -379.593348)
				)
				(arc
					(start 169.154602 -379.886972)
					(mid 169.167004 -379.928628)
					(end 169.154602 -379.970284)
				)
			)
		)
	)
	(zone
		(layers "In1.Cu" "In2.Cu")
		(hatch none 0.5)
		(connect_pads
			(clearance 0)
		)
		(min_thickness 0.25)
		(keepout
			(tracks not_allowed)
			(vias allowed)
			(pads allowed)
			(copperpour not_allowed)
			(footprints allowed)
		)
		(placement
			(enabled no)
			(sheetname "")
		)
		(fill yes
			(thermal_gap 0.5)
			(thermal_bridge_width 0.5)
			(island_removal_mode 0)
		)
		(polygon
			(pts
				(arc
					(start 172.30217 -318.035432)
					(mid 171.64177 -318.035432)
					(end 172.30217 -318.035432)
				)
			)
		)
	)
	(zone
		(layers "In1.Cu" "In2.Cu")
		(hatch none 0.5)
		(connect_pads
			(clearance 0)
		)
		(min_thickness 0.25)
		(keepout
			(tracks not_allowed)
			(vias allowed)
			(pads allowed)
			(copperpour not_allowed)
			(footprints allowed)
		)
		(placement
			(enabled no)
			(sheetname "")
		)
		(fill yes
			(thermal_gap 0.5)
			(thermal_bridge_width 0.5)
			(island_removal_mode 0)
		)
		(polygon
			(pts
				(arc
					(start 427.786292 -207.535018)
					(mid 427.125892 -207.535018)
					(end 427.786292 -207.535018)
				)
			)
		)
	)
	(zone
		(layers "In1.Cu" "In2.Cu")
		(hatch none 0.5)
		(connect_pads
			(clearance 0)
		)
		(min_thickness 0.25)
		(keepout
			(tracks not_allowed)
			(vias allowed)
			(pads allowed)
			(copperpour not_allowed)
			(footprints allowed)
		)
		(placement
			(enabled no)
			(sheetname "")
		)
		(fill yes
			(thermal_gap 0.5)
			(thermal_bridge_width 0.5)
			(island_removal_mode 0)
		)
		(polygon
			(pts
				(arc
					(start 40.57015 -280.635202)
					(mid 39.90975 -280.635202)
					(end 40.57015 -280.635202)
				)
			)
		)
	)
	(zone
		(layers "In1.Cu" "In2.Cu")
		(hatch none 0.5)
		(connect_pads
			(clearance 0)
		)
		(min_thickness 0.25)
		(keepout
			(tracks not_allowed)
			(vias allowed)
			(pads allowed)
			(copperpour not_allowed)
			(footprints allowed)
		)
		(placement
			(enabled no)
			(sheetname "")
		)
		(fill yes
			(thermal_gap 0.5)
			(thermal_bridge_width 0.5)
			(island_removal_mode 0)
		)
		(polygon
			(pts
				(arc
					(start 285.066232 -242.385088)
					(mid 284.405832 -242.385088)
					(end 285.066232 -242.385088)
				)
			)
		)
	)
	(zone
		(layers "In1.Cu" "In2.Cu")
		(hatch none 0.5)
		(connect_pads
			(clearance 0)
		)
		(min_thickness 0.25)
		(keepout
			(tracks not_allowed)
			(vias allowed)
			(pads allowed)
			(copperpour not_allowed)
			(footprints allowed)
		)
		(placement
			(enabled no)
			(sheetname "")
		)
		(fill yes
			(thermal_gap 0.5)
			(thermal_bridge_width 0.5)
			(island_removal_mode 0)
		)
		(polygon
			(pts
				(arc
					(start 300.15434 -212.635084)
					(mid 299.49394 -212.635084)
					(end 300.15434 -212.635084)
				)
			)
		)
	)
	(zone
		(layers "In1.Cu" "In2.Cu")
		(hatch none 0.5)
		(connect_pads
			(clearance 0)
		)
		(min_thickness 0.25)
		(keepout
			(tracks not_allowed)
			(vias allowed)
			(pads allowed)
			(copperpour not_allowed)
			(footprints allowed)
		)
		(placement
			(enabled no)
			(sheetname "")
		)
		(fill yes
			(thermal_gap 0.5)
			(thermal_bridge_width 0.5)
			(island_removal_mode 0)
		)
		(polygon
			(pts
				(arc
					(start 450.4182 -280.634948)
					(mid 449.7578 -280.634948)
					(end 450.4182 -280.634948)
				)
			)
		)
	)
	(zone
		(layers "In1.Cu" "In2.Cu")
		(hatch none 0.5)
		(connect_pads
			(clearance 0)
		)
		(min_thickness 0.25)
		(keepout
			(tracks not_allowed)
			(vias allowed)
			(pads allowed)
			(copperpour not_allowed)
			(footprints allowed)
		)
		(placement
			(enabled no)
			(sheetname "")
		)
		(fill yes
			(thermal_gap 0.5)
			(thermal_bridge_width 0.5)
			(island_removal_mode 0)
		)
		(polygon
			(pts
				(arc
					(start 439.430414 -294.235124)
					(mid 438.770014 -294.235124)
					(end 439.430414 -294.235124)
				)
			)
		)
	)
	(zone
		(layers "In1.Cu" "In2.Cu")
		(hatch none 0.5)
		(connect_pads
			(clearance 0)
		)
		(min_thickness 0.25)
		(keepout
			(tracks not_allowed)
			(vias allowed)
			(pads allowed)
			(copperpour not_allowed)
			(footprints allowed)
		)
		(placement
			(enabled no)
			(sheetname "")
		)
		(fill yes
			(thermal_gap 0.5)
			(thermal_bridge_width 0.5)
			(island_removal_mode 0)
		)
		(polygon
			(pts
				(arc
					(start 191.490346 -197.335394)
					(mid 190.829946 -197.335394)
					(end 191.490346 -197.335394)
				)
			)
		)
	)
	(zone
		(layers "In1.Cu" "In2.Cu")
		(hatch none 0.5)
		(connect_pads
			(clearance 0)
		)
		(min_thickness 0.25)
		(keepout
			(tracks not_allowed)
			(vias allowed)
			(pads allowed)
			(copperpour not_allowed)
			(footprints allowed)
		)
		(placement
			(enabled no)
			(sheetname "")
		)
		(fill yes
			(thermal_gap 0.5)
			(thermal_bridge_width 0.5)
			(island_removal_mode 0)
		)
		(polygon
			(pts
				(arc
					(start 25.482296 -308.685438)
					(mid 24.821896 -308.685438)
					(end 25.482296 -308.685438)
				)
			)
		)
	)
	(zone
		(layers "In1.Cu" "In2.Cu")
		(hatch none 0.5)
		(connect_pads
			(clearance 0)
		)
		(min_thickness 0.25)
		(keepout
			(tracks not_allowed)
			(vias allowed)
			(pads allowed)
			(copperpour not_allowed)
			(footprints allowed)
		)
		(placement
			(enabled no)
			(sheetname "")
		)
		(fill yes
			(thermal_gap 0.5)
			(thermal_bridge_width 0.5)
			(island_removal_mode 0)
		)
		(polygon
			(pts
				(arc
					(start 22.03831 -307.8353)
					(mid 21.37791 -307.8353)
					(end 22.03831 -307.8353)
				)
			)
		)
	)
	(zone
		(layers "In1.Cu" "In2.Cu")
		(hatch none 0.5)
		(connect_pads
			(clearance 0)
		)
		(min_thickness 0.25)
		(keepout
			(tracks not_allowed)
			(vias allowed)
			(pads allowed)
			(copperpour not_allowed)
			(footprints allowed)
		)
		(placement
			(enabled no)
			(sheetname "")
		)
		(fill yes
			(thermal_gap 0.5)
			(thermal_bridge_width 0.5)
			(island_removal_mode 0)
		)
		(polygon
			(pts
				(arc
					(start 187.390278 -263.635236)
					(mid 186.729878 -263.635236)
					(end 187.390278 -263.635236)
				)
			)
		)
	)
	(zone
		(layers "In1.Cu" "In2.Cu")
		(hatch none 0.5)
		(connect_pads
			(clearance 0)
		)
		(min_thickness 0.25)
		(keepout
			(tracks not_allowed)
			(vias allowed)
			(pads allowed)
			(copperpour not_allowed)
			(footprints allowed)
		)
		(placement
			(enabled no)
			(sheetname "")
		)
		(fill yes
			(thermal_gap 0.5)
			(thermal_bridge_width 0.5)
			(island_removal_mode 0)
		)
		(polygon
			(pts
				(arc
					(start 454.518268 -278.085042)
					(mid 453.857868 -278.085042)
					(end 454.518268 -278.085042)
				)
			)
		)
	)
	(zone
		(layers "In1.Cu" "In2.Cu")
		(hatch none 0.5)
		(connect_pads
			(clearance 0)
		)
		(min_thickness 0.25)
		(keepout
			(tracks not_allowed)
			(vias allowed)
			(pads allowed)
			(copperpour not_allowed)
			(footprints allowed)
		)
		(placement
			(enabled no)
			(sheetname "")
		)
		(fill yes
			(thermal_gap 0.5)
			(thermal_bridge_width 0.5)
			(island_removal_mode 0)
		)
		(polygon
			(pts
				(arc
					(start 446.974468 -272.135092)
					(mid 446.314068 -272.135092)
					(end 446.974468 -272.135092)
				)
			)
		)
	)
	(zone
		(layers "In1.Cu" "In2.Cu")
		(hatch none 0.5)
		(connect_pads
			(clearance 0)
		)
		(min_thickness 0.25)
		(keepout
			(tracks not_allowed)
			(vias allowed)
			(pads allowed)
			(copperpour not_allowed)
			(footprints allowed)
		)
		(placement
			(enabled no)
			(sheetname "")
		)
		(fill yes
			(thermal_gap 0.5)
			(thermal_bridge_width 0.5)
			(island_removal_mode 0)
		)
		(polygon
			(pts
				(arc
					(start 44.670218 -216.035382)
					(mid 44.009818 -216.035382)
					(end 44.670218 -216.035382)
				)
			)
		)
	)
	(zone
		(layers "In1.Cu" "In2.Cu")
		(hatch none 0.5)
		(connect_pads
			(clearance 0)
		)
		(min_thickness 0.25)
		(keepout
			(tracks not_allowed)
			(vias allowed)
			(pads allowed)
			(copperpour not_allowed)
			(footprints allowed)
		)
		(placement
			(enabled no)
			(sheetname "")
		)
		(fill yes
			(thermal_gap 0.5)
			(thermal_bridge_width 0.5)
			(island_removal_mode 0)
		)
		(polygon
			(pts
				(arc
					(start 446.974468 -210.085178)
					(mid 446.314068 -210.085178)
					(end 446.974468 -210.085178)
				)
			)
		)
	)
	(zone
		(layers "In1.Cu" "In2.Cu")
		(hatch none 0.5)
		(connect_pads
			(clearance 0)
		)
		(min_thickness 0.25)
		(keepout
			(tracks not_allowed)
			(vias allowed)
			(pads allowed)
			(copperpour not_allowed)
			(footprints allowed)
		)
		(placement
			(enabled no)
			(sheetname "")
		)
		(fill yes
			(thermal_gap 0.5)
			(thermal_bridge_width 0.5)
			(island_removal_mode 0)
		)
		(polygon
			(pts
				(arc
					(start 194.934332 -209.235294)
					(mid 194.273932 -209.235294)
					(end 194.934332 -209.235294)
				)
			)
		)
	)
	(zone
		(layers "In1.Cu" "In2.Cu")
		(hatch none 0.5)
		(connect_pads
			(clearance 0)
		)
		(min_thickness 0.25)
		(keepout
			(tracks not_allowed)
			(vias allowed)
			(pads allowed)
			(copperpour not_allowed)
			(footprints allowed)
		)
		(placement
			(enabled no)
			(sheetname "")
		)
		(fill yes
			(thermal_gap 0.5)
			(thermal_bridge_width 0.5)
			(island_removal_mode 0)
		)
		(polygon
			(pts
				(arc
					(start 439.430414 -304.435002)
					(mid 438.770014 -304.435002)
					(end 439.430414 -304.435002)
				)
			)
		)
	)
	(zone
		(layers "In1.Cu" "In2.Cu")
		(hatch none 0.5)
		(connect_pads
			(clearance 0)
		)
		(min_thickness 0.25)
		(keepout
			(tracks not_allowed)
			(vias allowed)
			(pads allowed)
			(copperpour not_allowed)
			(footprints allowed)
		)
		(placement
			(enabled no)
			(sheetname "")
		)
		(fill yes
			(thermal_gap 0.5)
			(thermal_bridge_width 0.5)
			(island_removal_mode 0)
		)
		(polygon
			(pts
				(arc
					(start 194.934332 -253.435358)
					(mid 194.273932 -253.435358)
					(end 194.934332 -253.435358)
				)
			)
		)
	)
	(zone
		(layers "In1.Cu" "In2.Cu")
		(hatch none 0.5)
		(connect_pads
			(clearance 0)
		)
		(min_thickness 0.25)
		(keepout
			(tracks not_allowed)
			(vias allowed)
			(pads allowed)
			(copperpour not_allowed)
			(footprints allowed)
		)
		(placement
			(enabled no)
			(sheetname "")
		)
		(fill yes
			(thermal_gap 0.5)
			(thermal_bridge_width 0.5)
			(island_removal_mode 0)
		)
		(polygon
			(pts
				(arc
					(start 199.0344 -296.785284)
					(mid 198.374 -296.785284)
					(end 199.0344 -296.785284)
				)
			)
		)
	)
	(zone
		(layers "In1.Cu" "In2.Cu")
		(hatch none 0.5)
		(connect_pads
			(clearance 0)
		)
		(min_thickness 0.25)
		(keepout
			(tracks not_allowed)
			(vias allowed)
			(pads allowed)
			(copperpour not_allowed)
			(footprints allowed)
		)
		(placement
			(enabled no)
			(sheetname "")
		)
		(fill yes
			(thermal_gap 0.5)
			(thermal_bridge_width 0.5)
			(island_removal_mode 0)
		)
		(polygon
			(pts
				(arc
					(start 29.041598 -11.91768)
					(mid 29.01928 -11.971562)
					(end 28.965398 -11.99388)
				)
				(arc
					(start 27.928824 -11.99388)
					(mid 27.874942 -11.971562)
					(end 27.852624 -11.91768)
				)
				(arc
					(start 27.852624 -10.51814)
					(mid 27.874942 -10.464258)
					(end 27.928824 -10.44194)
				)
				(arc
					(start 28.965398 -10.44194)
					(mid 29.01928 -10.464258)
					(end 29.041598 -10.51814)
				)
			)
		)
	)
	(zone
		(layers "In1.Cu" "In2.Cu")
		(hatch none 0.5)
		(connect_pads
			(clearance 0)
		)
		(min_thickness 0.25)
		(keepout
			(tracks not_allowed)
			(vias allowed)
			(pads allowed)
			(copperpour not_allowed)
			(footprints allowed)
		)
		(placement
			(enabled no)
			(sheetname "")
		)
		(fill yes
			(thermal_gap 0.5)
			(thermal_bridge_width 0.5)
			(island_removal_mode 0)
		)
		(polygon
			(pts
				(arc
					(start 160.625536 -408.860244)
					(mid 160.647854 -408.914126)
					(end 160.701736 -408.936444)
				)
				(arc
					(start 160.897316 -408.936444)
					(mid 160.919192 -408.933312)
					(end 160.939226 -408.923998)
				)
				(arc
					(start 161.23285 -408.731466)
					(mid 161.274506 -408.719064)
					(end 161.316162 -408.731466)
				)
				(arc
					(start 161.611056 -408.923998)
					(mid 161.63098 -408.933234)
					(end 161.652712 -408.936444)
				)
				(arc
					(start 161.847276 -408.936444)
					(mid 161.901158 -408.914126)
					(end 161.923476 -408.860244)
				)
				(arc
					(start 161.923476 -408.174444)
					(mid 161.901158 -408.120562)
					(end 161.847276 -408.098244)
				)
				(arc
					(start 161.652712 -408.098244)
					(mid 161.630968 -408.101412)
					(end 161.611056 -408.11069)
				)
				(arc
					(start 161.314892 -408.303476)
					(mid 161.273208 -408.315698)
					(end 161.23158 -408.303222)
				)
				(arc
					(start 160.937956 -408.11069)
					(mid 160.918032 -408.101454)
					(end 160.8963 -408.098244)
				)
				(arc
					(start 160.701736 -408.098244)
					(mid 160.647854 -408.120562)
					(end 160.625536 -408.174444)
				)
			)
		)
	)
	(zone
		(layers "In1.Cu" "In2.Cu")
		(hatch none 0.5)
		(connect_pads
			(clearance 0)
		)
		(min_thickness 0.25)
		(keepout
			(tracks not_allowed)
			(vias allowed)
			(pads allowed)
			(copperpour not_allowed)
			(footprints allowed)
		)
		(placement
			(enabled no)
			(sheetname "")
		)
		(fill yes
			(thermal_gap 0.5)
			(thermal_bridge_width 0.5)
			(island_removal_mode 0)
		)
		(polygon
			(pts
				(arc
					(start 431.672238 -7.672324)
					(mid 431.694556 -7.618442)
					(end 431.748438 -7.596124)
				)
				(arc
					(start 432.785012 -7.596124)
					(mid 432.838894 -7.618442)
					(end 432.861212 -7.672324)
				)
				(arc
					(start 432.861212 -9.071864)
					(mid 432.838894 -9.125746)
					(end 432.785012 -9.148064)
				)
				(arc
					(start 431.748438 -9.148064)
					(mid 431.694556 -9.125746)
					(end 431.672238 -9.071864)
				)
			)
		)
	)
	(zone
		(layers "In1.Cu" "In2.Cu")
		(hatch none 0.5)
		(connect_pads
			(clearance 0)
		)
		(min_thickness 0.25)
		(keepout
			(tracks not_allowed)
			(vias allowed)
			(pads allowed)
			(copperpour not_allowed)
			(footprints allowed)
		)
		(placement
			(enabled no)
			(sheetname "")
		)
		(fill yes
			(thermal_gap 0.5)
			(thermal_bridge_width 0.5)
			(island_removal_mode 0)
		)
		(polygon
			(pts
				(arc
					(start 288.510218 -237.285022)
					(mid 287.849818 -237.285022)
					(end 288.510218 -237.285022)
				)
			)
		)
	)
	(zone
		(layers "In1.Cu" "In2.Cu")
		(hatch none 0.5)
		(connect_pads
			(clearance 0)
		)
		(min_thickness 0.25)
		(keepout
			(tracks not_allowed)
			(vias allowed)
			(pads allowed)
			(copperpour not_allowed)
			(footprints allowed)
		)
		(placement
			(enabled no)
			(sheetname "")
		)
		(fill yes
			(thermal_gap 0.5)
			(thermal_bridge_width 0.5)
			(island_removal_mode 0)
		)
		(polygon
			(pts
				(arc
					(start 22.03831 -315.485272)
					(mid 21.37791 -315.485272)
					(end 22.03831 -315.485272)
				)
			)
		)
	)
	(zone
		(layers "In1.Cu" "In2.Cu")
		(hatch none 0.5)
		(connect_pads
			(clearance 0)
		)
		(min_thickness 0.25)
		(keepout
			(tracks not_allowed)
			(vias allowed)
			(pads allowed)
			(copperpour not_allowed)
			(footprints allowed)
		)
		(placement
			(enabled no)
			(sheetname "")
		)
		(fill yes
			(thermal_gap 0.5)
			(thermal_bridge_width 0.5)
			(island_removal_mode 0)
		)
		(polygon
			(pts
				(arc
					(start 280.966164 -299.33519)
					(mid 280.305764 -299.33519)
					(end 280.966164 -299.33519)
				)
			)
		)
	)
	(zone
		(layers "In1.Cu" "In2.Cu")
		(hatch none 0.5)
		(connect_pads
			(clearance 0)
		)
		(min_thickness 0.25)
		(keepout
			(tracks not_allowed)
			(vias allowed)
			(pads allowed)
			(copperpour not_allowed)
			(footprints allowed)
		)
		(placement
			(enabled no)
			(sheetname "")
		)
		(fill yes
			(thermal_gap 0.5)
			(thermal_bridge_width 0.5)
			(island_removal_mode 0)
		)
		(polygon
			(pts
				(arc
					(start 300.15434 -229.63505)
					(mid 299.49394 -229.63505)
					(end 300.15434 -229.63505)
				)
			)
		)
	)
	(zone
		(layers "In1.Cu" "In2.Cu")
		(hatch none 0.5)
		(connect_pads
			(clearance 0)
		)
		(min_thickness 0.25)
		(keepout
			(tracks not_allowed)
			(vias allowed)
			(pads allowed)
			(copperpour not_allowed)
			(footprints allowed)
		)
		(placement
			(enabled no)
			(sheetname "")
		)
		(fill yes
			(thermal_gap 0.5)
			(thermal_bridge_width 0.5)
			(island_removal_mode 0)
		)
		(polygon
			(pts
				(arc
					(start 439.430414 -250.884944)
					(mid 438.770014 -250.884944)
					(end 439.430414 -250.884944)
				)
			)
		)
	)
	(zone
		(layers "In1.Cu" "In2.Cu")
		(hatch none 0.5)
		(connect_pads
			(clearance 0)
		)
		(min_thickness 0.25)
		(keepout
			(tracks not_allowed)
			(vias allowed)
			(pads allowed)
			(copperpour not_allowed)
			(footprints allowed)
		)
		(placement
			(enabled no)
			(sheetname "")
		)
		(fill yes
			(thermal_gap 0.5)
			(thermal_bridge_width 0.5)
			(island_removal_mode 0)
		)
		(polygon
			(pts
				(arc
					(start 176.402238 -270.435324)
					(mid 175.741838 -270.435324)
					(end 176.402238 -270.435324)
				)
			)
		)
	)
	(zone
		(layers "In1.Cu" "In2.Cu")
		(hatch none 0.5)
		(connect_pads
			(clearance 0)
		)
		(min_thickness 0.25)
		(keepout
			(tracks not_allowed)
			(vias allowed)
			(pads allowed)
			(copperpour not_allowed)
			(footprints allowed)
		)
		(placement
			(enabled no)
			(sheetname "")
		)
		(fill yes
			(thermal_gap 0.5)
			(thermal_bridge_width 0.5)
			(island_removal_mode 0)
		)
		(polygon
			(pts
				(arc
					(start 122.796046 -375.906284)
					(mid 122.81597 -375.91552)
					(end 122.837702 -375.91873)
				)
				(arc
					(start 123.032266 -375.91873)
					(mid 123.086148 -375.896412)
					(end 123.108466 -375.84253)
				)
				(arc
					(start 123.108466 -375.15673)
					(mid 123.086148 -375.102848)
					(end 123.032266 -375.08053)
				)
				(arc
					(start 122.837702 -375.08053)
					(mid 122.815958 -375.083698)
					(end 122.796046 -375.092976)
				)
				(arc
					(start 122.499882 -375.285762)
					(mid 122.458198 -375.297984)
					(end 122.41657 -375.285508)
				)
				(arc
					(start 122.122946 -375.092976)
					(mid 122.103022 -375.08374)
					(end 122.08129 -375.08053)
				)
				(arc
					(start 121.886726 -375.08053)
					(mid 121.832844 -375.102848)
					(end 121.810526 -375.15673)
				)
				(arc
					(start 121.810526 -375.84253)
					(mid 121.832844 -375.896412)
					(end 121.886726 -375.91873)
				)
				(arc
					(start 122.08256 -375.91873)
					(mid 122.104304 -375.915562)
					(end 122.124216 -375.906284)
				)
				(arc
					(start 122.41784 -375.713752)
					(mid 122.459496 -375.70135)
					(end 122.501152 -375.713752)
				)
			)
		)
	)
	(zone
		(layers "In1.Cu" "In2.Cu")
		(hatch none 0.5)
		(connect_pads
			(clearance 0)
		)
		(min_thickness 0.25)
		(keepout
			(tracks not_allowed)
			(vias allowed)
			(pads allowed)
			(copperpour not_allowed)
			(footprints allowed)
		)
		(placement
			(enabled no)
			(sheetname "")
		)
		(fill yes
			(thermal_gap 0.5)
			(thermal_bridge_width 0.5)
			(island_removal_mode 0)
		)
		(polygon
			(pts
				(arc
					(start 285.066232 -272.135092)
					(mid 284.405832 -272.135092)
					(end 285.066232 -272.135092)
				)
			)
		)
	)
	(zone
		(layers "In1.Cu" "In2.Cu")
		(hatch none 0.5)
		(connect_pads
			(clearance 0)
		)
		(min_thickness 0.25)
		(keepout
			(tracks not_allowed)
			(vias allowed)
			(pads allowed)
			(copperpour not_allowed)
			(footprints allowed)
		)
		(placement
			(enabled no)
			(sheetname "")
		)
		(fill yes
			(thermal_gap 0.5)
			(thermal_bridge_width 0.5)
			(island_removal_mode 0)
		)
		(polygon
			(pts
				(arc
					(start 191.490346 -272.135346)
					(mid 190.829946 -272.135346)
					(end 191.490346 -272.135346)
				)
			)
		)
	)
	(zone
		(layers "In1.Cu" "In2.Cu")
		(hatch none 0.5)
		(connect_pads
			(clearance 0)
		)
		(min_thickness 0.25)
		(keepout
			(tracks not_allowed)
			(vias allowed)
			(pads allowed)
			(copperpour not_allowed)
			(footprints allowed)
		)
		(placement
			(enabled no)
			(sheetname "")
		)
		(fill yes
			(thermal_gap 0.5)
			(thermal_bridge_width 0.5)
			(island_removal_mode 0)
		)
		(polygon
			(pts
				(arc
					(start 33.026096 -218.585288)
					(mid 32.365696 -218.585288)
					(end 33.026096 -218.585288)
				)
			)
		)
	)
	(zone
		(layers "In1.Cu" "In2.Cu")
		(hatch none 0.5)
		(connect_pads
			(clearance 0)
		)
		(min_thickness 0.25)
		(keepout
			(tracks not_allowed)
			(vias allowed)
			(pads allowed)
			(copperpour not_allowed)
			(footprints allowed)
		)
		(placement
			(enabled no)
			(sheetname "")
		)
		(fill yes
			(thermal_gap 0.5)
			(thermal_bridge_width 0.5)
			(island_removal_mode 0)
		)
		(polygon
			(pts
				(arc
					(start 273.422364 -278.93518)
					(mid 272.761964 -278.93518)
					(end 273.422364 -278.93518)
				)
			)
		)
	)
	(zone
		(layers "In1.Cu" "In2.Cu")
		(hatch none 0.5)
		(connect_pads
			(clearance 0)
		)
		(min_thickness 0.25)
		(keepout
			(tracks not_allowed)
			(vias allowed)
			(pads allowed)
			(copperpour not_allowed)
			(footprints allowed)
		)
		(placement
			(enabled no)
			(sheetname "")
		)
		(fill yes
			(thermal_gap 0.5)
			(thermal_bridge_width 0.5)
			(island_removal_mode 0)
		)
		(polygon
			(pts
				(arc
					(start 199.0344 -292.535356)
					(mid 198.374 -292.535356)
					(end 199.0344 -292.535356)
				)
			)
		)
	)
	(zone
		(layers "In1.Cu" "In2.Cu")
		(hatch none 0.5)
		(connect_pads
			(clearance 0)
		)
		(min_thickness 0.25)
		(keepout
			(tracks not_allowed)
			(vias allowed)
			(pads allowed)
			(copperpour not_allowed)
			(footprints allowed)
		)
		(placement
			(enabled no)
			(sheetname "")
		)
		(fill yes
			(thermal_gap 0.5)
			(thermal_bridge_width 0.5)
			(island_removal_mode 0)
		)
		(polygon
			(pts
				(arc
					(start 183.946292 -220.28531)
					(mid 183.285892 -220.28531)
					(end 183.946292 -220.28531)
				)
			)
		)
	)
	(zone
		(layers "In1.Cu" "In2.Cu")
		(hatch none 0.5)
		(connect_pads
			(clearance 0)
		)
		(min_thickness 0.25)
		(keepout
			(tracks not_allowed)
			(vias allowed)
			(pads allowed)
			(copperpour not_allowed)
			(footprints allowed)
		)
		(placement
			(enabled no)
			(sheetname "")
		)
		(fill yes
			(thermal_gap 0.5)
			(thermal_bridge_width 0.5)
			(island_removal_mode 0)
		)
		(polygon
			(pts
				(arc
					(start 420.242238 -284.034992)
					(mid 419.581838 -284.034992)
					(end 420.242238 -284.034992)
				)
			)
		)
	)
	(zone
		(layers "In1.Cu" "In2.Cu")
		(hatch none 0.5)
		(connect_pads
			(clearance 0)
		)
		(min_thickness 0.25)
		(keepout
			(tracks not_allowed)
			(vias allowed)
			(pads allowed)
			(copperpour not_allowed)
			(footprints allowed)
		)
		(placement
			(enabled no)
			(sheetname "")
		)
		(fill yes
			(thermal_gap 0.5)
			(thermal_bridge_width 0.5)
			(island_removal_mode 0)
		)
		(polygon
			(pts
				(arc
					(start 439.430414 -261.085076)
					(mid 438.770014 -261.085076)
					(end 439.430414 -261.085076)
				)
			)
		)
	)
	(zone
		(layers "In1.Cu" "In2.Cu")
		(hatch none 0.5)
		(connect_pads
			(clearance 0)
		)
		(min_thickness 0.25)
		(keepout
			(tracks not_allowed)
			(vias allowed)
			(pads allowed)
			(copperpour not_allowed)
			(footprints allowed)
		)
		(placement
			(enabled no)
			(sheetname "")
		)
		(fill yes
			(thermal_gap 0.5)
			(thermal_bridge_width 0.5)
			(island_removal_mode 0)
		)
		(polygon
			(pts
				(arc
					(start 285.066232 -311.23509)
					(mid 284.405832 -311.23509)
					(end 285.066232 -311.23509)
				)
			)
		)
	)
	(zone
		(layers "In1.Cu" "In2.Cu")
		(hatch none 0.5)
		(connect_pads
			(clearance 0)
		)
		(min_thickness 0.25)
		(keepout
			(tracks not_allowed)
			(vias allowed)
			(pads allowed)
			(copperpour not_allowed)
			(footprints allowed)
		)
		(placement
			(enabled no)
			(sheetname "")
		)
		(fill yes
			(thermal_gap 0.5)
			(thermal_bridge_width 0.5)
			(island_removal_mode 0)
		)
		(polygon
			(pts
				(arc
					(start 404.1521 -7.672324)
					(mid 404.174418 -7.618442)
					(end 404.2283 -7.596124)
				)
				(arc
					(start 405.264874 -7.596124)
					(mid 405.318756 -7.618442)
					(end 405.341074 -7.672324)
				)
				(arc
					(start 405.341074 -9.071864)
					(mid 405.318756 -9.125746)
					(end 405.264874 -9.148064)
				)
				(arc
					(start 404.2283 -9.148064)
					(mid 404.174418 -9.125746)
					(end 404.1521 -9.071864)
				)
			)
		)
	)
	(zone
		(layers "In1.Cu" "In2.Cu")
		(hatch none 0.5)
		(connect_pads
			(clearance 0)
		)
		(min_thickness 0.25)
		(keepout
			(tracks not_allowed)
			(vias allowed)
			(pads allowed)
			(copperpour not_allowed)
			(footprints allowed)
		)
		(placement
			(enabled no)
			(sheetname "")
		)
		(fill yes
			(thermal_gap 0.5)
			(thermal_bridge_width 0.5)
			(island_removal_mode 0)
		)
		(polygon
			(pts
				(arc
					(start 292.610286 -210.935062)
					(mid 291.949886 -210.935062)
					(end 292.610286 -210.935062)
				)
			)
		)
	)
	(zone
		(layers "In1.Cu" "In2.Cu")
		(hatch none 0.5)
		(connect_pads
			(clearance 0)
		)
		(min_thickness 0.25)
		(keepout
			(tracks not_allowed)
			(vias allowed)
			(pads allowed)
			(copperpour not_allowed)
			(footprints allowed)
		)
		(placement
			(enabled no)
			(sheetname "")
		)
		(fill yes
			(thermal_gap 0.5)
			(thermal_bridge_width 0.5)
			(island_removal_mode 0)
		)
		(polygon
			(pts
				(arc
					(start 52.214272 -272.135346)
					(mid 51.553872 -272.135346)
					(end 52.214272 -272.135346)
				)
			)
		)
	)
	(zone
		(layers "In1.Cu" "In2.Cu")
		(hatch none 0.5)
		(connect_pads
			(clearance 0)
		)
		(min_thickness 0.25)
		(keepout
			(tracks not_allowed)
			(vias allowed)
			(pads allowed)
			(copperpour not_allowed)
			(footprints allowed)
		)
		(placement
			(enabled no)
			(sheetname "")
		)
		(fill yes
			(thermal_gap 0.5)
			(thermal_bridge_width 0.5)
			(island_removal_mode 0)
		)
		(polygon
			(pts
				(arc
					(start 179.846224 -272.98523)
					(mid 179.185824 -272.98523)
					(end 179.846224 -272.98523)
				)
			)
		)
	)
	(zone
		(layers "In1.Cu" "In2.Cu")
		(hatch none 0.5)
		(connect_pads
			(clearance 0)
		)
		(min_thickness 0.25)
		(keepout
			(tracks not_allowed)
			(vias allowed)
			(pads allowed)
			(copperpour not_allowed)
			(footprints allowed)
		)
		(placement
			(enabled no)
			(sheetname "")
		)
		(fill yes
			(thermal_gap 0.5)
			(thermal_bridge_width 0.5)
			(island_removal_mode 0)
		)
		(polygon
			(pts
				(arc
					(start 183.946292 -315.485272)
					(mid 183.285892 -315.485272)
					(end 183.946292 -315.485272)
				)
			)
		)
	)
	(zone
		(layers "In1.Cu" "In2.Cu")
		(hatch none 0.5)
		(connect_pads
			(clearance 0)
		)
		(min_thickness 0.25)
		(keepout
			(tracks not_allowed)
			(vias allowed)
			(pads allowed)
			(copperpour not_allowed)
			(footprints allowed)
		)
		(placement
			(enabled no)
			(sheetname "")
		)
		(fill yes
			(thermal_gap 0.5)
			(thermal_bridge_width 0.5)
			(island_removal_mode 0)
		)
		(polygon
			(pts
				(arc
					(start 273.422364 -253.435104)
					(mid 272.761964 -253.435104)
					(end 273.422364 -253.435104)
				)
			)
		)
	)
	(zone
		(layers "In1.Cu" "In2.Cu")
		(hatch none 0.5)
		(connect_pads
			(clearance 0)
		)
		(min_thickness 0.25)
		(keepout
			(tracks not_allowed)
			(vias allowed)
			(pads allowed)
			(copperpour not_allowed)
			(footprints allowed)
		)
		(placement
			(enabled no)
			(sheetname "")
		)
		(fill yes
			(thermal_gap 0.5)
			(thermal_bridge_width 0.5)
			(island_removal_mode 0)
		)
		(polygon
			(pts
				(arc
					(start 191.490346 -285.735268)
					(mid 190.829946 -285.735268)
					(end 191.490346 -285.735268)
				)
			)
		)
	)
	(zone
		(layers "In1.Cu" "In2.Cu")
		(hatch none 0.5)
		(connect_pads
			(clearance 0)
		)
		(min_thickness 0.25)
		(keepout
			(tracks not_allowed)
			(vias allowed)
			(pads allowed)
			(copperpour not_allowed)
			(footprints allowed)
		)
		(placement
			(enabled no)
			(sheetname "")
		)
		(fill yes
			(thermal_gap 0.5)
			(thermal_bridge_width 0.5)
			(island_removal_mode 0)
		)
		(polygon
			(pts
				(arc
					(start 90.462354 -408.860244)
					(mid 90.484672 -408.914126)
					(end 90.538554 -408.936444)
				)
				(arc
					(start 90.734134 -408.936444)
					(mid 90.75601 -408.933312)
					(end 90.776044 -408.923998)
				)
				(arc
					(start 91.069668 -408.731466)
					(mid 91.111324 -408.719064)
					(end 91.15298 -408.731466)
				)
				(arc
					(start 91.447874 -408.923998)
					(mid 91.467798 -408.933234)
					(end 91.48953 -408.936444)
				)
				(arc
					(start 91.684094 -408.936444)
					(mid 91.737976 -408.914126)
					(end 91.760294 -408.860244)
				)
				(arc
					(start 91.760294 -408.174444)
					(mid 91.737976 -408.120562)
					(end 91.684094 -408.098244)
				)
				(arc
					(start 91.48953 -408.098244)
					(mid 91.467786 -408.101412)
					(end 91.447874 -408.11069)
				)
				(arc
					(start 91.15171 -408.303476)
					(mid 91.110026 -408.315698)
					(end 91.068398 -408.303222)
				)
				(arc
					(start 90.774774 -408.11069)
					(mid 90.75485 -408.101454)
					(end 90.733118 -408.098244)
				)
				(arc
					(start 90.538554 -408.098244)
					(mid 90.484672 -408.120562)
					(end 90.462354 -408.174444)
				)
			)
		)
	)
	(zone
		(layers "In1.Cu" "In2.Cu")
		(hatch none 0.5)
		(connect_pads
			(clearance 0)
		)
		(min_thickness 0.25)
		(keepout
			(tracks not_allowed)
			(vias allowed)
			(pads allowed)
			(copperpour not_allowed)
			(footprints allowed)
		)
		(placement
			(enabled no)
			(sheetname "")
		)
		(fill yes
			(thermal_gap 0.5)
			(thermal_bridge_width 0.5)
			(island_removal_mode 0)
		)
		(polygon
			(pts
				(arc
					(start 435.330346 -220.285056)
					(mid 434.669946 -220.285056)
					(end 435.330346 -220.285056)
				)
			)
		)
	)
	(zone
		(layers "In1.Cu" "In2.Cu")
		(hatch none 0.5)
		(connect_pads
			(clearance 0)
		)
		(min_thickness 0.25)
		(keepout
			(tracks not_allowed)
			(vias allowed)
			(pads allowed)
			(copperpour not_allowed)
			(footprints allowed)
		)
		(placement
			(enabled no)
			(sheetname "")
		)
		(fill yes
			(thermal_gap 0.5)
			(thermal_bridge_width 0.5)
			(island_removal_mode 0)
		)
		(polygon
			(pts
				(arc
					(start 32.64154 -11.91768)
					(mid 32.619222 -11.971562)
					(end 32.56534 -11.99388)
				)
				(arc
					(start 31.528766 -11.99388)
					(mid 31.474884 -11.971562)
					(end 31.452566 -11.91768)
				)
				(arc
					(start 31.452566 -10.51814)
					(mid 31.474884 -10.464258)
					(end 31.528766 -10.44194)
				)
				(arc
					(start 32.56534 -10.44194)
					(mid 32.619222 -10.464258)
					(end 32.64154 -10.51814)
				)
			)
		)
	)
	(zone
		(layers "In1.Cu" "In2.Cu")
		(hatch none 0.5)
		(connect_pads
			(clearance 0)
		)
		(min_thickness 0.25)
		(keepout
			(tracks not_allowed)
			(vias allowed)
			(pads allowed)
			(copperpour not_allowed)
			(footprints allowed)
		)
		(placement
			(enabled no)
			(sheetname "")
		)
		(fill yes
			(thermal_gap 0.5)
			(thermal_bridge_width 0.5)
			(island_removal_mode 0)
		)
		(polygon
			(pts
				(arc
					(start 273.422364 -302.73498)
					(mid 272.761964 -302.73498)
					(end 273.422364 -302.73498)
				)
			)
		)
	)
	(zone
		(layers "In1.Cu" "In2.Cu")
		(hatch none 0.5)
		(connect_pads
			(clearance 0)
		)
		(min_thickness 0.25)
		(keepout
			(tracks not_allowed)
			(vias allowed)
			(pads allowed)
			(copperpour not_allowed)
			(footprints allowed)
		)
		(placement
			(enabled no)
			(sheetname "")
		)
		(fill yes
			(thermal_gap 0.5)
			(thermal_bridge_width 0.5)
			(island_removal_mode 0)
		)
		(polygon
			(pts
				(arc
					(start 202.478132 -250.035314)
					(mid 201.817732 -250.035314)
					(end 202.478132 -250.035314)
				)
			)
		)
	)
	(zone
		(layers "In1.Cu" "In2.Cu")
		(hatch none 0.5)
		(connect_pads
			(clearance 0)
		)
		(min_thickness 0.25)
		(keepout
			(tracks not_allowed)
			(vias allowed)
			(pads allowed)
			(copperpour not_allowed)
			(footprints allowed)
		)
		(placement
			(enabled no)
			(sheetname "")
		)
		(fill yes
			(thermal_gap 0.5)
			(thermal_bridge_width 0.5)
			(island_removal_mode 0)
		)
		(polygon
			(pts
				(arc
					(start 285.066232 -234.735116)
					(mid 284.405832 -234.735116)
					(end 285.066232 -234.735116)
				)
			)
		)
	)
	(zone
		(layers "In1.Cu" "In2.Cu")
		(hatch none 0.5)
		(connect_pads
			(clearance 0)
		)
		(min_thickness 0.25)
		(keepout
			(tracks not_allowed)
			(vias allowed)
			(pads allowed)
			(copperpour not_allowed)
			(footprints allowed)
		)
		(placement
			(enabled no)
			(sheetname "")
		)
		(fill yes
			(thermal_gap 0.5)
			(thermal_bridge_width 0.5)
			(island_removal_mode 0)
		)
		(polygon
			(pts
				(arc
					(start 33.026096 -253.435358)
					(mid 32.365696 -253.435358)
					(end 33.026096 -253.435358)
				)
			)
		)
	)
	(zone
		(layers "In1.Cu" "In2.Cu")
		(hatch none 0.5)
		(connect_pads
			(clearance 0)
		)
		(min_thickness 0.25)
		(keepout
			(tracks not_allowed)
			(vias allowed)
			(pads allowed)
			(copperpour not_allowed)
			(footprints allowed)
		)
		(placement
			(enabled no)
			(sheetname "")
		)
		(fill yes
			(thermal_gap 0.5)
			(thermal_bridge_width 0.5)
			(island_removal_mode 0)
		)
		(polygon
			(pts
				(arc
					(start 133.041644 -17.197578)
					(mid 133.019326 -17.25146)
					(end 132.965444 -17.273778)
				)
				(arc
					(start 131.92887 -17.273778)
					(mid 131.874988 -17.25146)
					(end 131.85267 -17.197578)
				)
				(arc
					(start 131.85267 -15.798038)
					(mid 131.874988 -15.744156)
					(end 131.92887 -15.721838)
				)
				(arc
					(start 132.965444 -15.721838)
					(mid 133.019326 -15.744156)
					(end 133.041644 -15.798038)
				)
			)
		)
	)
	(zone
		(layers "In1.Cu" "In2.Cu")
		(hatch none 0.5)
		(connect_pads
			(clearance 0)
		)
		(min_thickness 0.25)
		(keepout
			(tracks not_allowed)
			(vias allowed)
			(pads allowed)
			(copperpour not_allowed)
			(footprints allowed)
		)
		(placement
			(enabled no)
			(sheetname "")
		)
		(fill yes
			(thermal_gap 0.5)
			(thermal_bridge_width 0.5)
			(island_removal_mode 0)
		)
		(polygon
			(pts
				(arc
					(start 450.4182 -288.285174)
					(mid 449.7578 -288.285174)
					(end 450.4182 -288.285174)
				)
			)
		)
	)
	(zone
		(layers "In1.Cu" "In2.Cu")
		(hatch none 0.5)
		(connect_pads
			(clearance 0)
		)
		(min_thickness 0.25)
		(keepout
			(tracks not_allowed)
			(vias allowed)
			(pads allowed)
			(copperpour not_allowed)
			(footprints allowed)
		)
		(placement
			(enabled no)
			(sheetname "")
		)
		(fill yes
			(thermal_gap 0.5)
			(thermal_bridge_width 0.5)
			(island_removal_mode 0)
		)
		(polygon
			(pts
				(arc
					(start 191.490346 -249.18543)
					(mid 190.829946 -249.18543)
					(end 191.490346 -249.18543)
				)
			)
		)
	)
	(zone
		(layers "In1.Cu" "In2.Cu")
		(hatch none 0.5)
		(connect_pads
			(clearance 0)
		)
		(min_thickness 0.25)
		(keepout
			(tracks not_allowed)
			(vias allowed)
			(pads allowed)
			(copperpour not_allowed)
			(footprints allowed)
		)
		(placement
			(enabled no)
			(sheetname "")
		)
		(fill yes
			(thermal_gap 0.5)
			(thermal_bridge_width 0.5)
			(island_removal_mode 0)
		)
		(polygon
			(pts
				(arc
					(start 40.57015 -205.83525)
					(mid 39.90975 -205.83525)
					(end 40.57015 -205.83525)
				)
			)
		)
	)
	(zone
		(layers "In1.Cu" "In2.Cu")
		(hatch none 0.5)
		(connect_pads
			(clearance 0)
		)
		(min_thickness 0.25)
		(keepout
			(tracks not_allowed)
			(vias allowed)
			(pads allowed)
			(copperpour not_allowed)
			(footprints allowed)
		)
		(placement
			(enabled no)
			(sheetname "")
		)
		(fill yes
			(thermal_gap 0.5)
			(thermal_bridge_width 0.5)
			(island_removal_mode 0)
		)
		(polygon
			(pts
				(arc
					(start 199.0344 -252.58522)
					(mid 198.374 -252.58522)
					(end 199.0344 -252.58522)
				)
			)
		)
	)
	(zone
		(layers "In1.Cu" "In2.Cu")
		(hatch none 0.5)
		(connect_pads
			(clearance 0)
		)
		(min_thickness 0.25)
		(keepout
			(tracks not_allowed)
			(vias allowed)
			(pads allowed)
			(copperpour not_allowed)
			(footprints allowed)
		)
		(placement
			(enabled no)
			(sheetname "")
		)
		(fill yes
			(thermal_gap 0.5)
			(thermal_bridge_width 0.5)
			(island_removal_mode 0)
		)
		(polygon
			(pts
				(arc
					(start 40.57015 -244.935248)
					(mid 39.90975 -244.935248)
					(end 40.57015 -244.935248)
				)
			)
		)
	)
	(zone
		(layers "In1.Cu" "In2.Cu")
		(hatch none 0.5)
		(connect_pads
			(clearance 0)
		)
		(min_thickness 0.25)
		(keepout
			(tracks not_allowed)
			(vias allowed)
			(pads allowed)
			(copperpour not_allowed)
			(footprints allowed)
		)
		(placement
			(enabled no)
			(sheetname "")
		)
		(fill yes
			(thermal_gap 0.5)
			(thermal_bridge_width 0.5)
			(island_removal_mode 0)
		)
		(polygon
			(pts
				(arc
					(start 300.15434 -301.885096)
					(mid 299.49394 -301.885096)
					(end 300.15434 -301.885096)
				)
			)
		)
	)
	(zone
		(layers "In1.Cu" "In2.Cu")
		(hatch none 0.5)
		(connect_pads
			(clearance 0)
		)
		(min_thickness 0.25)
		(keepout
			(tracks not_allowed)
			(vias allowed)
			(pads allowed)
			(copperpour not_allowed)
			(footprints allowed)
		)
		(placement
			(enabled no)
			(sheetname "")
		)
		(fill yes
			(thermal_gap 0.5)
			(thermal_bridge_width 0.5)
			(island_removal_mode 0)
		)
		(polygon
			(pts
				(arc
					(start 22.03831 -301.88535)
					(mid 21.37791 -301.88535)
					(end 22.03831 -301.88535)
				)
			)
		)
	)
	(zone
		(layers "In1.Cu" "In2.Cu")
		(hatch none 0.5)
		(connect_pads
			(clearance 0)
		)
		(min_thickness 0.25)
		(keepout
			(tracks not_allowed)
			(vias allowed)
			(pads allowed)
			(copperpour not_allowed)
			(footprints allowed)
		)
		(placement
			(enabled no)
			(sheetname "")
		)
		(fill yes
			(thermal_gap 0.5)
			(thermal_bridge_width 0.5)
			(island_removal_mode 0)
		)
		(polygon
			(pts
				(arc
					(start 405.952198 -7.672324)
					(mid 405.974516 -7.618442)
					(end 406.028398 -7.596124)
				)
				(arc
					(start 407.064972 -7.596124)
					(mid 407.118854 -7.618442)
					(end 407.141172 -7.672324)
				)
				(arc
					(start 407.141172 -9.071864)
					(mid 407.118854 -9.125746)
					(end 407.064972 -9.148064)
				)
				(arc
					(start 406.028398 -9.148064)
					(mid 405.974516 -9.125746)
					(end 405.952198 -9.071864)
				)
			)
		)
	)
	(zone
		(layers "In1.Cu" "In2.Cu")
		(hatch none 0.5)
		(connect_pads
			(clearance 0)
		)
		(min_thickness 0.25)
		(keepout
			(tracks not_allowed)
			(vias allowed)
			(pads allowed)
			(copperpour not_allowed)
			(footprints allowed)
		)
		(placement
			(enabled no)
			(sheetname "")
		)
		(fill yes
			(thermal_gap 0.5)
			(thermal_bridge_width 0.5)
			(island_removal_mode 0)
		)
		(polygon
			(pts
				(arc
					(start 439.430414 -247.485154)
					(mid 438.770014 -247.485154)
					(end 439.430414 -247.485154)
				)
			)
		)
	)
	(zone
		(layers "In1.Cu" "In2.Cu")
		(hatch none 0.5)
		(connect_pads
			(clearance 0)
		)
		(min_thickness 0.25)
		(keepout
			(tracks not_allowed)
			(vias allowed)
			(pads allowed)
			(copperpour not_allowed)
			(footprints allowed)
		)
		(placement
			(enabled no)
			(sheetname "")
		)
		(fill yes
			(thermal_gap 0.5)
			(thermal_bridge_width 0.5)
			(island_removal_mode 0)
		)
		(polygon
			(pts
				(arc
					(start 37.126164 -206.685388)
					(mid 36.465764 -206.685388)
					(end 37.126164 -206.685388)
				)
			)
		)
	)
	(zone
		(layers "In1.Cu" "In2.Cu")
		(hatch none 0.5)
		(connect_pads
			(clearance 0)
		)
		(min_thickness 0.25)
		(keepout
			(tracks not_allowed)
			(vias allowed)
			(pads allowed)
			(copperpour not_allowed)
			(footprints allowed)
		)
		(placement
			(enabled no)
			(sheetname "")
		)
		(fill yes
			(thermal_gap 0.5)
			(thermal_bridge_width 0.5)
			(island_removal_mode 0)
		)
		(polygon
			(pts
				(arc
					(start 44.670218 -317.185294)
					(mid 44.009818 -317.185294)
					(end 44.670218 -317.185294)
				)
			)
		)
	)
	(zone
		(layers "In1.Cu" "In2.Cu")
		(hatch none 0.5)
		(connect_pads
			(clearance 0)
		)
		(min_thickness 0.25)
		(keepout
			(tracks not_allowed)
			(vias allowed)
			(pads allowed)
			(copperpour not_allowed)
			(footprints allowed)
		)
		(placement
			(enabled no)
			(sheetname "")
		)
		(fill yes
			(thermal_gap 0.5)
			(thermal_bridge_width 0.5)
			(island_removal_mode 0)
		)
		(polygon
			(pts
				(arc
					(start 442.8744 -278.93518)
					(mid 442.214 -278.93518)
					(end 442.8744 -278.93518)
				)
			)
		)
	)
	(zone
		(layers "In1.Cu" "In2.Cu")
		(hatch none 0.5)
		(connect_pads
			(clearance 0)
		)
		(min_thickness 0.25)
		(keepout
			(tracks not_allowed)
			(vias allowed)
			(pads allowed)
			(copperpour not_allowed)
			(footprints allowed)
		)
		(placement
			(enabled no)
			(sheetname "")
		)
		(fill yes
			(thermal_gap 0.5)
			(thermal_bridge_width 0.5)
			(island_removal_mode 0)
		)
		(polygon
			(pts
				(arc
					(start 435.330346 -205.834996)
					(mid 434.669946 -205.834996)
					(end 435.330346 -205.834996)
				)
			)
		)
	)
	(zone
		(layers "In1.Cu" "In2.Cu")
		(hatch none 0.5)
		(connect_pads
			(clearance 0)
		)
		(min_thickness 0.25)
		(keepout
			(tracks not_allowed)
			(vias allowed)
			(pads allowed)
			(copperpour not_allowed)
			(footprints allowed)
		)
		(placement
			(enabled no)
			(sheetname "")
		)
		(fill yes
			(thermal_gap 0.5)
			(thermal_bridge_width 0.5)
			(island_removal_mode 0)
		)
		(polygon
			(pts
				(arc
					(start 22.03831 -240.68532)
					(mid 21.37791 -240.68532)
					(end 22.03831 -240.68532)
				)
			)
		)
	)
	(zone
		(layers "In1.Cu" "In2.Cu")
		(hatch none 0.5)
		(connect_pads
			(clearance 0)
		)
		(min_thickness 0.25)
		(keepout
			(tracks not_allowed)
			(vias allowed)
			(pads allowed)
			(copperpour not_allowed)
			(footprints allowed)
		)
		(placement
			(enabled no)
			(sheetname "")
		)
		(fill yes
			(thermal_gap 0.5)
			(thermal_bridge_width 0.5)
			(island_removal_mode 0)
		)
		(polygon
			(pts
				(arc
					(start 176.402238 -242.385342)
					(mid 175.741838 -242.385342)
					(end 176.402238 -242.385342)
				)
			)
		)
	)
	(zone
		(layers "In1.Cu" "In2.Cu")
		(hatch none 0.5)
		(connect_pads
			(clearance 0)
		)
		(min_thickness 0.25)
		(keepout
			(tracks not_allowed)
			(vias allowed)
			(pads allowed)
			(copperpour not_allowed)
			(footprints allowed)
		)
		(placement
			(enabled no)
			(sheetname "")
		)
		(fill yes
			(thermal_gap 0.5)
			(thermal_bridge_width 0.5)
			(island_removal_mode 0)
		)
		(polygon
			(pts
				(arc
					(start 439.430414 -311.23509)
					(mid 438.770014 -311.23509)
					(end 439.430414 -311.23509)
				)
			)
		)
	)
	(zone
		(layers "In1.Cu" "In2.Cu")
		(hatch none 0.5)
		(connect_pads
			(clearance 0)
		)
		(min_thickness 0.25)
		(keepout
			(tracks not_allowed)
			(vias allowed)
			(pads allowed)
			(copperpour not_allowed)
			(footprints allowed)
		)
		(placement
			(enabled no)
			(sheetname "")
		)
		(fill yes
			(thermal_gap 0.5)
			(thermal_bridge_width 0.5)
			(island_removal_mode 0)
		)
		(polygon
			(pts
				(arc
					(start 296.054272 -213.484968)
					(mid 295.393872 -213.484968)
					(end 296.054272 -213.484968)
				)
			)
		)
	)
	(zone
		(layers "In1.Cu" "In2.Cu")
		(hatch none 0.5)
		(connect_pads
			(clearance 0)
		)
		(min_thickness 0.25)
		(keepout
			(tracks not_allowed)
			(vias allowed)
			(pads allowed)
			(copperpour not_allowed)
			(footprints allowed)
		)
		(placement
			(enabled no)
			(sheetname "")
		)
		(fill yes
			(thermal_gap 0.5)
			(thermal_bridge_width 0.5)
			(island_removal_mode 0)
		)
		(polygon
			(pts
				(arc
					(start 183.946292 -228.78542)
					(mid 183.285892 -228.78542)
					(end 183.946292 -228.78542)
				)
			)
		)
	)
	(zone
		(layers "In1.Cu" "In2.Cu")
		(hatch none 0.5)
		(connect_pads
			(clearance 0)
		)
		(min_thickness 0.25)
		(keepout
			(tracks not_allowed)
			(vias allowed)
			(pads allowed)
			(copperpour not_allowed)
			(footprints allowed)
		)
		(placement
			(enabled no)
			(sheetname "")
		)
		(fill yes
			(thermal_gap 0.5)
			(thermal_bridge_width 0.5)
			(island_removal_mode 0)
		)
		(polygon
			(pts
				(arc
					(start 17.938242 -226.23526)
					(mid 17.277842 -226.23526)
					(end 17.938242 -226.23526)
				)
			)
		)
	)
	(zone
		(layers "In1.Cu" "In2.Cu")
		(hatch none 0.5)
		(connect_pads
			(clearance 0)
		)
		(min_thickness 0.25)
		(keepout
			(tracks not_allowed)
			(vias allowed)
			(pads allowed)
			(copperpour not_allowed)
			(footprints allowed)
		)
		(placement
			(enabled no)
			(sheetname "")
		)
		(fill yes
			(thermal_gap 0.5)
			(thermal_bridge_width 0.5)
			(island_removal_mode 0)
		)
		(polygon
			(pts
				(arc
					(start 37.126164 -312.935366)
					(mid 36.465764 -312.935366)
					(end 37.126164 -312.935366)
				)
			)
		)
	)
	(zone
		(layers "In1.Cu" "In2.Cu")
		(hatch none 0.5)
		(connect_pads
			(clearance 0)
		)
		(min_thickness 0.25)
		(keepout
			(tracks not_allowed)
			(vias allowed)
			(pads allowed)
			(copperpour not_allowed)
			(footprints allowed)
		)
		(placement
			(enabled no)
			(sheetname "")
		)
		(fill yes
			(thermal_gap 0.5)
			(thermal_bridge_width 0.5)
			(island_removal_mode 0)
		)
		(polygon
			(pts
				(arc
					(start 368.585242 -379.360684)
					(mid 368.605166 -379.36992)
					(end 368.626898 -379.37313)
				)
				(arc
					(start 368.821462 -379.37313)
					(mid 368.875344 -379.350812)
					(end 368.897662 -379.29693)
				)
				(arc
					(start 368.897662 -378.61113)
					(mid 368.875344 -378.557248)
					(end 368.821462 -378.53493)
				)
				(arc
					(start 368.626898 -378.53493)
					(mid 368.605154 -378.538098)
					(end 368.585242 -378.547376)
				)
				(arc
					(start 368.289078 -378.740162)
					(mid 368.247394 -378.752384)
					(end 368.205766 -378.739908)
				)
				(arc
					(start 367.912142 -378.547376)
					(mid 367.892218 -378.53814)
					(end 367.870486 -378.53493)
				)
				(arc
					(start 367.675922 -378.53493)
					(mid 367.62204 -378.557248)
					(end 367.599722 -378.61113)
				)
				(arc
					(start 367.599722 -379.29693)
					(mid 367.62204 -379.350812)
					(end 367.675922 -379.37313)
				)
				(arc
					(start 367.871756 -379.37313)
					(mid 367.8935 -379.369962)
					(end 367.913412 -379.360684)
				)
				(arc
					(start 368.207036 -379.168152)
					(mid 368.248692 -379.15575)
					(end 368.290348 -379.168152)
				)
			)
		)
	)
	(zone
		(layers "In1.Cu" "In2.Cu")
		(hatch none 0.5)
		(connect_pads
			(clearance 0)
		)
		(min_thickness 0.25)
		(keepout
			(tracks not_allowed)
			(vias allowed)
			(pads allowed)
			(copperpour not_allowed)
			(footprints allowed)
		)
		(placement
			(enabled no)
			(sheetname "")
		)
		(fill yes
			(thermal_gap 0.5)
			(thermal_bridge_width 0.5)
			(island_removal_mode 0)
		)
		(polygon
			(pts
				(arc
					(start 187.390278 -238.985298)
					(mid 186.729878 -238.985298)
					(end 187.390278 -238.985298)
				)
			)
		)
	)
	(zone
		(layers "In1.Cu" "In2.Cu")
		(hatch none 0.5)
		(connect_pads
			(clearance 0)
		)
		(min_thickness 0.25)
		(keepout
			(tracks not_allowed)
			(vias allowed)
			(pads allowed)
			(copperpour not_allowed)
			(footprints allowed)
		)
		(placement
			(enabled no)
			(sheetname "")
		)
		(fill yes
			(thermal_gap 0.5)
			(thermal_bridge_width 0.5)
			(island_removal_mode 0)
		)
		(polygon
			(pts
				(arc
					(start 300.15434 -247.485154)
					(mid 299.49394 -247.485154)
					(end 300.15434 -247.485154)
				)
			)
		)
	)
	(zone
		(layers "In1.Cu" "In2.Cu")
		(hatch none 0.5)
		(connect_pads
			(clearance 0)
		)
		(min_thickness 0.25)
		(keepout
			(tracks not_allowed)
			(vias allowed)
			(pads allowed)
			(copperpour not_allowed)
			(footprints allowed)
		)
		(placement
			(enabled no)
			(sheetname "")
		)
		(fill yes
			(thermal_gap 0.5)
			(thermal_bridge_width 0.5)
			(island_removal_mode 0)
		)
		(polygon
			(pts
				(arc
					(start 446.974468 -266.185142)
					(mid 446.314068 -266.185142)
					(end 446.974468 -266.185142)
				)
			)
		)
	)
	(zone
		(layers "In1.Cu" "In2.Cu")
		(hatch none 0.5)
		(connect_pads
			(clearance 0)
		)
		(min_thickness 0.25)
		(keepout
			(tracks not_allowed)
			(vias allowed)
			(pads allowed)
			(copperpour not_allowed)
			(footprints allowed)
		)
		(placement
			(enabled no)
			(sheetname "")
		)
		(fill yes
			(thermal_gap 0.5)
			(thermal_bridge_width 0.5)
			(island_removal_mode 0)
		)
		(polygon
			(pts
				(arc
					(start 280.966164 -284.034992)
					(mid 280.305764 -284.034992)
					(end 280.966164 -284.034992)
				)
			)
		)
	)
	(zone
		(layers "In1.Cu" "In2.Cu")
		(hatch none 0.5)
		(connect_pads
			(clearance 0)
		)
		(min_thickness 0.25)
		(keepout
			(tracks not_allowed)
			(vias allowed)
			(pads allowed)
			(copperpour not_allowed)
			(footprints allowed)
		)
		(placement
			(enabled no)
			(sheetname "")
		)
		(fill yes
			(thermal_gap 0.5)
			(thermal_bridge_width 0.5)
			(island_removal_mode 0)
		)
		(polygon
			(pts
				(arc
					(start 44.670218 -285.735268)
					(mid 44.009818 -285.735268)
					(end 44.670218 -285.735268)
				)
			)
		)
	)
	(zone
		(layers "In1.Cu" "In2.Cu")
		(hatch none 0.5)
		(connect_pads
			(clearance 0)
		)
		(min_thickness 0.25)
		(keepout
			(tracks not_allowed)
			(vias allowed)
			(pads allowed)
			(copperpour not_allowed)
			(footprints allowed)
		)
		(placement
			(enabled no)
			(sheetname "")
		)
		(fill yes
			(thermal_gap 0.5)
			(thermal_bridge_width 0.5)
			(island_removal_mode 0)
		)
		(polygon
			(pts
				(arc
					(start 292.610286 -219.435172)
					(mid 291.949886 -219.435172)
					(end 292.610286 -219.435172)
				)
			)
		)
	)
	(zone
		(layers "In1.Cu" "In2.Cu")
		(hatch none 0.5)
		(connect_pads
			(clearance 0)
		)
		(min_thickness 0.25)
		(keepout
			(tracks not_allowed)
			(vias allowed)
			(pads allowed)
			(copperpour not_allowed)
			(footprints allowed)
		)
		(placement
			(enabled no)
			(sheetname "")
		)
		(fill yes
			(thermal_gap 0.5)
			(thermal_bridge_width 0.5)
			(island_removal_mode 0)
		)
		(polygon
			(pts
				(arc
					(start 454.518268 -250.884944)
					(mid 453.857868 -250.884944)
					(end 454.518268 -250.884944)
				)
			)
		)
	)
	(zone
		(layers "In1.Cu" "In2.Cu")
		(hatch none 0.5)
		(connect_pads
			(clearance 0)
		)
		(min_thickness 0.25)
		(keepout
			(tracks not_allowed)
			(vias allowed)
			(pads allowed)
			(copperpour not_allowed)
			(footprints allowed)
		)
		(placement
			(enabled no)
			(sheetname "")
		)
		(fill yes
			(thermal_gap 0.5)
			(thermal_bridge_width 0.5)
			(island_removal_mode 0)
		)
		(polygon
			(pts
				(arc
					(start 427.786292 -288.285174)
					(mid 427.125892 -288.285174)
					(end 427.786292 -288.285174)
				)
			)
		)
	)
	(zone
		(layers "In1.Cu" "In2.Cu")
		(hatch none 0.5)
		(connect_pads
			(clearance 0)
		)
		(min_thickness 0.25)
		(keepout
			(tracks not_allowed)
			(vias allowed)
			(pads allowed)
			(copperpour not_allowed)
			(footprints allowed)
		)
		(placement
			(enabled no)
			(sheetname "")
		)
		(fill yes
			(thermal_gap 0.5)
			(thermal_bridge_width 0.5)
			(island_removal_mode 0)
		)
		(polygon
			(pts
				(arc
					(start 277.522432 -254.284988)
					(mid 276.862032 -254.284988)
					(end 277.522432 -254.284988)
				)
			)
		)
	)
	(zone
		(layers "In1.Cu" "In2.Cu")
		(hatch none 0.5)
		(connect_pads
			(clearance 0)
		)
		(min_thickness 0.25)
		(keepout
			(tracks not_allowed)
			(vias allowed)
			(pads allowed)
			(copperpour not_allowed)
			(footprints allowed)
		)
		(placement
			(enabled no)
			(sheetname "")
		)
		(fill yes
			(thermal_gap 0.5)
			(thermal_bridge_width 0.5)
			(island_removal_mode 0)
		)
		(polygon
			(pts
				(arc
					(start 300.15434 -278.085042)
					(mid 299.49394 -278.085042)
					(end 300.15434 -278.085042)
				)
			)
		)
	)
	(zone
		(layers "In1.Cu" "In2.Cu")
		(hatch none 0.5)
		(connect_pads
			(clearance 0)
		)
		(min_thickness 0.25)
		(keepout
			(tracks not_allowed)
			(vias allowed)
			(pads allowed)
			(copperpour not_allowed)
			(footprints allowed)
		)
		(placement
			(enabled no)
			(sheetname "")
		)
		(fill yes
			(thermal_gap 0.5)
			(thermal_bridge_width 0.5)
			(island_removal_mode 0)
		)
		(polygon
			(pts
				(arc
					(start 450.4182 -263.634982)
					(mid 449.7578 -263.634982)
					(end 450.4182 -263.634982)
				)
			)
		)
	)
	(zone
		(layers "In1.Cu" "In2.Cu")
		(hatch none 0.5)
		(connect_pads
			(clearance 0)
		)
		(min_thickness 0.25)
		(keepout
			(tracks not_allowed)
			(vias allowed)
			(pads allowed)
			(copperpour not_allowed)
			(footprints allowed)
		)
		(placement
			(enabled no)
			(sheetname "")
		)
		(fill yes
			(thermal_gap 0.5)
			(thermal_bridge_width 0.5)
			(island_removal_mode 0)
		)
		(polygon
			(pts
				(arc
					(start 427.786292 -301.034958)
					(mid 427.125892 -301.034958)
					(end 427.786292 -301.034958)
				)
			)
		)
	)
	(zone
		(layers "In1.Cu" "In2.Cu")
		(hatch none 0.5)
		(connect_pads
			(clearance 0)
		)
		(min_thickness 0.25)
		(keepout
			(tracks not_allowed)
			(vias allowed)
			(pads allowed)
			(copperpour not_allowed)
			(footprints allowed)
		)
		(placement
			(enabled no)
			(sheetname "")
		)
		(fill yes
			(thermal_gap 0.5)
			(thermal_bridge_width 0.5)
			(island_removal_mode 0)
		)
		(polygon
			(pts
				(arc
					(start 269.978378 -252.584966)
					(mid 269.317978 -252.584966)
					(end 269.978378 -252.584966)
				)
			)
		)
	)
	(zone
		(layers "In1.Cu" "In2.Cu")
		(hatch none 0.5)
		(connect_pads
			(clearance 0)
		)
		(min_thickness 0.25)
		(keepout
			(tracks not_allowed)
			(vias allowed)
			(pads allowed)
			(copperpour not_allowed)
			(footprints allowed)
		)
		(placement
			(enabled no)
			(sheetname "")
		)
		(fill yes
			(thermal_gap 0.5)
			(thermal_bridge_width 0.5)
			(island_removal_mode 0)
		)
		(polygon
			(pts
				(arc
					(start 29.58211 -244.08511)
					(mid 28.92171 -244.08511)
					(end 29.58211 -244.08511)
				)
			)
		)
	)
	(zone
		(layers "In1.Cu" "In2.Cu")
		(hatch none 0.5)
		(connect_pads
			(clearance 0)
		)
		(min_thickness 0.25)
		(keepout
			(tracks not_allowed)
			(vias allowed)
			(pads allowed)
			(copperpour not_allowed)
			(footprints allowed)
		)
		(placement
			(enabled no)
			(sheetname "")
		)
		(fill yes
			(thermal_gap 0.5)
			(thermal_bridge_width 0.5)
			(island_removal_mode 0)
		)
		(polygon
			(pts
				(arc
					(start 277.522432 -210.085178)
					(mid 276.862032 -210.085178)
					(end 277.522432 -210.085178)
				)
			)
		)
	)
	(zone
		(layers "In1.Cu" "In2.Cu")
		(hatch none 0.5)
		(connect_pads
			(clearance 0)
		)
		(min_thickness 0.25)
		(keepout
			(tracks not_allowed)
			(vias allowed)
			(pads allowed)
			(copperpour not_allowed)
			(footprints allowed)
		)
		(placement
			(enabled no)
			(sheetname "")
		)
		(fill yes
			(thermal_gap 0.5)
			(thermal_bridge_width 0.5)
			(island_removal_mode 0)
		)
		(polygon
			(pts
				(arc
					(start 269.978378 -276.38502)
					(mid 269.317978 -276.38502)
					(end 269.978378 -276.38502)
				)
			)
		)
	)
	(zone
		(layers "In1.Cu" "In2.Cu")
		(hatch none 0.5)
		(connect_pads
			(clearance 0)
		)
		(min_thickness 0.25)
		(keepout
			(tracks not_allowed)
			(vias allowed)
			(pads allowed)
			(copperpour not_allowed)
			(footprints allowed)
		)
		(placement
			(enabled no)
			(sheetname "")
		)
		(fill yes
			(thermal_gap 0.5)
			(thermal_bridge_width 0.5)
			(island_removal_mode 0)
		)
		(polygon
			(pts
				(arc
					(start 199.0344 -311.235344)
					(mid 198.374 -311.235344)
					(end 199.0344 -311.235344)
				)
			)
		)
	)
	(zone
		(layers "In1.Cu" "In2.Cu")
		(hatch none 0.5)
		(connect_pads
			(clearance 0)
		)
		(min_thickness 0.25)
		(keepout
			(tracks not_allowed)
			(vias allowed)
			(pads allowed)
			(copperpour not_allowed)
			(footprints allowed)
		)
		(placement
			(enabled no)
			(sheetname "")
		)
		(fill yes
			(thermal_gap 0.5)
			(thermal_bridge_width 0.5)
			(island_removal_mode 0)
		)
		(polygon
			(pts
				(arc
					(start 52.214272 -240.68532)
					(mid 51.553872 -240.68532)
					(end 52.214272 -240.68532)
				)
			)
		)
	)
	(zone
		(layers "In1.Cu" "In2.Cu")
		(hatch none 0.5)
		(connect_pads
			(clearance 0)
		)
		(min_thickness 0.25)
		(keepout
			(tracks not_allowed)
			(vias allowed)
			(pads allowed)
			(copperpour not_allowed)
			(footprints allowed)
		)
		(placement
			(enabled no)
			(sheetname "")
		)
		(fill yes
			(thermal_gap 0.5)
			(thermal_bridge_width 0.5)
			(island_removal_mode 0)
		)
		(polygon
			(pts
				(arc
					(start 187.390278 -274.685252)
					(mid 186.729878 -274.685252)
					(end 187.390278 -274.685252)
				)
			)
		)
	)
	(zone
		(layers "In1.Cu" "In2.Cu")
		(hatch none 0.5)
		(connect_pads
			(clearance 0)
		)
		(min_thickness 0.25)
		(keepout
			(tracks not_allowed)
			(vias allowed)
			(pads allowed)
			(copperpour not_allowed)
			(footprints allowed)
		)
		(placement
			(enabled no)
			(sheetname "")
		)
		(fill yes
			(thermal_gap 0.5)
			(thermal_bridge_width 0.5)
			(island_removal_mode 0)
		)
		(polygon
			(pts
				(arc
					(start 44.670218 -254.285242)
					(mid 44.009818 -254.285242)
					(end 44.670218 -254.285242)
				)
			)
		)
	)
	(zone
		(layers "In1.Cu" "In2.Cu")
		(hatch none 0.5)
		(connect_pads
			(clearance 0)
		)
		(min_thickness 0.25)
		(keepout
			(tracks not_allowed)
			(vias allowed)
			(pads allowed)
			(copperpour not_allowed)
			(footprints allowed)
		)
		(placement
			(enabled no)
			(sheetname "")
		)
		(fill yes
			(thermal_gap 0.5)
			(thermal_bridge_width 0.5)
			(island_removal_mode 0)
		)
		(polygon
			(pts
				(arc
					(start 442.8744 -274.684998)
					(mid 442.214 -274.684998)
					(end 442.8744 -274.684998)
				)
			)
		)
	)
	(zone
		(layers "In1.Cu" "In2.Cu")
		(hatch none 0.5)
		(connect_pads
			(clearance 0)
		)
		(min_thickness 0.25)
		(keepout
			(tracks not_allowed)
			(vias allowed)
			(pads allowed)
			(copperpour not_allowed)
			(footprints allowed)
		)
		(placement
			(enabled no)
			(sheetname "")
		)
		(fill yes
			(thermal_gap 0.5)
			(thermal_bridge_width 0.5)
			(island_removal_mode 0)
		)
		(polygon
			(pts
				(arc
					(start 183.946292 -309.535322)
					(mid 183.285892 -309.535322)
					(end 183.946292 -309.535322)
				)
			)
		)
	)
	(zone
		(layers "In1.Cu" "In2.Cu")
		(hatch none 0.5)
		(connect_pads
			(clearance 0)
		)
		(min_thickness 0.25)
		(keepout
			(tracks not_allowed)
			(vias allowed)
			(pads allowed)
			(copperpour not_allowed)
			(footprints allowed)
		)
		(placement
			(enabled no)
			(sheetname "")
		)
		(fill yes
			(thermal_gap 0.5)
			(thermal_bridge_width 0.5)
			(island_removal_mode 0)
		)
		(polygon
			(pts
				(arc
					(start 183.946292 -199.035416)
					(mid 183.285892 -199.035416)
					(end 183.946292 -199.035416)
				)
			)
		)
	)
	(zone
		(layers "In1.Cu" "In2.Cu")
		(hatch none 0.5)
		(connect_pads
			(clearance 0)
		)
		(min_thickness 0.25)
		(keepout
			(tracks not_allowed)
			(vias allowed)
			(pads allowed)
			(copperpour not_allowed)
			(footprints allowed)
		)
		(placement
			(enabled no)
			(sheetname "")
		)
		(fill yes
			(thermal_gap 0.5)
			(thermal_bridge_width 0.5)
			(island_removal_mode 0)
		)
		(polygon
			(pts
				(arc
					(start 269.978378 -284.88513)
					(mid 269.317978 -284.88513)
					(end 269.978378 -284.88513)
				)
			)
		)
	)
	(zone
		(layers "In1.Cu" "In2.Cu")
		(hatch none 0.5)
		(connect_pads
			(clearance 0)
		)
		(min_thickness 0.25)
		(keepout
			(tracks not_allowed)
			(vias allowed)
			(pads allowed)
			(copperpour not_allowed)
			(footprints allowed)
		)
		(placement
			(enabled no)
			(sheetname "")
		)
		(fill yes
			(thermal_gap 0.5)
			(thermal_bridge_width 0.5)
			(island_removal_mode 0)
		)
		(polygon
			(pts
				(arc
					(start 22.03831 -199.035416)
					(mid 21.37791 -199.035416)
					(end 22.03831 -199.035416)
				)
			)
		)
	)
	(zone
		(layers "In1.Cu" "In2.Cu")
		(hatch none 0.5)
		(connect_pads
			(clearance 0)
		)
		(min_thickness 0.25)
		(keepout
			(tracks not_allowed)
			(vias allowed)
			(pads allowed)
			(copperpour not_allowed)
			(footprints allowed)
		)
		(placement
			(enabled no)
			(sheetname "")
		)
		(fill yes
			(thermal_gap 0.5)
			(thermal_bridge_width 0.5)
			(island_removal_mode 0)
		)
		(polygon
			(pts
				(arc
					(start 179.846224 -308.685438)
					(mid 179.185824 -308.685438)
					(end 179.846224 -308.685438)
				)
			)
		)
	)
	(zone
		(layers "In1.Cu" "In2.Cu")
		(hatch none 0.5)
		(connect_pads
			(clearance 0)
		)
		(min_thickness 0.25)
		(keepout
			(tracks not_allowed)
			(vias allowed)
			(pads allowed)
			(copperpour not_allowed)
			(footprints allowed)
		)
		(placement
			(enabled no)
			(sheetname "")
		)
		(fill yes
			(thermal_gap 0.5)
			(thermal_bridge_width 0.5)
			(island_removal_mode 0)
		)
		(polygon
			(pts
				(arc
					(start 285.066232 -238.13516)
					(mid 284.405832 -238.13516)
					(end 285.066232 -238.13516)
				)
			)
		)
	)
	(zone
		(layers "In1.Cu" "In2.Cu")
		(hatch none 0.5)
		(connect_pads
			(clearance 0)
		)
		(min_thickness 0.25)
		(keepout
			(tracks not_allowed)
			(vias allowed)
			(pads allowed)
			(copperpour not_allowed)
			(footprints allowed)
		)
		(placement
			(enabled no)
			(sheetname "")
		)
		(fill yes
			(thermal_gap 0.5)
			(thermal_bridge_width 0.5)
			(island_removal_mode 0)
		)
		(polygon
			(pts
				(arc
					(start 427.786292 -253.435104)
					(mid 427.125892 -253.435104)
					(end 427.786292 -253.435104)
				)
			)
		)
	)
	(zone
		(layers "In1.Cu" "In2.Cu")
		(hatch none 0.5)
		(connect_pads
			(clearance 0)
		)
		(min_thickness 0.25)
		(keepout
			(tracks not_allowed)
			(vias allowed)
			(pads allowed)
			(copperpour not_allowed)
			(footprints allowed)
		)
		(placement
			(enabled no)
			(sheetname "")
		)
		(fill yes
			(thermal_gap 0.5)
			(thermal_bridge_width 0.5)
			(island_removal_mode 0)
		)
		(polygon
			(pts
				(arc
					(start 273.422364 -282.33497)
					(mid 272.761964 -282.33497)
					(end 273.422364 -282.33497)
				)
			)
		)
	)
	(zone
		(layers "In1.Cu" "In2.Cu")
		(hatch none 0.5)
		(connect_pads
			(clearance 0)
		)
		(min_thickness 0.25)
		(keepout
			(tracks not_allowed)
			(vias allowed)
			(pads allowed)
			(copperpour not_allowed)
			(footprints allowed)
		)
		(placement
			(enabled no)
			(sheetname "")
		)
		(fill yes
			(thermal_gap 0.5)
			(thermal_bridge_width 0.5)
			(island_removal_mode 0)
		)
		(polygon
			(pts
				(arc
					(start 183.946292 -203.285344)
					(mid 183.285892 -203.285344)
					(end 183.946292 -203.285344)
				)
			)
		)
	)
	(zone
		(layers "In1.Cu" "In2.Cu")
		(hatch none 0.5)
		(connect_pads
			(clearance 0)
		)
		(min_thickness 0.25)
		(keepout
			(tracks not_allowed)
			(vias allowed)
			(pads allowed)
			(copperpour not_allowed)
			(footprints allowed)
		)
		(placement
			(enabled no)
			(sheetname "")
		)
		(fill yes
			(thermal_gap 0.5)
			(thermal_bridge_width 0.5)
			(island_removal_mode 0)
		)
		(polygon
			(pts
				(arc
					(start 25.482296 -199.8853)
					(mid 24.821896 -199.8853)
					(end 25.482296 -199.8853)
				)
			)
		)
	)
	(zone
		(layers "In1.Cu" "In2.Cu")
		(hatch none 0.5)
		(connect_pads
			(clearance 0)
		)
		(min_thickness 0.25)
		(keepout
			(tracks not_allowed)
			(vias allowed)
			(pads allowed)
			(copperpour not_allowed)
			(footprints allowed)
		)
		(placement
			(enabled no)
			(sheetname "")
		)
		(fill yes
			(thermal_gap 0.5)
			(thermal_bridge_width 0.5)
			(island_removal_mode 0)
		)
		(polygon
			(pts
				(arc
					(start 446.974468 -229.63505)
					(mid 446.314068 -229.63505)
					(end 446.974468 -229.63505)
				)
			)
		)
	)
	(zone
		(layers "In1.Cu" "In2.Cu")
		(hatch none 0.5)
		(connect_pads
			(clearance 0)
		)
		(min_thickness 0.25)
		(keepout
			(tracks not_allowed)
			(vias allowed)
			(pads allowed)
			(copperpour not_allowed)
			(footprints allowed)
		)
		(placement
			(enabled no)
			(sheetname "")
		)
		(fill yes
			(thermal_gap 0.5)
			(thermal_bridge_width 0.5)
			(island_removal_mode 0)
		)
		(polygon
			(pts
				(arc
					(start 431.88636 -238.13516)
					(mid 431.22596 -238.13516)
					(end 431.88636 -238.13516)
				)
			)
		)
	)
	(zone
		(layers "In1.Cu" "In2.Cu")
		(hatch none 0.5)
		(connect_pads
			(clearance 0)
		)
		(min_thickness 0.25)
		(keepout
			(tracks not_allowed)
			(vias allowed)
			(pads allowed)
			(copperpour not_allowed)
			(footprints allowed)
		)
		(placement
			(enabled no)
			(sheetname "")
		)
		(fill yes
			(thermal_gap 0.5)
			(thermal_bridge_width 0.5)
			(island_removal_mode 0)
		)
		(polygon
			(pts
				(arc
					(start 33.026096 -233.885232)
					(mid 32.365696 -233.885232)
					(end 33.026096 -233.885232)
				)
			)
		)
	)
	(zone
		(layers "In1.Cu" "In2.Cu")
		(hatch none 0.5)
		(connect_pads
			(clearance 0)
		)
		(min_thickness 0.25)
		(keepout
			(tracks not_allowed)
			(vias allowed)
			(pads allowed)
			(copperpour not_allowed)
			(footprints allowed)
		)
		(placement
			(enabled no)
			(sheetname "")
		)
		(fill yes
			(thermal_gap 0.5)
			(thermal_bridge_width 0.5)
			(island_removal_mode 0)
		)
		(polygon
			(pts
				(arc
					(start 187.390278 -299.335444)
					(mid 186.729878 -299.335444)
					(end 187.390278 -299.335444)
				)
			)
		)
	)
	(zone
		(layers "In1.Cu" "In2.Cu")
		(hatch none 0.5)
		(connect_pads
			(clearance 0)
		)
		(min_thickness 0.25)
		(keepout
			(tracks not_allowed)
			(vias allowed)
			(pads allowed)
			(copperpour not_allowed)
			(footprints allowed)
		)
		(placement
			(enabled no)
			(sheetname "")
		)
		(fill yes
			(thermal_gap 0.5)
			(thermal_bridge_width 0.5)
			(island_removal_mode 0)
		)
		(polygon
			(pts
				(arc
					(start 117.740176 -408.860244)
					(mid 117.762494 -408.914126)
					(end 117.816376 -408.936444)
				)
				(arc
					(start 118.011956 -408.936444)
					(mid 118.033832 -408.933312)
					(end 118.053866 -408.923998)
				)
				(arc
					(start 118.34749 -408.731466)
					(mid 118.389146 -408.719064)
					(end 118.430802 -408.731466)
				)
				(arc
					(start 118.725696 -408.923998)
					(mid 118.74562 -408.933234)
					(end 118.767352 -408.936444)
				)
				(arc
					(start 118.961916 -408.936444)
					(mid 119.015798 -408.914126)
					(end 119.038116 -408.860244)
				)
				(arc
					(start 119.038116 -408.174444)
					(mid 119.015798 -408.120562)
					(end 118.961916 -408.098244)
				)
				(arc
					(start 118.767352 -408.098244)
					(mid 118.745608 -408.101412)
					(end 118.725696 -408.11069)
				)
				(arc
					(start 118.429532 -408.303476)
					(mid 118.387848 -408.315698)
					(end 118.34622 -408.303222)
				)
				(arc
					(start 118.052596 -408.11069)
					(mid 118.032672 -408.101454)
					(end 118.01094 -408.098244)
				)
				(arc
					(start 117.816376 -408.098244)
					(mid 117.762494 -408.120562)
					(end 117.740176 -408.174444)
				)
			)
		)
	)
	(zone
		(layers "In1.Cu" "In2.Cu")
		(hatch none 0.5)
		(connect_pads
			(clearance 0)
		)
		(min_thickness 0.25)
		(keepout
			(tracks not_allowed)
			(vias allowed)
			(pads allowed)
			(copperpour not_allowed)
			(footprints allowed)
		)
		(placement
			(enabled no)
			(sheetname "")
		)
		(fill yes
			(thermal_gap 0.5)
			(thermal_bridge_width 0.5)
			(island_removal_mode 0)
		)
		(polygon
			(pts
				(arc
					(start 424.342306 -264.48512)
					(mid 423.681906 -264.48512)
					(end 424.342306 -264.48512)
				)
			)
		)
	)
	(zone
		(layers "In1.Cu" "In2.Cu")
		(hatch none 0.5)
		(connect_pads
			(clearance 0)
		)
		(min_thickness 0.25)
		(keepout
			(tracks not_allowed)
			(vias allowed)
			(pads allowed)
			(copperpour not_allowed)
			(footprints allowed)
		)
		(placement
			(enabled no)
			(sheetname "")
		)
		(fill yes
			(thermal_gap 0.5)
			(thermal_bridge_width 0.5)
			(island_removal_mode 0)
		)
		(polygon
			(pts
				(arc
					(start 285.066232 -197.33514)
					(mid 284.405832 -197.33514)
					(end 285.066232 -197.33514)
				)
			)
		)
	)
	(zone
		(layers "In1.Cu" "In2.Cu")
		(hatch none 0.5)
		(connect_pads
			(clearance 0)
		)
		(min_thickness 0.25)
		(keepout
			(tracks not_allowed)
			(vias allowed)
			(pads allowed)
			(copperpour not_allowed)
			(footprints allowed)
		)
		(placement
			(enabled no)
			(sheetname "")
		)
		(fill yes
			(thermal_gap 0.5)
			(thermal_bridge_width 0.5)
			(island_removal_mode 0)
		)
		(polygon
			(pts
				(arc
					(start 44.670218 -275.53539)
					(mid 44.009818 -275.53539)
					(end 44.670218 -275.53539)
				)
			)
		)
	)
	(zone
		(layers "In1.Cu" "In2.Cu")
		(hatch none 0.5)
		(connect_pads
			(clearance 0)
		)
		(min_thickness 0.25)
		(keepout
			(tracks not_allowed)
			(vias allowed)
			(pads allowed)
			(copperpour not_allowed)
			(footprints allowed)
		)
		(placement
			(enabled no)
			(sheetname "")
		)
		(fill yes
			(thermal_gap 0.5)
			(thermal_bridge_width 0.5)
			(island_removal_mode 0)
		)
		(polygon
			(pts
				(arc
					(start 191.490346 -278.085296)
					(mid 190.829946 -278.085296)
					(end 191.490346 -278.085296)
				)
			)
		)
	)
	(zone
		(layers "In1.Cu" "In2.Cu")
		(hatch none 0.5)
		(connect_pads
			(clearance 0)
		)
		(min_thickness 0.25)
		(keepout
			(tracks not_allowed)
			(vias allowed)
			(pads allowed)
			(copperpour not_allowed)
			(footprints allowed)
		)
		(placement
			(enabled no)
			(sheetname "")
		)
		(fill yes
			(thermal_gap 0.5)
			(thermal_bridge_width 0.5)
			(island_removal_mode 0)
		)
		(polygon
			(pts
				(arc
					(start 48.114204 -210.935316)
					(mid 47.453804 -210.935316)
					(end 48.114204 -210.935316)
				)
			)
		)
	)
	(zone
		(layers "In1.Cu" "In2.Cu")
		(hatch none 0.5)
		(connect_pads
			(clearance 0)
		)
		(min_thickness 0.25)
		(keepout
			(tracks not_allowed)
			(vias allowed)
			(pads allowed)
			(copperpour not_allowed)
			(footprints allowed)
		)
		(placement
			(enabled no)
			(sheetname "")
		)
		(fill yes
			(thermal_gap 0.5)
			(thermal_bridge_width 0.5)
			(island_removal_mode 0)
		)
		(polygon
			(pts
				(arc
					(start 285.066232 -261.085076)
					(mid 284.405832 -261.085076)
					(end 285.066232 -261.085076)
				)
			)
		)
	)
	(zone
		(layers "In1.Cu" "In2.Cu")
		(hatch none 0.5)
		(connect_pads
			(clearance 0)
		)
		(min_thickness 0.25)
		(keepout
			(tracks not_allowed)
			(vias allowed)
			(pads allowed)
			(copperpour not_allowed)
			(footprints allowed)
		)
		(placement
			(enabled no)
			(sheetname "")
		)
		(fill yes
			(thermal_gap 0.5)
			(thermal_bridge_width 0.5)
			(island_removal_mode 0)
		)
		(polygon
			(pts
				(arc
					(start 269.978378 -244.08511)
					(mid 269.317978 -244.08511)
					(end 269.978378 -244.08511)
				)
			)
		)
	)
	(zone
		(layers "In1.Cu" "In2.Cu")
		(hatch none 0.5)
		(connect_pads
			(clearance 0)
		)
		(min_thickness 0.25)
		(keepout
			(tracks not_allowed)
			(vias allowed)
			(pads allowed)
			(copperpour not_allowed)
			(footprints allowed)
		)
		(placement
			(enabled no)
			(sheetname "")
		)
		(fill yes
			(thermal_gap 0.5)
			(thermal_bridge_width 0.5)
			(island_removal_mode 0)
		)
		(polygon
			(pts
				(arc
					(start 199.0344 -301.88535)
					(mid 198.374 -301.88535)
					(end 199.0344 -301.88535)
				)
			)
		)
	)
	(zone
		(layers "In1.Cu" "In2.Cu")
		(hatch none 0.5)
		(connect_pads
			(clearance 0)
		)
		(min_thickness 0.25)
		(keepout
			(tracks not_allowed)
			(vias allowed)
			(pads allowed)
			(copperpour not_allowed)
			(footprints allowed)
		)
		(placement
			(enabled no)
			(sheetname "")
		)
		(fill yes
			(thermal_gap 0.5)
			(thermal_bridge_width 0.5)
			(island_removal_mode 0)
		)
		(polygon
			(pts
				(arc
					(start 183.946292 -212.635338)
					(mid 183.285892 -212.635338)
					(end 183.946292 -212.635338)
				)
			)
		)
	)
	(zone
		(layers "In1.Cu" "In2.Cu")
		(hatch none 0.5)
		(connect_pads
			(clearance 0)
		)
		(min_thickness 0.25)
		(keepout
			(tracks not_allowed)
			(vias allowed)
			(pads allowed)
			(copperpour not_allowed)
			(footprints allowed)
		)
		(placement
			(enabled no)
			(sheetname "")
		)
		(fill yes
			(thermal_gap 0.5)
			(thermal_bridge_width 0.5)
			(island_removal_mode 0)
		)
		(polygon
			(pts
				(arc
					(start 183.946292 -238.135414)
					(mid 183.285892 -238.135414)
					(end 183.946292 -238.135414)
				)
			)
		)
	)
	(zone
		(layers "In1.Cu" "In2.Cu")
		(hatch none 0.5)
		(connect_pads
			(clearance 0)
		)
		(min_thickness 0.25)
		(keepout
			(tracks not_allowed)
			(vias allowed)
			(pads allowed)
			(copperpour not_allowed)
			(footprints allowed)
		)
		(placement
			(enabled no)
			(sheetname "")
		)
		(fill yes
			(thermal_gap 0.5)
			(thermal_bridge_width 0.5)
			(island_removal_mode 0)
		)
		(polygon
			(pts
				(arc
					(start 373.740172 -417.242244)
					(mid 373.76249 -417.296126)
					(end 373.816372 -417.318444)
				)
				(arc
					(start 374.011952 -417.318444)
					(mid 374.033828 -417.315312)
					(end 374.053862 -417.305998)
				)
				(arc
					(start 374.347486 -417.113466)
					(mid 374.389142 -417.101064)
					(end 374.430798 -417.113466)
				)
				(arc
					(start 374.725692 -417.305998)
					(mid 374.745616 -417.315234)
					(end 374.767348 -417.318444)
				)
				(arc
					(start 374.961912 -417.318444)
					(mid 375.015794 -417.296126)
					(end 375.038112 -417.242244)
				)
				(arc
					(start 375.038112 -416.556444)
					(mid 375.015794 -416.502562)
					(end 374.961912 -416.480244)
				)
				(arc
					(start 374.767348 -416.480244)
					(mid 374.745604 -416.483412)
					(end 374.725692 -416.49269)
				)
				(arc
					(start 374.429528 -416.685476)
					(mid 374.387844 -416.697698)
					(end 374.346216 -416.685222)
				)
				(arc
					(start 374.052592 -416.49269)
					(mid 374.032668 -416.483454)
					(end 374.010936 -416.480244)
				)
				(arc
					(start 373.816372 -416.480244)
					(mid 373.76249 -416.502562)
					(end 373.740172 -416.556444)
				)
			)
		)
	)
	(zone
		(layers "In1.Cu" "In2.Cu")
		(hatch none 0.5)
		(connect_pads
			(clearance 0)
		)
		(min_thickness 0.25)
		(keepout
			(tracks not_allowed)
			(vias allowed)
			(pads allowed)
			(copperpour not_allowed)
			(footprints allowed)
		)
		(placement
			(enabled no)
			(sheetname "")
		)
		(fill yes
			(thermal_gap 0.5)
			(thermal_bridge_width 0.5)
			(island_removal_mode 0)
		)
		(polygon
			(pts
				(arc
					(start 44.670218 -250.885198)
					(mid 44.009818 -250.885198)
					(end 44.670218 -250.885198)
				)
			)
		)
	)
	(zone
		(layers "In1.Cu" "In2.Cu")
		(hatch none 0.5)
		(connect_pads
			(clearance 0)
		)
		(min_thickness 0.25)
		(keepout
			(tracks not_allowed)
			(vias allowed)
			(pads allowed)
			(copperpour not_allowed)
			(footprints allowed)
		)
		(placement
			(enabled no)
			(sheetname "")
		)
		(fill yes
			(thermal_gap 0.5)
			(thermal_bridge_width 0.5)
			(island_removal_mode 0)
		)
		(polygon
			(pts
				(arc
					(start 424.342306 -270.43507)
					(mid 423.681906 -270.43507)
					(end 424.342306 -270.43507)
				)
			)
		)
	)
	(zone
		(layers "In1.Cu" "In2.Cu")
		(hatch none 0.5)
		(connect_pads
			(clearance 0)
		)
		(min_thickness 0.25)
		(keepout
			(tracks not_allowed)
			(vias allowed)
			(pads allowed)
			(copperpour not_allowed)
			(footprints allowed)
		)
		(placement
			(enabled no)
			(sheetname "")
		)
		(fill yes
			(thermal_gap 0.5)
			(thermal_bridge_width 0.5)
			(island_removal_mode 0)
		)
		(polygon
			(pts
				(arc
					(start 269.978378 -304.435002)
					(mid 269.317978 -304.435002)
					(end 269.978378 -304.435002)
				)
			)
		)
	)
	(zone
		(layers "In1.Cu" "In2.Cu")
		(hatch none 0.5)
		(connect_pads
			(clearance 0)
		)
		(min_thickness 0.25)
		(keepout
			(tracks not_allowed)
			(vias allowed)
			(pads allowed)
			(copperpour not_allowed)
			(footprints allowed)
		)
		(placement
			(enabled no)
			(sheetname "")
		)
		(fill yes
			(thermal_gap 0.5)
			(thermal_bridge_width 0.5)
			(island_removal_mode 0)
		)
		(polygon
			(pts
				(arc
					(start 194.934332 -299.335444)
					(mid 194.273932 -299.335444)
					(end 194.934332 -299.335444)
				)
			)
		)
	)
	(zone
		(layers "In1.Cu" "In2.Cu")
		(hatch none 0.5)
		(connect_pads
			(clearance 0)
		)
		(min_thickness 0.25)
		(keepout
			(tracks not_allowed)
			(vias allowed)
			(pads allowed)
			(copperpour not_allowed)
			(footprints allowed)
		)
		(placement
			(enabled no)
			(sheetname "")
		)
		(fill yes
			(thermal_gap 0.5)
			(thermal_bridge_width 0.5)
			(island_removal_mode 0)
		)
		(polygon
			(pts
				(arc
					(start 33.026096 -295.085262)
					(mid 32.365696 -295.085262)
					(end 33.026096 -295.085262)
				)
			)
		)
	)
	(zone
		(layers "In1.Cu" "In2.Cu")
		(hatch none 0.5)
		(connect_pads
			(clearance 0)
		)
		(min_thickness 0.25)
		(keepout
			(tracks not_allowed)
			(vias allowed)
			(pads allowed)
			(copperpour not_allowed)
			(footprints allowed)
		)
		(placement
			(enabled no)
			(sheetname "")
		)
		(fill yes
			(thermal_gap 0.5)
			(thermal_bridge_width 0.5)
			(island_removal_mode 0)
		)
		(polygon
			(pts
				(arc
					(start 285.066232 -212.635084)
					(mid 284.405832 -212.635084)
					(end 285.066232 -212.635084)
				)
			)
		)
	)
	(zone
		(layers "In1.Cu" "In2.Cu")
		(hatch none 0.5)
		(connect_pads
			(clearance 0)
		)
		(min_thickness 0.25)
		(keepout
			(tracks not_allowed)
			(vias allowed)
			(pads allowed)
			(copperpour not_allowed)
			(footprints allowed)
		)
		(placement
			(enabled no)
			(sheetname "")
		)
		(fill yes
			(thermal_gap 0.5)
			(thermal_bridge_width 0.5)
			(island_removal_mode 0)
		)
		(polygon
			(pts
				(arc
					(start 202.478132 -295.085262)
					(mid 201.817732 -295.085262)
					(end 202.478132 -295.085262)
				)
			)
		)
	)
	(zone
		(layers "In1.Cu" "In2.Cu")
		(hatch none 0.5)
		(connect_pads
			(clearance 0)
		)
		(min_thickness 0.25)
		(keepout
			(tracks not_allowed)
			(vias allowed)
			(pads allowed)
			(copperpour not_allowed)
			(footprints allowed)
		)
		(placement
			(enabled no)
			(sheetname "")
		)
		(fill yes
			(thermal_gap 0.5)
			(thermal_bridge_width 0.5)
			(island_removal_mode 0)
		)
		(polygon
			(pts
				(arc
					(start 442.8744 -224.534984)
					(mid 442.214 -224.534984)
					(end 442.8744 -224.534984)
				)
			)
		)
	)
	(zone
		(layers "In1.Cu" "In2.Cu")
		(hatch none 0.5)
		(connect_pads
			(clearance 0)
		)
		(min_thickness 0.25)
		(keepout
			(tracks not_allowed)
			(vias allowed)
			(pads allowed)
			(copperpour not_allowed)
			(footprints allowed)
		)
		(placement
			(enabled no)
			(sheetname "")
		)
		(fill yes
			(thermal_gap 0.5)
			(thermal_bridge_width 0.5)
			(island_removal_mode 0)
		)
		(polygon
			(pts
				(arc
					(start 420.242238 -282.33497)
					(mid 419.581838 -282.33497)
					(end 420.242238 -282.33497)
				)
			)
		)
	)
	(zone
		(layers "In1.Cu" "In2.Cu")
		(hatch none 0.5)
		(connect_pads
			(clearance 0)
		)
		(min_thickness 0.25)
		(keepout
			(tracks not_allowed)
			(vias allowed)
			(pads allowed)
			(copperpour not_allowed)
			(footprints allowed)
		)
		(placement
			(enabled no)
			(sheetname "")
		)
		(fill yes
			(thermal_gap 0.5)
			(thermal_bridge_width 0.5)
			(island_removal_mode 0)
		)
		(polygon
			(pts
				(arc
					(start 431.88636 -244.08511)
					(mid 431.22596 -244.08511)
					(end 431.88636 -244.08511)
				)
			)
		)
	)
	(zone
		(layers "In1.Cu" "In2.Cu")
		(hatch none 0.5)
		(connect_pads
			(clearance 0)
		)
		(min_thickness 0.25)
		(keepout
			(tracks not_allowed)
			(vias allowed)
			(pads allowed)
			(copperpour not_allowed)
			(footprints allowed)
		)
		(placement
			(enabled no)
			(sheetname "")
		)
		(fill yes
			(thermal_gap 0.5)
			(thermal_bridge_width 0.5)
			(island_removal_mode 0)
		)
		(polygon
			(pts
				(arc
					(start 172.30217 -250.035314)
					(mid 171.64177 -250.035314)
					(end 172.30217 -250.035314)
				)
			)
		)
	)
	(zone
		(layers "In1.Cu" "In2.Cu")
		(hatch none 0.5)
		(connect_pads
			(clearance 0)
		)
		(min_thickness 0.25)
		(keepout
			(tracks not_allowed)
			(vias allowed)
			(pads allowed)
			(copperpour not_allowed)
			(footprints allowed)
		)
		(placement
			(enabled no)
			(sheetname "")
		)
		(fill yes
			(thermal_gap 0.5)
			(thermal_bridge_width 0.5)
			(island_removal_mode 0)
		)
		(polygon
			(pts
				(arc
					(start 288.510218 -211.784946)
					(mid 287.849818 -211.784946)
					(end 288.510218 -211.784946)
				)
			)
		)
	)
	(zone
		(layers "In1.Cu" "In2.Cu")
		(hatch none 0.5)
		(connect_pads
			(clearance 0)
		)
		(min_thickness 0.25)
		(keepout
			(tracks not_allowed)
			(vias allowed)
			(pads allowed)
			(copperpour not_allowed)
			(footprints allowed)
		)
		(placement
			(enabled no)
			(sheetname "")
		)
		(fill yes
			(thermal_gap 0.5)
			(thermal_bridge_width 0.5)
			(island_removal_mode 0)
		)
		(polygon
			(pts
				(arc
					(start 187.390278 -198.185278)
					(mid 186.729878 -198.185278)
					(end 187.390278 -198.185278)
				)
			)
		)
	)
	(zone
		(layers "In1.Cu" "In2.Cu")
		(hatch none 0.5)
		(connect_pads
			(clearance 0)
		)
		(min_thickness 0.25)
		(keepout
			(tracks not_allowed)
			(vias allowed)
			(pads allowed)
			(copperpour not_allowed)
			(footprints allowed)
		)
		(placement
			(enabled no)
			(sheetname "")
		)
		(fill yes
			(thermal_gap 0.5)
			(thermal_bridge_width 0.5)
			(island_removal_mode 0)
		)
		(polygon
			(pts
				(arc
					(start 277.522432 -295.085008)
					(mid 276.862032 -295.085008)
					(end 277.522432 -295.085008)
				)
			)
		)
	)
	(zone
		(layers "In1.Cu" "In2.Cu")
		(hatch none 0.5)
		(connect_pads
			(clearance 0)
		)
		(min_thickness 0.25)
		(keepout
			(tracks not_allowed)
			(vias allowed)
			(pads allowed)
			(copperpour not_allowed)
			(footprints allowed)
		)
		(placement
			(enabled no)
			(sheetname "")
		)
		(fill yes
			(thermal_gap 0.5)
			(thermal_bridge_width 0.5)
			(island_removal_mode 0)
		)
		(polygon
			(pts
				(arc
					(start 431.88636 -210.935062)
					(mid 431.22596 -210.935062)
					(end 431.88636 -210.935062)
				)
			)
		)
	)
	(zone
		(layers "In1.Cu" "In2.Cu")
		(hatch none 0.5)
		(connect_pads
			(clearance 0)
		)
		(min_thickness 0.25)
		(keepout
			(tracks not_allowed)
			(vias allowed)
			(pads allowed)
			(copperpour not_allowed)
			(footprints allowed)
		)
		(placement
			(enabled no)
			(sheetname "")
		)
		(fill yes
			(thermal_gap 0.5)
			(thermal_bridge_width 0.5)
			(island_removal_mode 0)
		)
		(polygon
			(pts
				(arc
					(start 431.88636 -252.584966)
					(mid 431.22596 -252.584966)
					(end 431.88636 -252.584966)
				)
			)
		)
	)
	(zone
		(layers "In1.Cu" "In2.Cu")
		(hatch none 0.5)
		(connect_pads
			(clearance 0)
		)
		(min_thickness 0.25)
		(keepout
			(tracks not_allowed)
			(vias allowed)
			(pads allowed)
			(copperpour not_allowed)
			(footprints allowed)
		)
		(placement
			(enabled no)
			(sheetname "")
		)
		(fill yes
			(thermal_gap 0.5)
			(thermal_bridge_width 0.5)
			(island_removal_mode 0)
		)
		(polygon
			(pts
				(arc
					(start 52.214272 -250.885198)
					(mid 51.553872 -250.885198)
					(end 52.214272 -250.885198)
				)
			)
		)
	)
	(zone
		(layers "In1.Cu" "In2.Cu")
		(hatch none 0.5)
		(connect_pads
			(clearance 0)
		)
		(min_thickness 0.25)
		(keepout
			(tracks not_allowed)
			(vias allowed)
			(pads allowed)
			(copperpour not_allowed)
			(footprints allowed)
		)
		(placement
			(enabled no)
			(sheetname "")
		)
		(fill yes
			(thermal_gap 0.5)
			(thermal_bridge_width 0.5)
			(island_removal_mode 0)
		)
		(polygon
			(pts
				(arc
					(start 269.978378 -221.985078)
					(mid 269.317978 -221.985078)
					(end 269.978378 -221.985078)
				)
			)
		)
	)
	(zone
		(layers "In1.Cu" "In2.Cu")
		(hatch none 0.5)
		(connect_pads
			(clearance 0)
		)
		(min_thickness 0.25)
		(keepout
			(tracks not_allowed)
			(vias allowed)
			(pads allowed)
			(copperpour not_allowed)
			(footprints allowed)
		)
		(placement
			(enabled no)
			(sheetname "")
		)
		(fill yes
			(thermal_gap 0.5)
			(thermal_bridge_width 0.5)
			(island_removal_mode 0)
		)
		(polygon
			(pts
				(arc
					(start 194.934332 -211.7852)
					(mid 194.273932 -211.7852)
					(end 194.934332 -211.7852)
				)
			)
		)
	)
	(zone
		(layers "In1.Cu" "In2.Cu")
		(hatch none 0.5)
		(connect_pads
			(clearance 0)
		)
		(min_thickness 0.25)
		(keepout
			(tracks not_allowed)
			(vias allowed)
			(pads allowed)
			(copperpour not_allowed)
			(footprints allowed)
		)
		(placement
			(enabled no)
			(sheetname "")
		)
		(fill yes
			(thermal_gap 0.5)
			(thermal_bridge_width 0.5)
			(island_removal_mode 0)
		)
		(polygon
			(pts
				(arc
					(start 40.57015 -302.735234)
					(mid 39.90975 -302.735234)
					(end 40.57015 -302.735234)
				)
			)
		)
	)
	(zone
		(layers "In1.Cu" "In2.Cu")
		(hatch none 0.5)
		(connect_pads
			(clearance 0)
		)
		(min_thickness 0.25)
		(keepout
			(tracks not_allowed)
			(vias allowed)
			(pads allowed)
			(copperpour not_allowed)
			(footprints allowed)
		)
		(placement
			(enabled no)
			(sheetname "")
		)
		(fill yes
			(thermal_gap 0.5)
			(thermal_bridge_width 0.5)
			(island_removal_mode 0)
		)
		(polygon
			(pts
				(arc
					(start 450.4182 -215.18499)
					(mid 449.7578 -215.18499)
					(end 450.4182 -215.18499)
				)
			)
		)
	)
	(zone
		(layers "In1.Cu" "In2.Cu")
		(hatch none 0.5)
		(connect_pads
			(clearance 0)
		)
		(min_thickness 0.25)
		(keepout
			(tracks not_allowed)
			(vias allowed)
			(pads allowed)
			(copperpour not_allowed)
			(footprints allowed)
		)
		(placement
			(enabled no)
			(sheetname "")
		)
		(fill yes
			(thermal_gap 0.5)
			(thermal_bridge_width 0.5)
			(island_removal_mode 0)
		)
		(polygon
			(pts
				(arc
					(start 202.478132 -216.885266)
					(mid 201.817732 -216.885266)
					(end 202.478132 -216.885266)
				)
			)
		)
	)
	(zone
		(layers "In1.Cu" "In2.Cu")
		(hatch none 0.5)
		(connect_pads
			(clearance 0)
		)
		(min_thickness 0.25)
		(keepout
			(tracks not_allowed)
			(vias allowed)
			(pads allowed)
			(copperpour not_allowed)
			(footprints allowed)
		)
		(placement
			(enabled no)
			(sheetname "")
		)
		(fill yes
			(thermal_gap 0.5)
			(thermal_bridge_width 0.5)
			(island_removal_mode 0)
		)
		(polygon
			(pts
				(arc
					(start 439.430414 -272.135092)
					(mid 438.770014 -272.135092)
					(end 439.430414 -272.135092)
				)
			)
		)
	)
	(zone
		(layers "In1.Cu" "In2.Cu")
		(hatch none 0.5)
		(connect_pads
			(clearance 0)
		)
		(min_thickness 0.25)
		(keepout
			(tracks not_allowed)
			(vias allowed)
			(pads allowed)
			(copperpour not_allowed)
			(footprints allowed)
		)
		(placement
			(enabled no)
			(sheetname "")
		)
		(fill yes
			(thermal_gap 0.5)
			(thermal_bridge_width 0.5)
			(island_removal_mode 0)
		)
		(polygon
			(pts
				(arc
					(start 199.0344 -247.485408)
					(mid 198.374 -247.485408)
					(end 199.0344 -247.485408)
				)
			)
		)
	)
	(zone
		(layers "In1.Cu" "In2.Cu")
		(hatch none 0.5)
		(connect_pads
			(clearance 0)
		)
		(min_thickness 0.25)
		(keepout
			(tracks not_allowed)
			(vias allowed)
			(pads allowed)
			(copperpour not_allowed)
			(footprints allowed)
		)
		(placement
			(enabled no)
			(sheetname "")
		)
		(fill yes
			(thermal_gap 0.5)
			(thermal_bridge_width 0.5)
			(island_removal_mode 0)
		)
		(polygon
			(pts
				(arc
					(start 33.026096 -209.235294)
					(mid 32.365696 -209.235294)
					(end 33.026096 -209.235294)
				)
			)
		)
	)
	(zone
		(layers "In1.Cu" "In2.Cu")
		(hatch none 0.5)
		(connect_pads
			(clearance 0)
		)
		(min_thickness 0.25)
		(keepout
			(tracks not_allowed)
			(vias allowed)
			(pads allowed)
			(copperpour not_allowed)
			(footprints allowed)
		)
		(placement
			(enabled no)
			(sheetname "")
		)
		(fill yes
			(thermal_gap 0.5)
			(thermal_bridge_width 0.5)
			(island_removal_mode 0)
		)
		(polygon
			(pts
				(arc
					(start 277.522432 -240.685066)
					(mid 276.862032 -240.685066)
					(end 277.522432 -240.685066)
				)
			)
		)
	)
	(zone
		(layers "In1.Cu" "In2.Cu")
		(hatch none 0.5)
		(connect_pads
			(clearance 0)
		)
		(min_thickness 0.25)
		(keepout
			(tracks not_allowed)
			(vias allowed)
			(pads allowed)
			(copperpour not_allowed)
			(footprints allowed)
		)
		(placement
			(enabled no)
			(sheetname "")
		)
		(fill yes
			(thermal_gap 0.5)
			(thermal_bridge_width 0.5)
			(island_removal_mode 0)
		)
		(polygon
			(pts
				(arc
					(start 420.242238 -278.93518)
					(mid 419.581838 -278.93518)
					(end 420.242238 -278.93518)
				)
			)
		)
	)
	(zone
		(layers "In1.Cu" "In2.Cu")
		(hatch none 0.5)
		(connect_pads
			(clearance 0)
		)
		(min_thickness 0.25)
		(keepout
			(tracks not_allowed)
			(vias allowed)
			(pads allowed)
			(copperpour not_allowed)
			(footprints allowed)
		)
		(placement
			(enabled no)
			(sheetname "")
		)
		(fill yes
			(thermal_gap 0.5)
			(thermal_bridge_width 0.5)
			(island_removal_mode 0)
		)
		(polygon
			(pts
				(arc
					(start 40.57015 -202.435206)
					(mid 39.90975 -202.435206)
					(end 40.57015 -202.435206)
				)
			)
		)
	)
	(zone
		(layers "In1.Cu" "In2.Cu")
		(hatch none 0.5)
		(connect_pads
			(clearance 0)
		)
		(min_thickness 0.25)
		(keepout
			(tracks not_allowed)
			(vias allowed)
			(pads allowed)
			(copperpour not_allowed)
			(footprints allowed)
		)
		(placement
			(enabled no)
			(sheetname "")
		)
		(fill yes
			(thermal_gap 0.5)
			(thermal_bridge_width 0.5)
			(island_removal_mode 0)
		)
		(polygon
			(pts
				(arc
					(start 17.938242 -318.035432)
					(mid 17.277842 -318.035432)
					(end 17.938242 -318.035432)
				)
			)
		)
	)
	(zone
		(layers "In1.Cu" "In2.Cu")
		(hatch none 0.5)
		(connect_pads
			(clearance 0)
		)
		(min_thickness 0.25)
		(keepout
			(tracks not_allowed)
			(vias allowed)
			(pads allowed)
			(copperpour not_allowed)
			(footprints allowed)
		)
		(placement
			(enabled no)
			(sheetname "")
		)
		(fill yes
			(thermal_gap 0.5)
			(thermal_bridge_width 0.5)
			(island_removal_mode 0)
		)
		(polygon
			(pts
				(arc
					(start 33.026096 -293.38524)
					(mid 32.365696 -293.38524)
					(end 33.026096 -293.38524)
				)
			)
		)
	)
	(zone
		(layers "In1.Cu" "In2.Cu")
		(hatch none 0.5)
		(connect_pads
			(clearance 0)
		)
		(min_thickness 0.25)
		(keepout
			(tracks not_allowed)
			(vias allowed)
			(pads allowed)
			(copperpour not_allowed)
			(footprints allowed)
		)
		(placement
			(enabled no)
			(sheetname "")
		)
		(fill yes
			(thermal_gap 0.5)
			(thermal_bridge_width 0.5)
			(island_removal_mode 0)
		)
		(polygon
			(pts
				(arc
					(start 292.610286 -317.18504)
					(mid 291.949886 -317.18504)
					(end 292.610286 -317.18504)
				)
			)
		)
	)
	(zone
		(layers "In1.Cu" "In2.Cu")
		(hatch none 0.5)
		(connect_pads
			(clearance 0)
		)
		(min_thickness 0.25)
		(keepout
			(tracks not_allowed)
			(vias allowed)
			(pads allowed)
			(copperpour not_allowed)
			(footprints allowed)
		)
		(placement
			(enabled no)
			(sheetname "")
		)
		(fill yes
			(thermal_gap 0.5)
			(thermal_bridge_width 0.5)
			(island_removal_mode 0)
		)
		(polygon
			(pts
				(arc
					(start 450.4182 -201.585068)
					(mid 449.7578 -201.585068)
					(end 450.4182 -201.585068)
				)
			)
		)
	)
	(zone
		(layers "In1.Cu" "In2.Cu")
		(hatch none 0.5)
		(connect_pads
			(clearance 0)
		)
		(min_thickness 0.25)
		(keepout
			(tracks not_allowed)
			(vias allowed)
			(pads allowed)
			(copperpour not_allowed)
			(footprints allowed)
		)
		(placement
			(enabled no)
			(sheetname "")
		)
		(fill yes
			(thermal_gap 0.5)
			(thermal_bridge_width 0.5)
			(island_removal_mode 0)
		)
		(polygon
			(pts
				(arc
					(start 202.478132 -313.78525)
					(mid 201.817732 -313.78525)
					(end 202.478132 -313.78525)
				)
			)
		)
	)
	(zone
		(layers "In1.Cu" "In2.Cu")
		(hatch none 0.5)
		(connect_pads
			(clearance 0)
		)
		(min_thickness 0.25)
		(keepout
			(tracks not_allowed)
			(vias allowed)
			(pads allowed)
			(copperpour not_allowed)
			(footprints allowed)
		)
		(placement
			(enabled no)
			(sheetname "")
		)
		(fill yes
			(thermal_gap 0.5)
			(thermal_bridge_width 0.5)
			(island_removal_mode 0)
		)
		(polygon
			(pts
				(arc
					(start 285.066232 -204.985112)
					(mid 284.405832 -204.985112)
					(end 285.066232 -204.985112)
				)
			)
		)
	)
	(zone
		(layers "In1.Cu" "In2.Cu")
		(hatch none 0.5)
		(connect_pads
			(clearance 0)
		)
		(min_thickness 0.25)
		(keepout
			(tracks not_allowed)
			(vias allowed)
			(pads allowed)
			(copperpour not_allowed)
			(footprints allowed)
		)
		(placement
			(enabled no)
			(sheetname "")
		)
		(fill yes
			(thermal_gap 0.5)
			(thermal_bridge_width 0.5)
			(island_removal_mode 0)
		)
		(polygon
			(pts
				(arc
					(start 33.026096 -250.035314)
					(mid 32.365696 -250.035314)
					(end 33.026096 -250.035314)
				)
			)
		)
	)
	(zone
		(layers "In1.Cu" "In2.Cu")
		(hatch none 0.5)
		(connect_pads
			(clearance 0)
		)
		(min_thickness 0.25)
		(keepout
			(tracks not_allowed)
			(vias allowed)
			(pads allowed)
			(copperpour not_allowed)
			(footprints allowed)
		)
		(placement
			(enabled no)
			(sheetname "")
		)
		(fill yes
			(thermal_gap 0.5)
			(thermal_bridge_width 0.5)
			(island_removal_mode 0)
		)
		(polygon
			(pts
				(arc
					(start 44.670218 -200.735438)
					(mid 44.009818 -200.735438)
					(end 44.670218 -200.735438)
				)
			)
		)
	)
	(zone
		(layers "In1.Cu" "In2.Cu")
		(hatch none 0.5)
		(connect_pads
			(clearance 0)
		)
		(min_thickness 0.25)
		(keepout
			(tracks not_allowed)
			(vias allowed)
			(pads allowed)
			(copperpour not_allowed)
			(footprints allowed)
		)
		(placement
			(enabled no)
			(sheetname "")
		)
		(fill yes
			(thermal_gap 0.5)
			(thermal_bridge_width 0.5)
			(island_removal_mode 0)
		)
		(polygon
			(pts
				(arc
					(start 136.410446 -370.978684)
					(mid 136.43037 -370.98792)
					(end 136.452102 -370.99113)
				)
				(arc
					(start 136.646666 -370.99113)
					(mid 136.700548 -370.968812)
					(end 136.722866 -370.91493)
				)
				(arc
					(start 136.722866 -370.22913)
					(mid 136.700548 -370.175248)
					(end 136.646666 -370.15293)
				)
				(arc
					(start 136.452102 -370.15293)
					(mid 136.430358 -370.156098)
					(end 136.410446 -370.165376)
				)
				(arc
					(start 136.114282 -370.358162)
					(mid 136.072598 -370.370384)
					(end 136.03097 -370.357908)
				)
				(arc
					(start 135.737346 -370.165376)
					(mid 135.717422 -370.15614)
					(end 135.69569 -370.15293)
				)
				(arc
					(start 135.501126 -370.15293)
					(mid 135.447244 -370.175248)
					(end 135.424926 -370.22913)
				)
				(arc
					(start 135.424926 -370.91493)
					(mid 135.447244 -370.968812)
					(end 135.501126 -370.99113)
				)
				(arc
					(start 135.69696 -370.99113)
					(mid 135.718704 -370.987962)
					(end 135.738616 -370.978684)
				)
				(arc
					(start 136.03224 -370.786152)
					(mid 136.073896 -370.77375)
					(end 136.115552 -370.786152)
				)
			)
		)
	)
	(zone
		(layers "In1.Cu" "In2.Cu")
		(hatch none 0.5)
		(connect_pads
			(clearance 0)
		)
		(min_thickness 0.25)
		(keepout
			(tracks not_allowed)
			(vias allowed)
			(pads allowed)
			(copperpour not_allowed)
			(footprints allowed)
		)
		(placement
			(enabled no)
			(sheetname "")
		)
		(fill yes
			(thermal_gap 0.5)
			(thermal_bridge_width 0.5)
			(island_removal_mode 0)
		)
		(polygon
			(pts
				(arc
					(start 431.88636 -197.33514)
					(mid 431.22596 -197.33514)
					(end 431.88636 -197.33514)
				)
			)
		)
	)
	(zone
		(layers "In1.Cu" "In2.Cu")
		(hatch none 0.5)
		(connect_pads
			(clearance 0)
		)
		(min_thickness 0.25)
		(keepout
			(tracks not_allowed)
			(vias allowed)
			(pads allowed)
			(copperpour not_allowed)
			(footprints allowed)
		)
		(placement
			(enabled no)
			(sheetname "")
		)
		(fill yes
			(thermal_gap 0.5)
			(thermal_bridge_width 0.5)
			(island_removal_mode 0)
		)
		(polygon
			(pts
				(arc
					(start 131.305046 -373.442484)
					(mid 131.32497 -373.45172)
					(end 131.346702 -373.45493)
				)
				(arc
					(start 131.541266 -373.45493)
					(mid 131.595148 -373.432612)
					(end 131.617466 -373.37873)
				)
				(arc
					(start 131.617466 -372.69293)
					(mid 131.595148 -372.639048)
					(end 131.541266 -372.61673)
				)
				(arc
					(start 131.346702 -372.61673)
					(mid 131.324958 -372.619898)
					(end 131.305046 -372.629176)
				)
				(arc
					(start 131.008882 -372.821962)
					(mid 130.967198 -372.834184)
					(end 130.92557 -372.821708)
				)
				(arc
					(start 130.631946 -372.629176)
					(mid 130.612022 -372.61994)
					(end 130.59029 -372.61673)
				)
				(arc
					(start 130.395726 -372.61673)
					(mid 130.341844 -372.639048)
					(end 130.319526 -372.69293)
				)
				(arc
					(start 130.319526 -373.37873)
					(mid 130.341844 -373.432612)
					(end 130.395726 -373.45493)
				)
				(arc
					(start 130.59156 -373.45493)
					(mid 130.613304 -373.451762)
					(end 130.633216 -373.442484)
				)
				(arc
					(start 130.92684 -373.249952)
					(mid 130.968496 -373.23755)
					(end 131.010152 -373.249952)
				)
			)
		)
	)
	(zone
		(layers "In1.Cu" "In2.Cu")
		(hatch none 0.5)
		(connect_pads
			(clearance 0)
		)
		(min_thickness 0.25)
		(keepout
			(tracks not_allowed)
			(vias allowed)
			(pads allowed)
			(copperpour not_allowed)
			(footprints allowed)
		)
		(placement
			(enabled no)
			(sheetname "")
		)
		(fill yes
			(thermal_gap 0.5)
			(thermal_bridge_width 0.5)
			(island_removal_mode 0)
		)
		(polygon
			(pts
				(arc
					(start 420.242238 -226.235006)
					(mid 419.581838 -226.235006)
					(end 420.242238 -226.235006)
				)
			)
		)
	)
	(zone
		(layers "In1.Cu" "In2.Cu")
		(hatch none 0.5)
		(connect_pads
			(clearance 0)
		)
		(min_thickness 0.25)
		(keepout
			(tracks not_allowed)
			(vias allowed)
			(pads allowed)
			(copperpour not_allowed)
			(footprints allowed)
		)
		(placement
			(enabled no)
			(sheetname "")
		)
		(fill yes
			(thermal_gap 0.5)
			(thermal_bridge_width 0.5)
			(island_removal_mode 0)
		)
		(polygon
			(pts
				(arc
					(start 435.330346 -295.935146)
					(mid 434.669946 -295.935146)
					(end 435.330346 -295.935146)
				)
			)
		)
	)
	(zone
		(layers "In1.Cu" "In2.Cu")
		(hatch none 0.5)
		(connect_pads
			(clearance 0)
		)
		(min_thickness 0.25)
		(keepout
			(tracks not_allowed)
			(vias allowed)
			(pads allowed)
			(copperpour not_allowed)
			(footprints allowed)
		)
		(placement
			(enabled no)
			(sheetname "")
		)
		(fill yes
			(thermal_gap 0.5)
			(thermal_bridge_width 0.5)
			(island_removal_mode 0)
		)
		(polygon
			(pts
				(arc
					(start 48.114204 -302.735234)
					(mid 47.453804 -302.735234)
					(end 48.114204 -302.735234)
				)
			)
		)
	)
	(zone
		(layers "In1.Cu" "In2.Cu")
		(hatch none 0.5)
		(connect_pads
			(clearance 0)
		)
		(min_thickness 0.25)
		(keepout
			(tracks not_allowed)
			(vias allowed)
			(pads allowed)
			(copperpour not_allowed)
			(footprints allowed)
		)
		(placement
			(enabled no)
			(sheetname "")
		)
		(fill yes
			(thermal_gap 0.5)
			(thermal_bridge_width 0.5)
			(island_removal_mode 0)
		)
		(polygon
			(pts
				(arc
					(start 398.188434 -390.65581)
					(mid 398.179198 -390.675734)
					(end 398.175988 -390.697466)
				)
				(arc
					(start 398.175988 -390.89203)
					(mid 398.198306 -390.945912)
					(end 398.252188 -390.96823)
				)
				(arc
					(start 398.937988 -390.96823)
					(mid 398.99187 -390.945912)
					(end 399.014188 -390.89203)
				)
				(arc
					(start 399.014188 -390.697466)
					(mid 399.01102 -390.675722)
					(end 399.001742 -390.65581)
				)
				(arc
					(start 398.808956 -390.359646)
					(mid 398.796734 -390.317962)
					(end 398.80921 -390.276334)
				)
				(arc
					(start 399.001742 -389.98271)
					(mid 399.010978 -389.962786)
					(end 399.014188 -389.941054)
				)
				(arc
					(start 399.014188 -389.74649)
					(mid 398.99187 -389.692608)
					(end 398.937988 -389.67029)
				)
				(arc
					(start 398.252188 -389.67029)
					(mid 398.198306 -389.692608)
					(end 398.175988 -389.74649)
				)
				(arc
					(start 398.175988 -389.942324)
					(mid 398.179156 -389.964068)
					(end 398.188434 -389.98398)
				)
				(arc
					(start 398.380966 -390.277604)
					(mid 398.393368 -390.31926)
					(end 398.380966 -390.360916)
				)
			)
		)
	)
	(zone
		(layers "In1.Cu" "In2.Cu")
		(hatch none 0.5)
		(connect_pads
			(clearance 0)
		)
		(min_thickness 0.25)
		(keepout
			(tracks not_allowed)
			(vias allowed)
			(pads allowed)
			(copperpour not_allowed)
			(footprints allowed)
		)
		(placement
			(enabled no)
			(sheetname "")
		)
		(fill yes
			(thermal_gap 0.5)
			(thermal_bridge_width 0.5)
			(island_removal_mode 0)
		)
		(polygon
			(pts
				(arc
					(start 280.966164 -306.985162)
					(mid 280.305764 -306.985162)
					(end 280.966164 -306.985162)
				)
			)
		)
	)
	(zone
		(layers "In1.Cu" "In2.Cu")
		(hatch none 0.5)
		(connect_pads
			(clearance 0)
		)
		(min_thickness 0.25)
		(keepout
			(tracks not_allowed)
			(vias allowed)
			(pads allowed)
			(copperpour not_allowed)
			(footprints allowed)
		)
		(placement
			(enabled no)
			(sheetname "")
		)
		(fill yes
			(thermal_gap 0.5)
			(thermal_bridge_width 0.5)
			(island_removal_mode 0)
		)
		(polygon
			(pts
				(arc
					(start 442.8744 -289.985196)
					(mid 442.214 -289.985196)
					(end 442.8744 -289.985196)
				)
			)
		)
	)
	(zone
		(layers "In1.Cu" "In2.Cu")
		(hatch none 0.5)
		(connect_pads
			(clearance 0)
		)
		(min_thickness 0.25)
		(keepout
			(tracks not_allowed)
			(vias allowed)
			(pads allowed)
			(copperpour not_allowed)
			(footprints allowed)
		)
		(placement
			(enabled no)
			(sheetname "")
		)
		(fill yes
			(thermal_gap 0.5)
			(thermal_bridge_width 0.5)
			(island_removal_mode 0)
		)
		(polygon
			(pts
				(arc
					(start 288.510218 -265.335004)
					(mid 287.849818 -265.335004)
					(end 288.510218 -265.335004)
				)
			)
		)
	)
	(zone
		(layers "In1.Cu" "In2.Cu")
		(hatch none 0.5)
		(connect_pads
			(clearance 0)
		)
		(min_thickness 0.25)
		(keepout
			(tracks not_allowed)
			(vias allowed)
			(pads allowed)
			(copperpour not_allowed)
			(footprints allowed)
		)
		(placement
			(enabled no)
			(sheetname "")
		)
		(fill yes
			(thermal_gap 0.5)
			(thermal_bridge_width 0.5)
			(island_removal_mode 0)
		)
		(polygon
			(pts
				(arc
					(start 300.15434 -281.485086)
					(mid 299.49394 -281.485086)
					(end 300.15434 -281.485086)
				)
			)
		)
	)
	(zone
		(layers "In1.Cu" "In2.Cu")
		(hatch none 0.5)
		(connect_pads
			(clearance 0)
		)
		(min_thickness 0.25)
		(keepout
			(tracks not_allowed)
			(vias allowed)
			(pads allowed)
			(copperpour not_allowed)
			(footprints allowed)
		)
		(placement
			(enabled no)
			(sheetname "")
		)
		(fill yes
			(thermal_gap 0.5)
			(thermal_bridge_width 0.5)
			(island_removal_mode 0)
		)
		(polygon
			(pts
				(arc
					(start 179.846224 -248.335292)
					(mid 179.185824 -248.335292)
					(end 179.846224 -248.335292)
				)
			)
		)
	)
	(zone
		(layers "In1.Cu" "In2.Cu")
		(hatch none 0.5)
		(connect_pads
			(clearance 0)
		)
		(min_thickness 0.25)
		(keepout
			(tracks not_allowed)
			(vias allowed)
			(pads allowed)
			(copperpour not_allowed)
			(footprints allowed)
		)
		(placement
			(enabled no)
			(sheetname "")
		)
		(fill yes
			(thermal_gap 0.5)
			(thermal_bridge_width 0.5)
			(island_removal_mode 0)
		)
		(polygon
			(pts
				(arc
					(start 172.30217 -198.185278)
					(mid 171.64177 -198.185278)
					(end 172.30217 -198.185278)
				)
			)
		)
	)
	(zone
		(layers "In1.Cu" "In2.Cu")
		(hatch none 0.5)
		(connect_pads
			(clearance 0)
		)
		(min_thickness 0.25)
		(keepout
			(tracks not_allowed)
			(vias allowed)
			(pads allowed)
			(copperpour not_allowed)
			(footprints allowed)
		)
		(placement
			(enabled no)
			(sheetname "")
		)
		(fill yes
			(thermal_gap 0.5)
			(thermal_bridge_width 0.5)
			(island_removal_mode 0)
		)
		(polygon
			(pts
				(arc
					(start 187.390278 -286.585406)
					(mid 186.729878 -286.585406)
					(end 187.390278 -286.585406)
				)
			)
		)
	)
	(zone
		(layers "In1.Cu" "In2.Cu")
		(hatch none 0.5)
		(connect_pads
			(clearance 0)
		)
		(min_thickness 0.25)
		(keepout
			(tracks not_allowed)
			(vias allowed)
			(pads allowed)
			(copperpour not_allowed)
			(footprints allowed)
		)
		(placement
			(enabled no)
			(sheetname "")
		)
		(fill yes
			(thermal_gap 0.5)
			(thermal_bridge_width 0.5)
			(island_removal_mode 0)
		)
		(polygon
			(pts
				(arc
					(start 285.066232 -275.535136)
					(mid 284.405832 -275.535136)
					(end 285.066232 -275.535136)
				)
			)
		)
	)
	(zone
		(layers "In1.Cu" "In2.Cu")
		(hatch none 0.5)
		(connect_pads
			(clearance 0)
		)
		(min_thickness 0.25)
		(keepout
			(tracks not_allowed)
			(vias allowed)
			(pads allowed)
			(copperpour not_allowed)
			(footprints allowed)
		)
		(placement
			(enabled no)
			(sheetname "")
		)
		(fill yes
			(thermal_gap 0.5)
			(thermal_bridge_width 0.5)
			(island_removal_mode 0)
		)
		(polygon
			(pts
				(arc
					(start 22.03831 -221.985332)
					(mid 21.37791 -221.985332)
					(end 22.03831 -221.985332)
				)
			)
		)
	)
	(zone
		(layers "In1.Cu" "In2.Cu")
		(hatch none 0.5)
		(connect_pads
			(clearance 0)
		)
		(min_thickness 0.25)
		(keepout
			(tracks not_allowed)
			(vias allowed)
			(pads allowed)
			(copperpour not_allowed)
			(footprints allowed)
		)
		(placement
			(enabled no)
			(sheetname "")
		)
		(fill yes
			(thermal_gap 0.5)
			(thermal_bridge_width 0.5)
			(island_removal_mode 0)
		)
		(polygon
			(pts
				(arc
					(start 179.846224 -297.635422)
					(mid 179.185824 -297.635422)
					(end 179.846224 -297.635422)
				)
			)
		)
	)
	(zone
		(layers "In1.Cu" "In2.Cu")
		(hatch none 0.5)
		(connect_pads
			(clearance 0)
		)
		(min_thickness 0.25)
		(keepout
			(tracks not_allowed)
			(vias allowed)
			(pads allowed)
			(copperpour not_allowed)
			(footprints allowed)
		)
		(placement
			(enabled no)
			(sheetname "")
		)
		(fill yes
			(thermal_gap 0.5)
			(thermal_bridge_width 0.5)
			(island_removal_mode 0)
		)
		(polygon
			(pts
				(arc
					(start 179.846224 -293.38524)
					(mid 179.185824 -293.38524)
					(end 179.846224 -293.38524)
				)
			)
		)
	)
	(zone
		(layers "In1.Cu" "In2.Cu")
		(hatch none 0.5)
		(connect_pads
			(clearance 0)
		)
		(min_thickness 0.25)
		(keepout
			(tracks not_allowed)
			(vias allowed)
			(pads allowed)
			(copperpour not_allowed)
			(footprints allowed)
		)
		(placement
			(enabled no)
			(sheetname "")
		)
		(fill yes
			(thermal_gap 0.5)
			(thermal_bridge_width 0.5)
			(island_removal_mode 0)
		)
		(polygon
			(pts
				(arc
					(start 25.482296 -250.035314)
					(mid 24.821896 -250.035314)
					(end 25.482296 -250.035314)
				)
			)
		)
	)
	(zone
		(layers "In1.Cu" "In2.Cu")
		(hatch none 0.5)
		(connect_pads
			(clearance 0)
		)
		(min_thickness 0.25)
		(keepout
			(tracks not_allowed)
			(vias allowed)
			(pads allowed)
			(copperpour not_allowed)
			(footprints allowed)
		)
		(placement
			(enabled no)
			(sheetname "")
		)
		(fill yes
			(thermal_gap 0.5)
			(thermal_bridge_width 0.5)
			(island_removal_mode 0)
		)
		(polygon
			(pts
				(arc
					(start 25.482296 -218.585288)
					(mid 24.821896 -218.585288)
					(end 25.482296 -218.585288)
				)
			)
		)
	)
	(zone
		(layers "In1.Cu" "In2.Cu")
		(hatch none 0.5)
		(connect_pads
			(clearance 0)
		)
		(min_thickness 0.25)
		(keepout
			(tracks not_allowed)
			(vias allowed)
			(pads allowed)
			(copperpour not_allowed)
			(footprints allowed)
		)
		(placement
			(enabled no)
			(sheetname "")
		)
		(fill yes
			(thermal_gap 0.5)
			(thermal_bridge_width 0.5)
			(island_removal_mode 0)
		)
		(polygon
			(pts
				(arc
					(start 269.978378 -231.335072)
					(mid 269.317978 -231.335072)
					(end 269.978378 -231.335072)
				)
			)
		)
	)
	(zone
		(layers "In1.Cu" "In2.Cu")
		(hatch none 0.5)
		(connect_pads
			(clearance 0)
		)
		(min_thickness 0.25)
		(keepout
			(tracks not_allowed)
			(vias allowed)
			(pads allowed)
			(copperpour not_allowed)
			(footprints allowed)
		)
		(placement
			(enabled no)
			(sheetname "")
		)
		(fill yes
			(thermal_gap 0.5)
			(thermal_bridge_width 0.5)
			(island_removal_mode 0)
		)
		(polygon
			(pts
				(arc
					(start 300.15434 -272.135092)
					(mid 299.49394 -272.135092)
					(end 300.15434 -272.135092)
				)
			)
		)
	)
	(zone
		(layers "In1.Cu" "In2.Cu")
		(hatch none 0.5)
		(connect_pads
			(clearance 0)
		)
		(min_thickness 0.25)
		(keepout
			(tracks not_allowed)
			(vias allowed)
			(pads allowed)
			(copperpour not_allowed)
			(footprints allowed)
		)
		(placement
			(enabled no)
			(sheetname "")
		)
		(fill yes
			(thermal_gap 0.5)
			(thermal_bridge_width 0.5)
			(island_removal_mode 0)
		)
		(polygon
			(pts
				(arc
					(start 202.478132 -238.985298)
					(mid 201.817732 -238.985298)
					(end 202.478132 -238.985298)
				)
			)
		)
	)
	(zone
		(layers "In1.Cu" "In2.Cu")
		(hatch none 0.5)
		(connect_pads
			(clearance 0)
		)
		(min_thickness 0.25)
		(keepout
			(tracks not_allowed)
			(vias allowed)
			(pads allowed)
			(copperpour not_allowed)
			(footprints allowed)
		)
		(placement
			(enabled no)
			(sheetname "")
		)
		(fill yes
			(thermal_gap 0.5)
			(thermal_bridge_width 0.5)
			(island_removal_mode 0)
		)
		(polygon
			(pts
				(arc
					(start 101.862128 -376.861578)
					(mid 101.852892 -376.881502)
					(end 101.849682 -376.903234)
				)
				(arc
					(start 101.849682 -377.097798)
					(mid 101.872 -377.15168)
					(end 101.925882 -377.173998)
				)
				(arc
					(start 102.611682 -377.173998)
					(mid 102.665564 -377.15168)
					(end 102.687882 -377.097798)
				)
				(arc
					(start 102.687882 -376.903234)
					(mid 102.684714 -376.88149)
					(end 102.675436 -376.861578)
				)
				(arc
					(start 102.48265 -376.565414)
					(mid 102.470428 -376.52373)
					(end 102.482904 -376.482102)
				)
				(arc
					(start 102.675436 -376.188478)
					(mid 102.684672 -376.168554)
					(end 102.687882 -376.146822)
				)
				(arc
					(start 102.687882 -375.952258)
					(mid 102.665564 -375.898376)
					(end 102.611682 -375.876058)
				)
				(arc
					(start 101.925882 -375.876058)
					(mid 101.872 -375.898376)
					(end 101.849682 -375.952258)
				)
				(arc
					(start 101.849682 -376.148092)
					(mid 101.85285 -376.169836)
					(end 101.862128 -376.189748)
				)
				(arc
					(start 102.05466 -376.483372)
					(mid 102.067062 -376.525028)
					(end 102.05466 -376.566684)
				)
			)
		)
	)
	(zone
		(layers "In1.Cu" "In2.Cu")
		(hatch none 0.5)
		(connect_pads
			(clearance 0)
		)
		(min_thickness 0.25)
		(keepout
			(tracks not_allowed)
			(vias allowed)
			(pads allowed)
			(copperpour not_allowed)
			(footprints allowed)
		)
		(placement
			(enabled no)
			(sheetname "")
		)
		(fill yes
			(thermal_gap 0.5)
			(thermal_bridge_width 0.5)
			(island_removal_mode 0)
		)
		(polygon
			(pts
				(arc
					(start 168.858184 -244.08511)
					(mid 168.197784 -244.08511)
					(end 168.858184 -244.08511)
				)
			)
		)
	)
	(zone
		(layers "In1.Cu" "In2.Cu")
		(hatch none 0.5)
		(connect_pads
			(clearance 0)
		)
		(min_thickness 0.25)
		(keepout
			(tracks not_allowed)
			(vias allowed)
			(pads allowed)
			(copperpour not_allowed)
			(footprints allowed)
		)
		(placement
			(enabled no)
			(sheetname "")
		)
		(fill yes
			(thermal_gap 0.5)
			(thermal_bridge_width 0.5)
			(island_removal_mode 0)
		)
		(polygon
			(pts
				(arc
					(start 40.57015 -238.985298)
					(mid 39.90975 -238.985298)
					(end 40.57015 -238.985298)
				)
			)
		)
	)
	(zone
		(layers "In1.Cu" "In2.Cu")
		(hatch none 0.5)
		(connect_pads
			(clearance 0)
		)
		(min_thickness 0.25)
		(keepout
			(tracks not_allowed)
			(vias allowed)
			(pads allowed)
			(copperpour not_allowed)
			(footprints allowed)
		)
		(placement
			(enabled no)
			(sheetname "")
		)
		(fill yes
			(thermal_gap 0.5)
			(thermal_bridge_width 0.5)
			(island_removal_mode 0)
		)
		(polygon
			(pts
				(arc
					(start 273.422364 -211.784946)
					(mid 272.761964 -211.784946)
					(end 273.422364 -211.784946)
				)
			)
		)
	)
	(zone
		(layers "In1.Cu" "In2.Cu")
		(hatch none 0.5)
		(connect_pads
			(clearance 0)
		)
		(min_thickness 0.25)
		(keepout
			(tracks not_allowed)
			(vias allowed)
			(pads allowed)
			(copperpour not_allowed)
			(footprints allowed)
		)
		(placement
			(enabled no)
			(sheetname "")
		)
		(fill yes
			(thermal_gap 0.5)
			(thermal_bridge_width 0.5)
			(island_removal_mode 0)
		)
		(polygon
			(pts
				(arc
					(start 280.966164 -199.885046)
					(mid 280.305764 -199.885046)
					(end 280.966164 -199.885046)
				)
			)
		)
	)
	(zone
		(layers "In1.Cu" "In2.Cu")
		(hatch none 0.5)
		(connect_pads
			(clearance 0)
		)
		(min_thickness 0.25)
		(keepout
			(tracks not_allowed)
			(vias allowed)
			(pads allowed)
			(copperpour not_allowed)
			(footprints allowed)
		)
		(placement
			(enabled no)
			(sheetname "")
		)
		(fill yes
			(thermal_gap 0.5)
			(thermal_bridge_width 0.5)
			(island_removal_mode 0)
		)
		(polygon
			(pts
				(arc
					(start 17.938242 -278.935434)
					(mid 17.277842 -278.935434)
					(end 17.938242 -278.935434)
				)
			)
		)
	)
	(zone
		(layers "In1.Cu" "In2.Cu")
		(hatch none 0.5)
		(connect_pads
			(clearance 0)
		)
		(min_thickness 0.25)
		(keepout
			(tracks not_allowed)
			(vias allowed)
			(pads allowed)
			(copperpour not_allowed)
			(footprints allowed)
		)
		(placement
			(enabled no)
			(sheetname "")
		)
		(fill yes
			(thermal_gap 0.5)
			(thermal_bridge_width 0.5)
			(island_removal_mode 0)
		)
		(polygon
			(pts
				(arc
					(start 183.946292 -273.835368)
					(mid 183.285892 -273.835368)
					(end 183.946292 -273.835368)
				)
			)
		)
	)
	(zone
		(layers "In1.Cu" "In2.Cu")
		(hatch none 0.5)
		(connect_pads
			(clearance 0)
		)
		(min_thickness 0.25)
		(keepout
			(tracks not_allowed)
			(vias allowed)
			(pads allowed)
			(copperpour not_allowed)
			(footprints allowed)
		)
		(placement
			(enabled no)
			(sheetname "")
		)
		(fill yes
			(thermal_gap 0.5)
			(thermal_bridge_width 0.5)
			(island_removal_mode 0)
		)
		(polygon
			(pts
				(arc
					(start 439.430414 -217.73515)
					(mid 438.770014 -217.73515)
					(end 439.430414 -217.73515)
				)
			)
		)
	)
	(zone
		(layers "In1.Cu" "In2.Cu")
		(hatch none 0.5)
		(connect_pads
			(clearance 0)
		)
		(min_thickness 0.25)
		(keepout
			(tracks not_allowed)
			(vias allowed)
			(pads allowed)
			(copperpour not_allowed)
			(footprints allowed)
		)
		(placement
			(enabled no)
			(sheetname "")
		)
		(fill yes
			(thermal_gap 0.5)
			(thermal_bridge_width 0.5)
			(island_removal_mode 0)
		)
		(polygon
			(pts
				(arc
					(start 179.846224 -261.935214)
					(mid 179.185824 -261.935214)
					(end 179.846224 -261.935214)
				)
			)
		)
	)
	(zone
		(layers "In1.Cu" "In2.Cu")
		(hatch none 0.5)
		(connect_pads
			(clearance 0)
		)
		(min_thickness 0.25)
		(keepout
			(tracks not_allowed)
			(vias allowed)
			(pads allowed)
			(copperpour not_allowed)
			(footprints allowed)
		)
		(placement
			(enabled no)
			(sheetname "")
		)
		(fill yes
			(thermal_gap 0.5)
			(thermal_bridge_width 0.5)
			(island_removal_mode 0)
		)
		(polygon
			(pts
				(arc
					(start 25.482296 -295.085262)
					(mid 24.821896 -295.085262)
					(end 25.482296 -295.085262)
				)
			)
		)
	)
	(zone
		(layers "In1.Cu" "In2.Cu")
		(hatch none 0.5)
		(connect_pads
			(clearance 0)
		)
		(min_thickness 0.25)
		(keepout
			(tracks not_allowed)
			(vias allowed)
			(pads allowed)
			(copperpour not_allowed)
			(footprints allowed)
		)
		(placement
			(enabled no)
			(sheetname "")
		)
		(fill yes
			(thermal_gap 0.5)
			(thermal_bridge_width 0.5)
			(island_removal_mode 0)
		)
		(polygon
			(pts
				(arc
					(start 172.30217 -295.9354)
					(mid 171.64177 -295.9354)
					(end 172.30217 -295.9354)
				)
			)
		)
	)
	(zone
		(layers "In1.Cu" "In2.Cu")
		(hatch none 0.5)
		(connect_pads
			(clearance 0)
		)
		(min_thickness 0.25)
		(keepout
			(tracks not_allowed)
			(vias allowed)
			(pads allowed)
			(copperpour not_allowed)
			(footprints allowed)
		)
		(placement
			(enabled no)
			(sheetname "")
		)
		(fill yes
			(thermal_gap 0.5)
			(thermal_bridge_width 0.5)
			(island_removal_mode 0)
		)
		(polygon
			(pts
				(arc
					(start 29.582364 -223.685354)
					(mid 28.921964 -223.685354)
					(end 29.582364 -223.685354)
				)
			)
		)
	)
	(zone
		(layers "In1.Cu" "In2.Cu")
		(hatch none 0.5)
		(connect_pads
			(clearance 0)
		)
		(min_thickness 0.25)
		(keepout
			(tracks not_allowed)
			(vias allowed)
			(pads allowed)
			(copperpour not_allowed)
			(footprints allowed)
		)
		(placement
			(enabled no)
			(sheetname "")
		)
		(fill yes
			(thermal_gap 0.5)
			(thermal_bridge_width 0.5)
			(island_removal_mode 0)
		)
		(polygon
			(pts
				(arc
					(start 172.30217 -304.435256)
					(mid 171.64177 -304.435256)
					(end 172.30217 -304.435256)
				)
			)
		)
	)
	(zone
		(layers "In1.Cu" "In2.Cu")
		(hatch none 0.5)
		(connect_pads
			(clearance 0)
		)
		(min_thickness 0.25)
		(keepout
			(tracks not_allowed)
			(vias allowed)
			(pads allowed)
			(copperpour not_allowed)
			(footprints allowed)
		)
		(placement
			(enabled no)
			(sheetname "")
		)
		(fill yes
			(thermal_gap 0.5)
			(thermal_bridge_width 0.5)
			(island_removal_mode 0)
		)
		(polygon
			(pts
				(arc
					(start 191.490346 -290.835334)
					(mid 190.829946 -290.835334)
					(end 191.490346 -290.835334)
				)
			)
		)
	)
	(zone
		(layers "In1.Cu" "In2.Cu")
		(hatch none 0.5)
		(connect_pads
			(clearance 0)
		)
		(min_thickness 0.25)
		(keepout
			(tracks not_allowed)
			(vias allowed)
			(pads allowed)
			(copperpour not_allowed)
			(footprints allowed)
		)
		(placement
			(enabled no)
			(sheetname "")
		)
		(fill yes
			(thermal_gap 0.5)
			(thermal_bridge_width 0.5)
			(island_removal_mode 0)
		)
		(polygon
			(pts
				(arc
					(start 427.786292 -235.585)
					(mid 427.125892 -235.585)
					(end 427.786292 -235.585)
				)
			)
		)
	)
	(zone
		(layers "In1.Cu" "In2.Cu")
		(hatch none 0.5)
		(connect_pads
			(clearance 0)
		)
		(min_thickness 0.25)
		(keepout
			(tracks not_allowed)
			(vias allowed)
			(pads allowed)
			(copperpour not_allowed)
			(footprints allowed)
		)
		(placement
			(enabled no)
			(sheetname "")
		)
		(fill yes
			(thermal_gap 0.5)
			(thermal_bridge_width 0.5)
			(island_removal_mode 0)
		)
		(polygon
			(pts
				(arc
					(start 300.15434 -315.485018)
					(mid 299.49394 -315.485018)
					(end 300.15434 -315.485018)
				)
			)
		)
	)
	(zone
		(layers "In1.Cu" "In2.Cu")
		(hatch none 0.5)
		(connect_pads
			(clearance 0)
		)
		(min_thickness 0.25)
		(keepout
			(tracks not_allowed)
			(vias allowed)
			(pads allowed)
			(copperpour not_allowed)
			(footprints allowed)
		)
		(placement
			(enabled no)
			(sheetname "")
		)
		(fill yes
			(thermal_gap 0.5)
			(thermal_bridge_width 0.5)
			(island_removal_mode 0)
		)
		(polygon
			(pts
				(arc
					(start 427.786292 -232.184956)
					(mid 427.125892 -232.184956)
					(end 427.786292 -232.184956)
				)
			)
		)
	)
	(zone
		(layers "In1.Cu" "In2.Cu")
		(hatch none 0.5)
		(connect_pads
			(clearance 0)
		)
		(min_thickness 0.25)
		(keepout
			(tracks not_allowed)
			(vias allowed)
			(pads allowed)
			(copperpour not_allowed)
			(footprints allowed)
		)
		(placement
			(enabled no)
			(sheetname "")
		)
		(fill yes
			(thermal_gap 0.5)
			(thermal_bridge_width 0.5)
			(island_removal_mode 0)
		)
		(polygon
			(pts
				(arc
					(start 17.938242 -204.135228)
					(mid 17.277842 -204.135228)
					(end 17.938242 -204.135228)
				)
			)
		)
	)
	(zone
		(layers "In1.Cu" "In2.Cu")
		(hatch none 0.5)
		(connect_pads
			(clearance 0)
		)
		(min_thickness 0.25)
		(keepout
			(tracks not_allowed)
			(vias allowed)
			(pads allowed)
			(copperpour not_allowed)
			(footprints allowed)
		)
		(placement
			(enabled no)
			(sheetname "")
		)
		(fill yes
			(thermal_gap 0.5)
			(thermal_bridge_width 0.5)
			(island_removal_mode 0)
		)
		(polygon
			(pts
				(arc
					(start 183.946292 -283.185362)
					(mid 183.285892 -283.185362)
					(end 183.946292 -283.185362)
				)
			)
		)
	)
	(zone
		(layers "In1.Cu" "In2.Cu")
		(hatch none 0.5)
		(connect_pads
			(clearance 0)
		)
		(min_thickness 0.25)
		(keepout
			(tracks not_allowed)
			(vias allowed)
			(pads allowed)
			(copperpour not_allowed)
			(footprints allowed)
		)
		(placement
			(enabled no)
			(sheetname "")
		)
		(fill yes
			(thermal_gap 0.5)
			(thermal_bridge_width 0.5)
			(island_removal_mode 0)
		)
		(polygon
			(pts
				(arc
					(start 292.610286 -279.785064)
					(mid 291.949886 -279.785064)
					(end 292.610286 -279.785064)
				)
			)
		)
	)
	(zone
		(layers "In1.Cu" "In2.Cu")
		(hatch none 0.5)
		(connect_pads
			(clearance 0)
		)
		(min_thickness 0.25)
		(keepout
			(tracks not_allowed)
			(vias allowed)
			(pads allowed)
			(copperpour not_allowed)
			(footprints allowed)
		)
		(placement
			(enabled no)
			(sheetname "")
		)
		(fill yes
			(thermal_gap 0.5)
			(thermal_bridge_width 0.5)
			(island_removal_mode 0)
		)
		(polygon
			(pts
				(arc
					(start 40.57015 -218.585288)
					(mid 39.90975 -218.585288)
					(end 40.57015 -218.585288)
				)
			)
		)
	)
	(zone
		(layers "In1.Cu" "In2.Cu")
		(hatch none 0.5)
		(connect_pads
			(clearance 0)
		)
		(min_thickness 0.25)
		(keepout
			(tracks not_allowed)
			(vias allowed)
			(pads allowed)
			(copperpour not_allowed)
			(footprints allowed)
		)
		(placement
			(enabled no)
			(sheetname "")
		)
		(fill yes
			(thermal_gap 0.5)
			(thermal_bridge_width 0.5)
			(island_removal_mode 0)
		)
		(polygon
			(pts
				(arc
					(start 187.390278 -243.235226)
					(mid 186.729878 -243.235226)
					(end 187.390278 -243.235226)
				)
			)
		)
	)
	(zone
		(layers "In1.Cu" "In2.Cu")
		(hatch none 0.5)
		(connect_pads
			(clearance 0)
		)
		(min_thickness 0.25)
		(keepout
			(tracks not_allowed)
			(vias allowed)
			(pads allowed)
			(copperpour not_allowed)
			(footprints allowed)
		)
		(placement
			(enabled no)
			(sheetname "")
		)
		(fill yes
			(thermal_gap 0.5)
			(thermal_bridge_width 0.5)
			(island_removal_mode 0)
		)
		(polygon
			(pts
				(arc
					(start 37.126164 -317.185294)
					(mid 36.465764 -317.185294)
					(end 37.126164 -317.185294)
				)
			)
		)
	)
	(zone
		(layers "In1.Cu" "In2.Cu")
		(hatch none 0.5)
		(connect_pads
			(clearance 0)
		)
		(min_thickness 0.25)
		(keepout
			(tracks not_allowed)
			(vias allowed)
			(pads allowed)
			(copperpour not_allowed)
			(footprints allowed)
		)
		(placement
			(enabled no)
			(sheetname "")
		)
		(fill yes
			(thermal_gap 0.5)
			(thermal_bridge_width 0.5)
			(island_removal_mode 0)
		)
		(polygon
			(pts
				(arc
					(start 288.510218 -304.435002)
					(mid 287.849818 -304.435002)
					(end 288.510218 -304.435002)
				)
			)
		)
	)
	(zone
		(layers "In1.Cu" "In2.Cu")
		(hatch none 0.5)
		(connect_pads
			(clearance 0)
		)
		(min_thickness 0.25)
		(keepout
			(tracks not_allowed)
			(vias allowed)
			(pads allowed)
			(copperpour not_allowed)
			(footprints allowed)
		)
		(placement
			(enabled no)
			(sheetname "")
		)
		(fill yes
			(thermal_gap 0.5)
			(thermal_bridge_width 0.5)
			(island_removal_mode 0)
		)
		(polygon
			(pts
				(arc
					(start 300.15434 -264.48512)
					(mid 299.49394 -264.48512)
					(end 300.15434 -264.48512)
				)
			)
		)
	)
	(zone
		(layers "In1.Cu" "In2.Cu")
		(hatch none 0.5)
		(connect_pads
			(clearance 0)
		)
		(min_thickness 0.25)
		(keepout
			(tracks not_allowed)
			(vias allowed)
			(pads allowed)
			(copperpour not_allowed)
			(footprints allowed)
		)
		(placement
			(enabled no)
			(sheetname "")
		)
		(fill yes
			(thermal_gap 0.5)
			(thermal_bridge_width 0.5)
			(island_removal_mode 0)
		)
		(polygon
			(pts
				(arc
					(start 33.026096 -267.03528)
					(mid 32.365696 -267.03528)
					(end 33.026096 -267.03528)
				)
			)
		)
	)
	(zone
		(layers "In1.Cu" "In2.Cu")
		(hatch none 0.5)
		(connect_pads
			(clearance 0)
		)
		(min_thickness 0.25)
		(keepout
			(tracks not_allowed)
			(vias allowed)
			(pads allowed)
			(copperpour not_allowed)
			(footprints allowed)
		)
		(placement
			(enabled no)
			(sheetname "")
		)
		(fill yes
			(thermal_gap 0.5)
			(thermal_bridge_width 0.5)
			(island_removal_mode 0)
		)
		(polygon
			(pts
				(arc
					(start 439.430414 -240.685066)
					(mid 438.770014 -240.685066)
					(end 439.430414 -240.685066)
				)
			)
		)
	)
	(zone
		(layers "In1.Cu" "In2.Cu")
		(hatch none 0.5)
		(connect_pads
			(clearance 0)
		)
		(min_thickness 0.25)
		(keepout
			(tracks not_allowed)
			(vias allowed)
			(pads allowed)
			(copperpour not_allowed)
			(footprints allowed)
		)
		(placement
			(enabled no)
			(sheetname "")
		)
		(fill yes
			(thermal_gap 0.5)
			(thermal_bridge_width 0.5)
			(island_removal_mode 0)
		)
		(polygon
			(pts
				(arc
					(start 280.966164 -232.184956)
					(mid 280.305764 -232.184956)
					(end 280.966164 -232.184956)
				)
			)
		)
	)
	(zone
		(layers "In1.Cu" "In2.Cu")
		(hatch none 0.5)
		(connect_pads
			(clearance 0)
		)
		(min_thickness 0.25)
		(keepout
			(tracks not_allowed)
			(vias allowed)
			(pads allowed)
			(copperpour not_allowed)
			(footprints allowed)
		)
		(placement
			(enabled no)
			(sheetname "")
		)
		(fill yes
			(thermal_gap 0.5)
			(thermal_bridge_width 0.5)
			(island_removal_mode 0)
		)
		(polygon
			(pts
				(arc
					(start 446.974468 -273.835114)
					(mid 446.314068 -273.835114)
					(end 446.974468 -273.835114)
				)
			)
		)
	)
	(zone
		(layers "In1.Cu" "In2.Cu")
		(hatch none 0.5)
		(connect_pads
			(clearance 0)
		)
		(min_thickness 0.25)
		(keepout
			(tracks not_allowed)
			(vias allowed)
			(pads allowed)
			(copperpour not_allowed)
			(footprints allowed)
		)
		(placement
			(enabled no)
			(sheetname "")
		)
		(fill yes
			(thermal_gap 0.5)
			(thermal_bridge_width 0.5)
			(island_removal_mode 0)
		)
		(polygon
			(pts
				(arc
					(start 194.934332 -232.18521)
					(mid 194.273932 -232.18521)
					(end 194.934332 -232.18521)
				)
			)
		)
	)
	(zone
		(layers "In1.Cu" "In2.Cu")
		(hatch none 0.5)
		(connect_pads
			(clearance 0)
		)
		(min_thickness 0.25)
		(keepout
			(tracks not_allowed)
			(vias allowed)
			(pads allowed)
			(copperpour not_allowed)
			(footprints allowed)
		)
		(placement
			(enabled no)
			(sheetname "")
		)
		(fill yes
			(thermal_gap 0.5)
			(thermal_bridge_width 0.5)
			(island_removal_mode 0)
		)
		(polygon
			(pts
				(arc
					(start 431.88636 -249.185176)
					(mid 431.22596 -249.185176)
					(end 431.88636 -249.185176)
				)
			)
		)
	)
	(zone
		(layers "In1.Cu" "In2.Cu")
		(hatch none 0.5)
		(connect_pads
			(clearance 0)
		)
		(min_thickness 0.25)
		(keepout
			(tracks not_allowed)
			(vias allowed)
			(pads allowed)
			(copperpour not_allowed)
			(footprints allowed)
		)
		(placement
			(enabled no)
			(sheetname "")
		)
		(fill yes
			(thermal_gap 0.5)
			(thermal_bridge_width 0.5)
			(island_removal_mode 0)
		)
		(polygon
			(pts
				(arc
					(start 191.490346 -236.435392)
					(mid 190.829946 -236.435392)
					(end 191.490346 -236.435392)
				)
			)
		)
	)
	(zone
		(layers "In1.Cu" "In2.Cu")
		(hatch none 0.5)
		(connect_pads
			(clearance 0)
		)
		(min_thickness 0.25)
		(keepout
			(tracks not_allowed)
			(vias allowed)
			(pads allowed)
			(copperpour not_allowed)
			(footprints allowed)
		)
		(placement
			(enabled no)
			(sheetname "")
		)
		(fill yes
			(thermal_gap 0.5)
			(thermal_bridge_width 0.5)
			(island_removal_mode 0)
		)
		(polygon
			(pts
				(arc
					(start 191.490346 -295.085262)
					(mid 190.829946 -295.085262)
					(end 191.490346 -295.085262)
				)
			)
		)
	)
	(zone
		(layers "In1.Cu" "In2.Cu")
		(hatch none 0.5)
		(connect_pads
			(clearance 0)
		)
		(min_thickness 0.25)
		(keepout
			(tracks not_allowed)
			(vias allowed)
			(pads allowed)
			(copperpour not_allowed)
			(footprints allowed)
		)
		(placement
			(enabled no)
			(sheetname "")
		)
		(fill yes
			(thermal_gap 0.5)
			(thermal_bridge_width 0.5)
			(island_removal_mode 0)
		)
		(polygon
			(pts
				(arc
					(start 22.03831 -296.785284)
					(mid 21.37791 -296.785284)
					(end 22.03831 -296.785284)
				)
			)
		)
	)
	(zone
		(layers "In1.Cu" "In2.Cu")
		(hatch none 0.5)
		(connect_pads
			(clearance 0)
		)
		(min_thickness 0.25)
		(keepout
			(tracks not_allowed)
			(vias allowed)
			(pads allowed)
			(copperpour not_allowed)
			(footprints allowed)
		)
		(placement
			(enabled no)
			(sheetname "")
		)
		(fill yes
			(thermal_gap 0.5)
			(thermal_bridge_width 0.5)
			(island_removal_mode 0)
		)
		(polygon
			(pts
				(arc
					(start 296.054272 -201.585068)
					(mid 295.393872 -201.585068)
					(end 296.054272 -201.585068)
				)
			)
		)
	)
	(zone
		(layers "In1.Cu" "In2.Cu")
		(hatch none 0.5)
		(connect_pads
			(clearance 0)
		)
		(min_thickness 0.25)
		(keepout
			(tracks not_allowed)
			(vias allowed)
			(pads allowed)
			(copperpour not_allowed)
			(footprints allowed)
		)
		(placement
			(enabled no)
			(sheetname "")
		)
		(fill yes
			(thermal_gap 0.5)
			(thermal_bridge_width 0.5)
			(island_removal_mode 0)
		)
		(polygon
			(pts
				(arc
					(start 172.30217 -199.8853)
					(mid 171.64177 -199.8853)
					(end 172.30217 -199.8853)
				)
			)
		)
	)
	(zone
		(layers "In1.Cu" "In2.Cu")
		(hatch none 0.5)
		(connect_pads
			(clearance 0)
		)
		(min_thickness 0.25)
		(keepout
			(tracks not_allowed)
			(vias allowed)
			(pads allowed)
			(copperpour not_allowed)
			(footprints allowed)
		)
		(placement
			(enabled no)
			(sheetname "")
		)
		(fill yes
			(thermal_gap 0.5)
			(thermal_bridge_width 0.5)
			(island_removal_mode 0)
		)
		(polygon
			(pts
				(arc
					(start 37.126164 -210.935316)
					(mid 36.465764 -210.935316)
					(end 37.126164 -210.935316)
				)
			)
		)
	)
	(zone
		(layers "In1.Cu" "In2.Cu")
		(hatch none 0.5)
		(connect_pads
			(clearance 0)
		)
		(min_thickness 0.25)
		(keepout
			(tracks not_allowed)
			(vias allowed)
			(pads allowed)
			(copperpour not_allowed)
			(footprints allowed)
		)
		(placement
			(enabled no)
			(sheetname "")
		)
		(fill yes
			(thermal_gap 0.5)
			(thermal_bridge_width 0.5)
			(island_removal_mode 0)
		)
		(polygon
			(pts
				(arc
					(start 25.482296 -282.335224)
					(mid 24.821896 -282.335224)
					(end 25.482296 -282.335224)
				)
			)
		)
	)
	(zone
		(layers "In1.Cu" "In2.Cu")
		(hatch none 0.5)
		(connect_pads
			(clearance 0)
		)
		(min_thickness 0.25)
		(keepout
			(tracks not_allowed)
			(vias allowed)
			(pads allowed)
			(copperpour not_allowed)
			(footprints allowed)
		)
		(placement
			(enabled no)
			(sheetname "")
		)
		(fill yes
			(thermal_gap 0.5)
			(thermal_bridge_width 0.5)
			(island_removal_mode 0)
		)
		(polygon
			(pts
				(arc
					(start 179.846224 -291.685218)
					(mid 179.185824 -291.685218)
					(end 179.846224 -291.685218)
				)
			)
		)
	)
	(zone
		(layers "In1.Cu" "In2.Cu")
		(hatch none 0.5)
		(connect_pads
			(clearance 0)
		)
		(min_thickness 0.25)
		(keepout
			(tracks not_allowed)
			(vias allowed)
			(pads allowed)
			(copperpour not_allowed)
			(footprints allowed)
		)
		(placement
			(enabled no)
			(sheetname "")
		)
		(fill yes
			(thermal_gap 0.5)
			(thermal_bridge_width 0.5)
			(island_removal_mode 0)
		)
		(polygon
			(pts
				(arc
					(start 269.978378 -214.335106)
					(mid 269.317978 -214.335106)
					(end 269.978378 -214.335106)
				)
			)
		)
	)
	(zone
		(layers "In1.Cu" "In2.Cu")
		(hatch none 0.5)
		(connect_pads
			(clearance 0)
		)
		(min_thickness 0.25)
		(keepout
			(tracks not_allowed)
			(vias allowed)
			(pads allowed)
			(copperpour not_allowed)
			(footprints allowed)
		)
		(placement
			(enabled no)
			(sheetname "")
		)
		(fill yes
			(thermal_gap 0.5)
			(thermal_bridge_width 0.5)
			(island_removal_mode 0)
		)
		(polygon
			(pts
				(arc
					(start 435.330346 -207.535018)
					(mid 434.669946 -207.535018)
					(end 435.330346 -207.535018)
				)
			)
		)
	)
	(zone
		(layers "In1.Cu" "In2.Cu")
		(hatch none 0.5)
		(connect_pads
			(clearance 0)
		)
		(min_thickness 0.25)
		(keepout
			(tracks not_allowed)
			(vias allowed)
			(pads allowed)
			(copperpour not_allowed)
			(footprints allowed)
		)
		(placement
			(enabled no)
			(sheetname "")
		)
		(fill yes
			(thermal_gap 0.5)
			(thermal_bridge_width 0.5)
			(island_removal_mode 0)
		)
		(polygon
			(pts
				(arc
					(start 183.946292 -236.435392)
					(mid 183.285892 -236.435392)
					(end 183.946292 -236.435392)
				)
			)
		)
	)
	(zone
		(layers "In1.Cu" "In2.Cu")
		(hatch none 0.5)
		(connect_pads
			(clearance 0)
		)
		(min_thickness 0.25)
		(keepout
			(tracks not_allowed)
			(vias allowed)
			(pads allowed)
			(copperpour not_allowed)
			(footprints allowed)
		)
		(placement
			(enabled no)
			(sheetname "")
		)
		(fill yes
			(thermal_gap 0.5)
			(thermal_bridge_width 0.5)
			(island_removal_mode 0)
		)
		(polygon
			(pts
				(arc
					(start 296.054272 -229.63505)
					(mid 295.393872 -229.63505)
					(end 296.054272 -229.63505)
				)
			)
		)
	)
	(zone
		(layers "In1.Cu" "In2.Cu")
		(hatch none 0.5)
		(connect_pads
			(clearance 0)
		)
		(min_thickness 0.25)
		(keepout
			(tracks not_allowed)
			(vias allowed)
			(pads allowed)
			(copperpour not_allowed)
			(footprints allowed)
		)
		(placement
			(enabled no)
			(sheetname "")
		)
		(fill yes
			(thermal_gap 0.5)
			(thermal_bridge_width 0.5)
			(island_removal_mode 0)
		)
		(polygon
			(pts
				(arc
					(start 136.434322 -376.861578)
					(mid 136.425086 -376.881502)
					(end 136.421876 -376.903234)
				)
				(arc
					(start 136.421876 -377.097798)
					(mid 136.444194 -377.15168)
					(end 136.498076 -377.173998)
				)
				(arc
					(start 137.183876 -377.173998)
					(mid 137.237758 -377.15168)
					(end 137.260076 -377.097798)
				)
				(arc
					(start 137.260076 -376.903234)
					(mid 137.256908 -376.88149)
					(end 137.24763 -376.861578)
				)
				(arc
					(start 137.054844 -376.565414)
					(mid 137.042622 -376.52373)
					(end 137.055098 -376.482102)
				)
				(arc
					(start 137.24763 -376.188478)
					(mid 137.256866 -376.168554)
					(end 137.260076 -376.146822)
				)
				(arc
					(start 137.260076 -375.952258)
					(mid 137.237758 -375.898376)
					(end 137.183876 -375.876058)
				)
				(arc
					(start 136.498076 -375.876058)
					(mid 136.444194 -375.898376)
					(end 136.421876 -375.952258)
				)
				(arc
					(start 136.421876 -376.148092)
					(mid 136.425044 -376.169836)
					(end 136.434322 -376.189748)
				)
				(arc
					(start 136.626854 -376.483372)
					(mid 136.639256 -376.525028)
					(end 136.626854 -376.566684)
				)
			)
		)
	)
	(zone
		(layers "In1.Cu" "In2.Cu")
		(hatch none 0.5)
		(connect_pads
			(clearance 0)
		)
		(min_thickness 0.25)
		(keepout
			(tracks not_allowed)
			(vias allowed)
			(pads allowed)
			(copperpour not_allowed)
			(footprints allowed)
		)
		(placement
			(enabled no)
			(sheetname "")
		)
		(fill yes
			(thermal_gap 0.5)
			(thermal_bridge_width 0.5)
			(island_removal_mode 0)
		)
		(polygon
			(pts
				(arc
					(start 431.88636 -229.63505)
					(mid 431.22596 -229.63505)
					(end 431.88636 -229.63505)
				)
			)
		)
	)
	(zone
		(layers "In1.Cu" "In2.Cu")
		(hatch none 0.5)
		(connect_pads
			(clearance 0)
		)
		(min_thickness 0.25)
		(keepout
			(tracks not_allowed)
			(vias allowed)
			(pads allowed)
			(copperpour not_allowed)
			(footprints allowed)
		)
		(placement
			(enabled no)
			(sheetname "")
		)
		(fill yes
			(thermal_gap 0.5)
			(thermal_bridge_width 0.5)
			(island_removal_mode 0)
		)
		(polygon
			(pts
				(arc
					(start 427.786292 -295.935146)
					(mid 427.125892 -295.935146)
					(end 427.786292 -295.935146)
				)
			)
		)
	)
	(zone
		(layers "In1.Cu" "In2.Cu")
		(hatch none 0.5)
		(connect_pads
			(clearance 0)
		)
		(min_thickness 0.25)
		(keepout
			(tracks not_allowed)
			(vias allowed)
			(pads allowed)
			(copperpour not_allowed)
			(footprints allowed)
		)
		(placement
			(enabled no)
			(sheetname "")
		)
		(fill yes
			(thermal_gap 0.5)
			(thermal_bridge_width 0.5)
			(island_removal_mode 0)
		)
		(polygon
			(pts
				(arc
					(start 37.126164 -292.535356)
					(mid 36.465764 -292.535356)
					(end 37.126164 -292.535356)
				)
			)
		)
	)
	(zone
		(layers "In1.Cu" "In2.Cu")
		(hatch none 0.5)
		(connect_pads
			(clearance 0)
		)
		(min_thickness 0.25)
		(keepout
			(tracks not_allowed)
			(vias allowed)
			(pads allowed)
			(copperpour not_allowed)
			(footprints allowed)
		)
		(placement
			(enabled no)
			(sheetname "")
		)
		(fill yes
			(thermal_gap 0.5)
			(thermal_bridge_width 0.5)
			(island_removal_mode 0)
		)
		(polygon
			(pts
				(arc
					(start 427.786292 -204.134974)
					(mid 427.125892 -204.134974)
					(end 427.786292 -204.134974)
				)
			)
		)
	)
	(zone
		(layers "In1.Cu" "In2.Cu")
		(hatch none 0.5)
		(connect_pads
			(clearance 0)
		)
		(min_thickness 0.25)
		(keepout
			(tracks not_allowed)
			(vias allowed)
			(pads allowed)
			(copperpour not_allowed)
			(footprints allowed)
		)
		(placement
			(enabled no)
			(sheetname "")
		)
		(fill yes
			(thermal_gap 0.5)
			(thermal_bridge_width 0.5)
			(island_removal_mode 0)
		)
		(polygon
			(pts
				(arc
					(start 399.41119 -381.824484)
					(mid 399.431114 -381.83372)
					(end 399.452846 -381.83693)
				)
				(arc
					(start 399.64741 -381.83693)
					(mid 399.701292 -381.814612)
					(end 399.72361 -381.76073)
				)
				(arc
					(start 399.72361 -381.07493)
					(mid 399.701292 -381.021048)
					(end 399.64741 -380.99873)
				)
				(arc
					(start 399.452846 -380.99873)
					(mid 399.431102 -381.001898)
					(end 399.41119 -381.011176)
				)
				(arc
					(start 399.115026 -381.203962)
					(mid 399.073342 -381.216184)
					(end 399.031714 -381.203708)
				)
				(arc
					(start 398.73809 -381.011176)
					(mid 398.718166 -381.00194)
					(end 398.696434 -380.99873)
				)
				(arc
					(start 398.50187 -380.99873)
					(mid 398.447988 -381.021048)
					(end 398.42567 -381.07493)
				)
				(arc
					(start 398.42567 -381.76073)
					(mid 398.447988 -381.814612)
					(end 398.50187 -381.83693)
				)
				(arc
					(start 398.697704 -381.83693)
					(mid 398.719448 -381.833762)
					(end 398.73936 -381.824484)
				)
				(arc
					(start 399.032984 -381.631952)
					(mid 399.07464 -381.61955)
					(end 399.116296 -381.631952)
				)
			)
		)
	)
	(zone
		(layers "In1.Cu" "In2.Cu")
		(hatch none 0.5)
		(connect_pads
			(clearance 0)
		)
		(min_thickness 0.25)
		(keepout
			(tracks not_allowed)
			(vias allowed)
			(pads allowed)
			(copperpour not_allowed)
			(footprints allowed)
		)
		(placement
			(enabled no)
			(sheetname "")
		)
		(fill yes
			(thermal_gap 0.5)
			(thermal_bridge_width 0.5)
			(island_removal_mode 0)
		)
		(polygon
			(pts
				(arc
					(start 300.15434 -276.38502)
					(mid 299.49394 -276.38502)
					(end 300.15434 -276.38502)
				)
			)
		)
	)
	(zone
		(layers "In1.Cu" "In2.Cu")
		(hatch none 0.5)
		(connect_pads
			(clearance 0)
		)
		(min_thickness 0.25)
		(keepout
			(tracks not_allowed)
			(vias allowed)
			(pads allowed)
			(copperpour not_allowed)
			(footprints allowed)
		)
		(placement
			(enabled no)
			(sheetname "")
		)
		(fill yes
			(thermal_gap 0.5)
			(thermal_bridge_width 0.5)
			(island_removal_mode 0)
		)
		(polygon
			(pts
				(arc
					(start 288.510218 -272.984976)
					(mid 287.849818 -272.984976)
					(end 288.510218 -272.984976)
				)
			)
		)
	)
	(zone
		(layers "In1.Cu" "In2.Cu")
		(hatch none 0.5)
		(connect_pads
			(clearance 0)
		)
		(min_thickness 0.25)
		(keepout
			(tracks not_allowed)
			(vias allowed)
			(pads allowed)
			(copperpour not_allowed)
			(footprints allowed)
		)
		(placement
			(enabled no)
			(sheetname "")
		)
		(fill yes
			(thermal_gap 0.5)
			(thermal_bridge_width 0.5)
			(island_removal_mode 0)
		)
		(polygon
			(pts
				(arc
					(start 285.066232 -210.085178)
					(mid 284.405832 -210.085178)
					(end 285.066232 -210.085178)
				)
			)
		)
	)
	(zone
		(layers "In1.Cu" "In2.Cu")
		(hatch none 0.5)
		(connect_pads
			(clearance 0)
		)
		(min_thickness 0.25)
		(keepout
			(tracks not_allowed)
			(vias allowed)
			(pads allowed)
			(copperpour not_allowed)
			(footprints allowed)
		)
		(placement
			(enabled no)
			(sheetname "")
		)
		(fill yes
			(thermal_gap 0.5)
			(thermal_bridge_width 0.5)
			(island_removal_mode 0)
		)
		(polygon
			(pts
				(arc
					(start 176.402238 -306.135278)
					(mid 175.741838 -306.135278)
					(end 176.402238 -306.135278)
				)
			)
		)
	)
	(zone
		(layers "In1.Cu" "In2.Cu")
		(hatch none 0.5)
		(connect_pads
			(clearance 0)
		)
		(min_thickness 0.25)
		(keepout
			(tracks not_allowed)
			(vias allowed)
			(pads allowed)
			(copperpour not_allowed)
			(footprints allowed)
		)
		(placement
			(enabled no)
			(sheetname "")
		)
		(fill yes
			(thermal_gap 0.5)
			(thermal_bridge_width 0.5)
			(island_removal_mode 0)
		)
		(polygon
			(pts
				(arc
					(start 202.478132 -297.635422)
					(mid 201.817732 -297.635422)
					(end 202.478132 -297.635422)
				)
			)
		)
	)
	(zone
		(layers "In1.Cu" "In2.Cu")
		(hatch none 0.5)
		(connect_pads
			(clearance 0)
		)
		(min_thickness 0.25)
		(keepout
			(tracks not_allowed)
			(vias allowed)
			(pads allowed)
			(copperpour not_allowed)
			(footprints allowed)
		)
		(placement
			(enabled no)
			(sheetname "")
		)
		(fill yes
			(thermal_gap 0.5)
			(thermal_bridge_width 0.5)
			(island_removal_mode 0)
		)
		(polygon
			(pts
				(arc
					(start 280.966164 -318.035178)
					(mid 280.305764 -318.035178)
					(end 280.966164 -318.035178)
				)
			)
		)
	)
	(zone
		(layers "In1.Cu" "In2.Cu")
		(hatch none 0.5)
		(connect_pads
			(clearance 0)
		)
		(min_thickness 0.25)
		(keepout
			(tracks not_allowed)
			(vias allowed)
			(pads allowed)
			(copperpour not_allowed)
			(footprints allowed)
		)
		(placement
			(enabled no)
			(sheetname "")
		)
		(fill yes
			(thermal_gap 0.5)
			(thermal_bridge_width 0.5)
			(island_removal_mode 0)
		)
		(polygon
			(pts
				(arc
					(start 273.422364 -277.235158)
					(mid 272.761964 -277.235158)
					(end 273.422364 -277.235158)
				)
			)
		)
	)
	(zone
		(layers "In1.Cu" "In2.Cu")
		(hatch none 0.5)
		(connect_pads
			(clearance 0)
		)
		(min_thickness 0.25)
		(keepout
			(tracks not_allowed)
			(vias allowed)
			(pads allowed)
			(copperpour not_allowed)
			(footprints allowed)
		)
		(placement
			(enabled no)
			(sheetname "")
		)
		(fill yes
			(thermal_gap 0.5)
			(thermal_bridge_width 0.5)
			(island_removal_mode 0)
		)
		(polygon
			(pts
				(arc
					(start 199.0344 -238.985298)
					(mid 198.374 -238.985298)
					(end 199.0344 -238.985298)
				)
			)
		)
	)
	(zone
		(layers "In1.Cu" "In2.Cu")
		(hatch none 0.5)
		(connect_pads
			(clearance 0)
		)
		(min_thickness 0.25)
		(keepout
			(tracks not_allowed)
			(vias allowed)
			(pads allowed)
			(copperpour not_allowed)
			(footprints allowed)
		)
		(placement
			(enabled no)
			(sheetname "")
		)
		(fill yes
			(thermal_gap 0.5)
			(thermal_bridge_width 0.5)
			(island_removal_mode 0)
		)
		(polygon
			(pts
				(arc
					(start 300.15434 -298.485052)
					(mid 299.49394 -298.485052)
					(end 300.15434 -298.485052)
				)
			)
		)
	)
	(zone
		(layers "In1.Cu" "In2.Cu")
		(hatch none 0.5)
		(connect_pads
			(clearance 0)
		)
		(min_thickness 0.25)
		(keepout
			(tracks not_allowed)
			(vias allowed)
			(pads allowed)
			(copperpour not_allowed)
			(footprints allowed)
		)
		(placement
			(enabled no)
			(sheetname "")
		)
		(fill yes
			(thermal_gap 0.5)
			(thermal_bridge_width 0.5)
			(island_removal_mode 0)
		)
		(polygon
			(pts
				(arc
					(start 454.518268 -261.085076)
					(mid 453.857868 -261.085076)
					(end 454.518268 -261.085076)
				)
			)
		)
	)
	(zone
		(layers "In1.Cu" "In2.Cu")
		(hatch none 0.5)
		(connect_pads
			(clearance 0)
		)
		(min_thickness 0.25)
		(keepout
			(tracks not_allowed)
			(vias allowed)
			(pads allowed)
			(copperpour not_allowed)
			(footprints allowed)
		)
		(placement
			(enabled no)
			(sheetname "")
		)
		(fill yes
			(thermal_gap 0.5)
			(thermal_bridge_width 0.5)
			(island_removal_mode 0)
		)
		(polygon
			(pts
				(arc
					(start 183.946292 -231.335326)
					(mid 183.285892 -231.335326)
					(end 183.946292 -231.335326)
				)
			)
		)
	)
	(zone
		(layers "In1.Cu" "In2.Cu")
		(hatch none 0.5)
		(connect_pads
			(clearance 0)
		)
		(min_thickness 0.25)
		(keepout
			(tracks not_allowed)
			(vias allowed)
			(pads allowed)
			(copperpour not_allowed)
			(footprints allowed)
		)
		(placement
			(enabled no)
			(sheetname "")
		)
		(fill yes
			(thermal_gap 0.5)
			(thermal_bridge_width 0.5)
			(island_removal_mode 0)
		)
		(polygon
			(pts
				(arc
					(start 273.422364 -243.234972)
					(mid 272.761964 -243.234972)
					(end 273.422364 -243.234972)
				)
			)
		)
	)
	(zone
		(layers "In1.Cu" "In2.Cu")
		(hatch none 0.5)
		(connect_pads
			(clearance 0)
		)
		(min_thickness 0.25)
		(keepout
			(tracks not_allowed)
			(vias allowed)
			(pads allowed)
			(copperpour not_allowed)
			(footprints allowed)
		)
		(placement
			(enabled no)
			(sheetname "")
		)
		(fill yes
			(thermal_gap 0.5)
			(thermal_bridge_width 0.5)
			(island_removal_mode 0)
		)
		(polygon
			(pts
				(arc
					(start 150.218394 -373.442484)
					(mid 150.238318 -373.45172)
					(end 150.26005 -373.45493)
				)
				(arc
					(start 150.454614 -373.45493)
					(mid 150.508496 -373.432612)
					(end 150.530814 -373.37873)
				)
				(arc
					(start 150.530814 -372.69293)
					(mid 150.508496 -372.639048)
					(end 150.454614 -372.61673)
				)
				(arc
					(start 150.26005 -372.61673)
					(mid 150.238306 -372.619898)
					(end 150.218394 -372.629176)
				)
				(arc
					(start 149.92223 -372.821962)
					(mid 149.880546 -372.834184)
					(end 149.838918 -372.821708)
				)
				(arc
					(start 149.545294 -372.629176)
					(mid 149.52537 -372.61994)
					(end 149.503638 -372.61673)
				)
				(arc
					(start 149.309074 -372.61673)
					(mid 149.255192 -372.639048)
					(end 149.232874 -372.69293)
				)
				(arc
					(start 149.232874 -373.37873)
					(mid 149.255192 -373.432612)
					(end 149.309074 -373.45493)
				)
				(arc
					(start 149.504908 -373.45493)
					(mid 149.526652 -373.451762)
					(end 149.546564 -373.442484)
				)
				(arc
					(start 149.840188 -373.249952)
					(mid 149.881844 -373.23755)
					(end 149.9235 -373.249952)
				)
			)
		)
	)
	(zone
		(layers "In1.Cu" "In2.Cu")
		(hatch none 0.5)
		(connect_pads
			(clearance 0)
		)
		(min_thickness 0.25)
		(keepout
			(tracks not_allowed)
			(vias allowed)
			(pads allowed)
			(copperpour not_allowed)
			(footprints allowed)
		)
		(placement
			(enabled no)
			(sheetname "")
		)
		(fill yes
			(thermal_gap 0.5)
			(thermal_bridge_width 0.5)
			(island_removal_mode 0)
		)
		(polygon
			(pts
				(arc
					(start 191.490346 -273.835368)
					(mid 190.829946 -273.835368)
					(end 191.490346 -273.835368)
				)
			)
		)
	)
	(zone
		(layers "In1.Cu" "In2.Cu")
		(hatch none 0.5)
		(connect_pads
			(clearance 0)
		)
		(min_thickness 0.25)
		(keepout
			(tracks not_allowed)
			(vias allowed)
			(pads allowed)
			(copperpour not_allowed)
			(footprints allowed)
		)
		(placement
			(enabled no)
			(sheetname "")
		)
		(fill yes
			(thermal_gap 0.5)
			(thermal_bridge_width 0.5)
			(island_removal_mode 0)
		)
		(polygon
			(pts
				(arc
					(start 179.846224 -230.485442)
					(mid 179.185824 -230.485442)
					(end 179.846224 -230.485442)
				)
			)
		)
	)
	(zone
		(layers "In1.Cu" "In2.Cu")
		(hatch none 0.5)
		(connect_pads
			(clearance 0)
		)
		(min_thickness 0.25)
		(keepout
			(tracks not_allowed)
			(vias allowed)
			(pads allowed)
			(copperpour not_allowed)
			(footprints allowed)
		)
		(placement
			(enabled no)
			(sheetname "")
		)
		(fill yes
			(thermal_gap 0.5)
			(thermal_bridge_width 0.5)
			(island_removal_mode 0)
		)
		(polygon
			(pts
				(arc
					(start 33.026096 -261.935214)
					(mid 32.365696 -261.935214)
					(end 33.026096 -261.935214)
				)
			)
		)
	)
	(zone
		(layers "In1.Cu" "In2.Cu")
		(hatch none 0.5)
		(connect_pads
			(clearance 0)
		)
		(min_thickness 0.25)
		(keepout
			(tracks not_allowed)
			(vias allowed)
			(pads allowed)
			(copperpour not_allowed)
			(footprints allowed)
		)
		(placement
			(enabled no)
			(sheetname "")
		)
		(fill yes
			(thermal_gap 0.5)
			(thermal_bridge_width 0.5)
			(island_removal_mode 0)
		)
		(polygon
			(pts
				(arc
					(start 439.430414 -221.985078)
					(mid 438.770014 -221.985078)
					(end 439.430414 -221.985078)
				)
			)
		)
	)
	(zone
		(layers "In1.Cu" "In2.Cu")
		(hatch none 0.5)
		(connect_pads
			(clearance 0)
		)
		(min_thickness 0.25)
		(keepout
			(tracks not_allowed)
			(vias allowed)
			(pads allowed)
			(copperpour not_allowed)
			(footprints allowed)
		)
		(placement
			(enabled no)
			(sheetname "")
		)
		(fill yes
			(thermal_gap 0.5)
			(thermal_bridge_width 0.5)
			(island_removal_mode 0)
		)
		(polygon
			(pts
				(arc
					(start 83.118452 -373.442484)
					(mid 83.138376 -373.45172)
					(end 83.160108 -373.45493)
				)
				(arc
					(start 83.354672 -373.45493)
					(mid 83.408554 -373.432612)
					(end 83.430872 -373.37873)
				)
				(arc
					(start 83.430872 -372.69293)
					(mid 83.408554 -372.639048)
					(end 83.354672 -372.61673)
				)
				(arc
					(start 83.160108 -372.61673)
					(mid 83.138364 -372.619898)
					(end 83.118452 -372.629176)
				)
				(arc
					(start 82.822288 -372.821962)
					(mid 82.780604 -372.834184)
					(end 82.738976 -372.821708)
				)
				(arc
					(start 82.445352 -372.629176)
					(mid 82.425428 -372.61994)
					(end 82.403696 -372.61673)
				)
				(arc
					(start 82.209132 -372.61673)
					(mid 82.15525 -372.639048)
					(end 82.132932 -372.69293)
				)
				(arc
					(start 82.132932 -373.37873)
					(mid 82.15525 -373.432612)
					(end 82.209132 -373.45493)
				)
				(arc
					(start 82.404966 -373.45493)
					(mid 82.42671 -373.451762)
					(end 82.446622 -373.442484)
				)
				(arc
					(start 82.740246 -373.249952)
					(mid 82.781902 -373.23755)
					(end 82.823558 -373.249952)
				)
			)
		)
	)
	(zone
		(layers "In1.Cu" "In2.Cu")
		(hatch none 0.5)
		(connect_pads
			(clearance 0)
		)
		(min_thickness 0.25)
		(keepout
			(tracks not_allowed)
			(vias allowed)
			(pads allowed)
			(copperpour not_allowed)
			(footprints allowed)
		)
		(placement
			(enabled no)
			(sheetname "")
		)
		(fill yes
			(thermal_gap 0.5)
			(thermal_bridge_width 0.5)
			(island_removal_mode 0)
		)
		(polygon
			(pts
				(arc
					(start 29.582364 -219.435426)
					(mid 28.921964 -219.435426)
					(end 29.582364 -219.435426)
				)
			)
		)
	)
	(zone
		(layers "In1.Cu" "In2.Cu")
		(hatch none 0.5)
		(connect_pads
			(clearance 0)
		)
		(min_thickness 0.25)
		(keepout
			(tracks not_allowed)
			(vias allowed)
			(pads allowed)
			(copperpour not_allowed)
			(footprints allowed)
		)
		(placement
			(enabled no)
			(sheetname "")
		)
		(fill yes
			(thermal_gap 0.5)
			(thermal_bridge_width 0.5)
			(island_removal_mode 0)
		)
		(polygon
			(pts
				(arc
					(start 187.390278 -284.035246)
					(mid 186.729878 -284.035246)
					(end 187.390278 -284.035246)
				)
			)
		)
	)
	(zone
		(layers "In1.Cu" "In2.Cu")
		(hatch none 0.5)
		(connect_pads
			(clearance 0)
		)
		(min_thickness 0.25)
		(keepout
			(tracks not_allowed)
			(vias allowed)
			(pads allowed)
			(copperpour not_allowed)
			(footprints allowed)
		)
		(placement
			(enabled no)
			(sheetname "")
		)
		(fill yes
			(thermal_gap 0.5)
			(thermal_bridge_width 0.5)
			(island_removal_mode 0)
		)
		(polygon
			(pts
				(arc
					(start 53.703474 -408.860244)
					(mid 53.725792 -408.914126)
					(end 53.779674 -408.936444)
				)
				(arc
					(start 53.975254 -408.936444)
					(mid 53.99713 -408.933312)
					(end 54.017164 -408.923998)
				)
				(arc
					(start 54.310788 -408.731466)
					(mid 54.352444 -408.719064)
					(end 54.3941 -408.731466)
				)
				(arc
					(start 54.688994 -408.923998)
					(mid 54.708918 -408.933234)
					(end 54.73065 -408.936444)
				)
				(arc
					(start 54.925214 -408.936444)
					(mid 54.979096 -408.914126)
					(end 55.001414 -408.860244)
				)
				(arc
					(start 55.001414 -408.174444)
					(mid 54.979096 -408.120562)
					(end 54.925214 -408.098244)
				)
				(arc
					(start 54.73065 -408.098244)
					(mid 54.708906 -408.101412)
					(end 54.688994 -408.11069)
				)
				(arc
					(start 54.39283 -408.303476)
					(mid 54.351146 -408.315698)
					(end 54.309518 -408.303222)
				)
				(arc
					(start 54.015894 -408.11069)
					(mid 53.99597 -408.101454)
					(end 53.974238 -408.098244)
				)
				(arc
					(start 53.779674 -408.098244)
					(mid 53.725792 -408.120562)
					(end 53.703474 -408.174444)
				)
			)
		)
	)
	(zone
		(layers "In1.Cu" "In2.Cu")
		(hatch none 0.5)
		(connect_pads
			(clearance 0)
		)
		(min_thickness 0.25)
		(keepout
			(tracks not_allowed)
			(vias allowed)
			(pads allowed)
			(copperpour not_allowed)
			(footprints allowed)
		)
		(placement
			(enabled no)
			(sheetname "")
		)
		(fill yes
			(thermal_gap 0.5)
			(thermal_bridge_width 0.5)
			(island_removal_mode 0)
		)
		(polygon
			(pts
				(arc
					(start 25.482296 -299.335444)
					(mid 24.821896 -299.335444)
					(end 25.482296 -299.335444)
				)
			)
		)
	)
	(zone
		(layers "In1.Cu" "In2.Cu")
		(hatch none 0.5)
		(connect_pads
			(clearance 0)
		)
		(min_thickness 0.25)
		(keepout
			(tracks not_allowed)
			(vias allowed)
			(pads allowed)
			(copperpour not_allowed)
			(footprints allowed)
		)
		(placement
			(enabled no)
			(sheetname "")
		)
		(fill yes
			(thermal_gap 0.5)
			(thermal_bridge_width 0.5)
			(island_removal_mode 0)
		)
		(polygon
			(pts
				(arc
					(start 202.478132 -226.23526)
					(mid 201.817732 -226.23526)
					(end 202.478132 -226.23526)
				)
			)
		)
	)
	(zone
		(layers "In1.Cu" "In2.Cu")
		(hatch none 0.5)
		(connect_pads
			(clearance 0)
		)
		(min_thickness 0.25)
		(keepout
			(tracks not_allowed)
			(vias allowed)
			(pads allowed)
			(copperpour not_allowed)
			(footprints allowed)
		)
		(placement
			(enabled no)
			(sheetname "")
		)
		(fill yes
			(thermal_gap 0.5)
			(thermal_bridge_width 0.5)
			(island_removal_mode 0)
		)
		(polygon
			(pts
				(arc
					(start 187.390278 -289.98545)
					(mid 186.729878 -289.98545)
					(end 187.390278 -289.98545)
				)
			)
		)
	)
	(zone
		(layers "In1.Cu" "In2.Cu")
		(hatch none 0.5)
		(connect_pads
			(clearance 0)
		)
		(min_thickness 0.25)
		(keepout
			(tracks not_allowed)
			(vias allowed)
			(pads allowed)
			(copperpour not_allowed)
			(footprints allowed)
		)
		(placement
			(enabled no)
			(sheetname "")
		)
		(fill yes
			(thermal_gap 0.5)
			(thermal_bridge_width 0.5)
			(island_removal_mode 0)
		)
		(polygon
			(pts
				(arc
					(start 179.846224 -288.285428)
					(mid 179.185824 -288.285428)
					(end 179.846224 -288.285428)
				)
			)
		)
	)
	(zone
		(layers "In1.Cu" "In2.Cu")
		(hatch none 0.5)
		(connect_pads
			(clearance 0)
		)
		(min_thickness 0.25)
		(keepout
			(tracks not_allowed)
			(vias allowed)
			(pads allowed)
			(copperpour not_allowed)
			(footprints allowed)
		)
		(placement
			(enabled no)
			(sheetname "")
		)
		(fill yes
			(thermal_gap 0.5)
			(thermal_bridge_width 0.5)
			(island_removal_mode 0)
		)
		(polygon
			(pts
				(arc
					(start 442.8744 -237.285022)
					(mid 442.214 -237.285022)
					(end 442.8744 -237.285022)
				)
			)
		)
	)
	(zone
		(layers "In1.Cu" "In2.Cu")
		(hatch none 0.5)
		(connect_pads
			(clearance 0)
		)
		(min_thickness 0.25)
		(keepout
			(tracks not_allowed)
			(vias allowed)
			(pads allowed)
			(copperpour not_allowed)
			(footprints allowed)
		)
		(placement
			(enabled no)
			(sheetname "")
		)
		(fill yes
			(thermal_gap 0.5)
			(thermal_bridge_width 0.5)
			(island_removal_mode 0)
		)
		(polygon
			(pts
				(arc
					(start 48.114204 -230.485442)
					(mid 47.453804 -230.485442)
					(end 48.114204 -230.485442)
				)
			)
		)
	)
	(zone
		(layers "In1.Cu" "In2.Cu")
		(hatch none 0.5)
		(connect_pads
			(clearance 0)
		)
		(min_thickness 0.25)
		(keepout
			(tracks not_allowed)
			(vias allowed)
			(pads allowed)
			(copperpour not_allowed)
			(footprints allowed)
		)
		(placement
			(enabled no)
			(sheetname "")
		)
		(fill yes
			(thermal_gap 0.5)
			(thermal_bridge_width 0.5)
			(island_removal_mode 0)
		)
		(polygon
			(pts
				(arc
					(start 450.4182 -301.034958)
					(mid 449.7578 -301.034958)
					(end 450.4182 -301.034958)
				)
			)
		)
	)
	(zone
		(layers "In1.Cu" "In2.Cu")
		(hatch none 0.5)
		(connect_pads
			(clearance 0)
		)
		(min_thickness 0.25)
		(keepout
			(tracks not_allowed)
			(vias allowed)
			(pads allowed)
			(copperpour not_allowed)
			(footprints allowed)
		)
		(placement
			(enabled no)
			(sheetname "")
		)
		(fill yes
			(thermal_gap 0.5)
			(thermal_bridge_width 0.5)
			(island_removal_mode 0)
		)
		(polygon
			(pts
				(arc
					(start 25.482296 -221.135194)
					(mid 24.821896 -221.135194)
					(end 25.482296 -221.135194)
				)
			)
		)
	)
	(zone
		(layers "In1.Cu" "In2.Cu")
		(hatch none 0.5)
		(connect_pads
			(clearance 0)
		)
		(min_thickness 0.25)
		(keepout
			(tracks not_allowed)
			(vias allowed)
			(pads allowed)
			(copperpour not_allowed)
			(footprints allowed)
		)
		(placement
			(enabled no)
			(sheetname "")
		)
		(fill yes
			(thermal_gap 0.5)
			(thermal_bridge_width 0.5)
			(island_removal_mode 0)
		)
		(polygon
			(pts
				(arc
					(start 191.490346 -254.285242)
					(mid 190.829946 -254.285242)
					(end 191.490346 -254.285242)
				)
			)
		)
	)
	(zone
		(layers "In1.Cu" "In2.Cu")
		(hatch none 0.5)
		(connect_pads
			(clearance 0)
		)
		(min_thickness 0.25)
		(keepout
			(tracks not_allowed)
			(vias allowed)
			(pads allowed)
			(copperpour not_allowed)
			(footprints allowed)
		)
		(placement
			(enabled no)
			(sheetname "")
		)
		(fill yes
			(thermal_gap 0.5)
			(thermal_bridge_width 0.5)
			(island_removal_mode 0)
		)
		(polygon
			(pts
				(arc
					(start 44.670218 -267.885418)
					(mid 44.009818 -267.885418)
					(end 44.670218 -267.885418)
				)
			)
		)
	)
	(zone
		(layers "In1.Cu" "In2.Cu")
		(hatch none 0.5)
		(connect_pads
			(clearance 0)
		)
		(min_thickness 0.25)
		(keepout
			(tracks not_allowed)
			(vias allowed)
			(pads allowed)
			(copperpour not_allowed)
			(footprints allowed)
		)
		(placement
			(enabled no)
			(sheetname "")
		)
		(fill yes
			(thermal_gap 0.5)
			(thermal_bridge_width 0.5)
			(island_removal_mode 0)
		)
		(polygon
			(pts
				(arc
					(start 40.57015 -233.885232)
					(mid 39.90975 -233.885232)
					(end 40.57015 -233.885232)
				)
			)
		)
	)
	(zone
		(layers "In1.Cu" "In2.Cu")
		(hatch none 0.5)
		(connect_pads
			(clearance 0)
		)
		(min_thickness 0.25)
		(keepout
			(tracks not_allowed)
			(vias allowed)
			(pads allowed)
			(copperpour not_allowed)
			(footprints allowed)
		)
		(placement
			(enabled no)
			(sheetname "")
		)
		(fill yes
			(thermal_gap 0.5)
			(thermal_bridge_width 0.5)
			(island_removal_mode 0)
		)
		(polygon
			(pts
				(arc
					(start 33.026096 -237.285276)
					(mid 32.365696 -237.285276)
					(end 33.026096 -237.285276)
				)
			)
		)
	)
	(zone
		(layers "In1.Cu" "In2.Cu")
		(hatch none 0.5)
		(connect_pads
			(clearance 0)
		)
		(min_thickness 0.25)
		(keepout
			(tracks not_allowed)
			(vias allowed)
			(pads allowed)
			(copperpour not_allowed)
			(footprints allowed)
		)
		(placement
			(enabled no)
			(sheetname "")
		)
		(fill yes
			(thermal_gap 0.5)
			(thermal_bridge_width 0.5)
			(island_removal_mode 0)
		)
		(polygon
			(pts
				(arc
					(start 269.978378 -200.735184)
					(mid 269.317978 -200.735184)
					(end 269.978378 -200.735184)
				)
			)
		)
	)
	(zone
		(layers "In1.Cu" "In2.Cu")
		(hatch none 0.5)
		(connect_pads
			(clearance 0)
		)
		(min_thickness 0.25)
		(keepout
			(tracks not_allowed)
			(vias allowed)
			(pads allowed)
			(copperpour not_allowed)
			(footprints allowed)
		)
		(placement
			(enabled no)
			(sheetname "")
		)
		(fill yes
			(thermal_gap 0.5)
			(thermal_bridge_width 0.5)
			(island_removal_mode 0)
		)
		(polygon
			(pts
				(arc
					(start 427.786292 -268.735048)
					(mid 427.125892 -268.735048)
					(end 427.786292 -268.735048)
				)
			)
		)
	)
	(zone
		(layers "In1.Cu" "In2.Cu")
		(hatch none 0.5)
		(connect_pads
			(clearance 0)
		)
		(min_thickness 0.25)
		(keepout
			(tracks not_allowed)
			(vias allowed)
			(pads allowed)
			(copperpour not_allowed)
			(footprints allowed)
		)
		(placement
			(enabled no)
			(sheetname "")
		)
		(fill yes
			(thermal_gap 0.5)
			(thermal_bridge_width 0.5)
			(island_removal_mode 0)
		)
		(polygon
			(pts
				(arc
					(start 280.966164 -289.985196)
					(mid 280.305764 -289.985196)
					(end 280.966164 -289.985196)
				)
			)
		)
	)
	(zone
		(layers "In1.Cu" "In2.Cu")
		(hatch none 0.5)
		(connect_pads
			(clearance 0)
		)
		(min_thickness 0.25)
		(keepout
			(tracks not_allowed)
			(vias allowed)
			(pads allowed)
			(copperpour not_allowed)
			(footprints allowed)
		)
		(placement
			(enabled no)
			(sheetname "")
		)
		(fill yes
			(thermal_gap 0.5)
			(thermal_bridge_width 0.5)
			(island_removal_mode 0)
		)
		(polygon
			(pts
				(arc
					(start 37.126164 -296.785284)
					(mid 36.465764 -296.785284)
					(end 37.126164 -296.785284)
				)
			)
		)
	)
	(zone
		(layers "In1.Cu" "In2.Cu")
		(hatch none 0.5)
		(connect_pads
			(clearance 0)
		)
		(min_thickness 0.25)
		(keepout
			(tracks not_allowed)
			(vias allowed)
			(pads allowed)
			(copperpour not_allowed)
			(footprints allowed)
		)
		(placement
			(enabled no)
			(sheetname "")
		)
		(fill yes
			(thermal_gap 0.5)
			(thermal_bridge_width 0.5)
			(island_removal_mode 0)
		)
		(polygon
			(pts
				(arc
					(start 296.054272 -308.685184)
					(mid 295.393872 -308.685184)
					(end 296.054272 -308.685184)
				)
			)
		)
	)
	(zone
		(layers "In1.Cu" "In2.Cu")
		(hatch none 0.5)
		(connect_pads
			(clearance 0)
		)
		(min_thickness 0.25)
		(keepout
			(tracks not_allowed)
			(vias allowed)
			(pads allowed)
			(copperpour not_allowed)
			(footprints allowed)
		)
		(placement
			(enabled no)
			(sheetname "")
		)
		(fill yes
			(thermal_gap 0.5)
			(thermal_bridge_width 0.5)
			(island_removal_mode 0)
		)
		(polygon
			(pts
				(arc
					(start 22.03831 -303.585372)
					(mid 21.37791 -303.585372)
					(end 22.03831 -303.585372)
				)
			)
		)
	)
	(zone
		(layers "In1.Cu" "In2.Cu")
		(hatch none 0.5)
		(connect_pads
			(clearance 0)
		)
		(min_thickness 0.25)
		(keepout
			(tracks not_allowed)
			(vias allowed)
			(pads allowed)
			(copperpour not_allowed)
			(footprints allowed)
		)
		(placement
			(enabled no)
			(sheetname "")
		)
		(fill yes
			(thermal_gap 0.5)
			(thermal_bridge_width 0.5)
			(island_removal_mode 0)
		)
		(polygon
			(pts
				(arc
					(start 439.430414 -236.435138)
					(mid 438.770014 -236.435138)
					(end 439.430414 -236.435138)
				)
			)
		)
	)
	(zone
		(layers "In1.Cu" "In2.Cu")
		(hatch none 0.5)
		(connect_pads
			(clearance 0)
		)
		(min_thickness 0.25)
		(keepout
			(tracks not_allowed)
			(vias allowed)
			(pads allowed)
			(copperpour not_allowed)
			(footprints allowed)
		)
		(placement
			(enabled no)
			(sheetname "")
		)
		(fill yes
			(thermal_gap 0.5)
			(thermal_bridge_width 0.5)
			(island_removal_mode 0)
		)
		(polygon
			(pts
				(arc
					(start 277.522432 -250.884944)
					(mid 276.862032 -250.884944)
					(end 277.522432 -250.884944)
				)
			)
		)
	)
	(zone
		(layers "In1.Cu" "In2.Cu")
		(hatch none 0.5)
		(connect_pads
			(clearance 0)
		)
		(min_thickness 0.25)
		(keepout
			(tracks not_allowed)
			(vias allowed)
			(pads allowed)
			(copperpour not_allowed)
			(footprints allowed)
		)
		(placement
			(enabled no)
			(sheetname "")
		)
		(fill yes
			(thermal_gap 0.5)
			(thermal_bridge_width 0.5)
			(island_removal_mode 0)
		)
		(polygon
			(pts
				(arc
					(start 285.066232 -210.935062)
					(mid 284.405832 -210.935062)
					(end 285.066232 -210.935062)
				)
			)
		)
	)
	(zone
		(layers "In1.Cu" "In2.Cu")
		(hatch none 0.5)
		(connect_pads
			(clearance 0)
		)
		(min_thickness 0.25)
		(keepout
			(tracks not_allowed)
			(vias allowed)
			(pads allowed)
			(copperpour not_allowed)
			(footprints allowed)
		)
		(placement
			(enabled no)
			(sheetname "")
		)
		(fill yes
			(thermal_gap 0.5)
			(thermal_bridge_width 0.5)
			(island_removal_mode 0)
		)
		(polygon
			(pts
				(arc
					(start 172.30217 -314.635388)
					(mid 171.64177 -314.635388)
					(end 172.30217 -314.635388)
				)
			)
		)
	)
	(zone
		(layers "In1.Cu" "In2.Cu")
		(hatch none 0.5)
		(connect_pads
			(clearance 0)
		)
		(min_thickness 0.25)
		(keepout
			(tracks not_allowed)
			(vias allowed)
			(pads allowed)
			(copperpour not_allowed)
			(footprints allowed)
		)
		(placement
			(enabled no)
			(sheetname "")
		)
		(fill yes
			(thermal_gap 0.5)
			(thermal_bridge_width 0.5)
			(island_removal_mode 0)
		)
		(polygon
			(pts
				(arc
					(start 37.126164 -204.985366)
					(mid 36.465764 -204.985366)
					(end 37.126164 -204.985366)
				)
			)
		)
	)
	(zone
		(layers "In1.Cu" "In2.Cu")
		(hatch none 0.5)
		(connect_pads
			(clearance 0)
		)
		(min_thickness 0.25)
		(keepout
			(tracks not_allowed)
			(vias allowed)
			(pads allowed)
			(copperpour not_allowed)
			(footprints allowed)
		)
		(placement
			(enabled no)
			(sheetname "")
		)
		(fill yes
			(thermal_gap 0.5)
			(thermal_bridge_width 0.5)
			(island_removal_mode 0)
		)
		(polygon
			(pts
				(arc
					(start 183.946292 -275.53539)
					(mid 183.285892 -275.53539)
					(end 183.946292 -275.53539)
				)
			)
		)
	)
	(zone
		(layers "In1.Cu" "In2.Cu")
		(hatch none 0.5)
		(connect_pads
			(clearance 0)
		)
		(min_thickness 0.25)
		(keepout
			(tracks not_allowed)
			(vias allowed)
			(pads allowed)
			(copperpour not_allowed)
			(footprints allowed)
		)
		(placement
			(enabled no)
			(sheetname "")
		)
		(fill yes
			(thermal_gap 0.5)
			(thermal_bridge_width 0.5)
			(island_removal_mode 0)
		)
		(polygon
			(pts
				(arc
					(start 25.482296 -261.935214)
					(mid 24.821896 -261.935214)
					(end 25.482296 -261.935214)
				)
			)
		)
	)
	(zone
		(layers "In1.Cu" "In2.Cu")
		(hatch none 0.5)
		(connect_pads
			(clearance 0)
		)
		(min_thickness 0.25)
		(keepout
			(tracks not_allowed)
			(vias allowed)
			(pads allowed)
			(copperpour not_allowed)
			(footprints allowed)
		)
		(placement
			(enabled no)
			(sheetname "")
		)
		(fill yes
			(thermal_gap 0.5)
			(thermal_bridge_width 0.5)
			(island_removal_mode 0)
		)
		(polygon
			(pts
				(arc
					(start 199.0344 -234.73537)
					(mid 198.374 -234.73537)
					(end 199.0344 -234.73537)
				)
			)
		)
	)
	(zone
		(layers "In1.Cu" "In2.Cu")
		(hatch none 0.5)
		(connect_pads
			(clearance 0)
		)
		(min_thickness 0.25)
		(keepout
			(tracks not_allowed)
			(vias allowed)
			(pads allowed)
			(copperpour not_allowed)
			(footprints allowed)
		)
		(placement
			(enabled no)
			(sheetname "")
		)
		(fill yes
			(thermal_gap 0.5)
			(thermal_bridge_width 0.5)
			(island_removal_mode 0)
		)
		(polygon
			(pts
				(arc
					(start 420.242238 -221.13494)
					(mid 419.581838 -221.13494)
					(end 420.242238 -221.13494)
				)
			)
		)
	)
	(zone
		(layers "In1.Cu" "In2.Cu")
		(hatch none 0.5)
		(connect_pads
			(clearance 0)
		)
		(min_thickness 0.25)
		(keepout
			(tracks not_allowed)
			(vias allowed)
			(pads allowed)
			(copperpour not_allowed)
			(footprints allowed)
		)
		(placement
			(enabled no)
			(sheetname "")
		)
		(fill yes
			(thermal_gap 0.5)
			(thermal_bridge_width 0.5)
			(island_removal_mode 0)
		)
		(polygon
			(pts
				(arc
					(start 179.846224 -310.385206)
					(mid 179.185824 -310.385206)
					(end 179.846224 -310.385206)
				)
			)
		)
	)
	(zone
		(layers "In1.Cu" "In2.Cu")
		(hatch none 0.5)
		(connect_pads
			(clearance 0)
		)
		(min_thickness 0.25)
		(keepout
			(tracks not_allowed)
			(vias allowed)
			(pads allowed)
			(copperpour not_allowed)
			(footprints allowed)
		)
		(placement
			(enabled no)
			(sheetname "")
		)
		(fill yes
			(thermal_gap 0.5)
			(thermal_bridge_width 0.5)
			(island_removal_mode 0)
		)
		(polygon
			(pts
				(arc
					(start 420.242238 -295.935146)
					(mid 419.581838 -295.935146)
					(end 420.242238 -295.935146)
				)
			)
		)
	)
	(zone
		(layers "In1.Cu" "In2.Cu")
		(hatch none 0.5)
		(connect_pads
			(clearance 0)
		)
		(min_thickness 0.25)
		(keepout
			(tracks not_allowed)
			(vias allowed)
			(pads allowed)
			(copperpour not_allowed)
			(footprints allowed)
		)
		(placement
			(enabled no)
			(sheetname "")
		)
		(fill yes
			(thermal_gap 0.5)
			(thermal_bridge_width 0.5)
			(island_removal_mode 0)
		)
		(polygon
			(pts
				(arc
					(start 44.162472 -7.672324)
					(mid 44.18479 -7.618442)
					(end 44.238672 -7.596124)
				)
				(arc
					(start 45.275246 -7.596124)
					(mid 45.329128 -7.618442)
					(end 45.351446 -7.672324)
				)
				(arc
					(start 45.351446 -9.071864)
					(mid 45.329128 -9.125746)
					(end 45.275246 -9.148064)
				)
				(arc
					(start 44.238672 -9.148064)
					(mid 44.18479 -9.125746)
					(end 44.162472 -9.071864)
				)
			)
		)
	)
	(zone
		(layers "In1.Cu" "In2.Cu")
		(hatch none 0.5)
		(connect_pads
			(clearance 0)
		)
		(min_thickness 0.25)
		(keepout
			(tracks not_allowed)
			(vias allowed)
			(pads allowed)
			(copperpour not_allowed)
			(footprints allowed)
		)
		(placement
			(enabled no)
			(sheetname "")
		)
		(fill yes
			(thermal_gap 0.5)
			(thermal_bridge_width 0.5)
			(island_removal_mode 0)
		)
		(polygon
			(pts
				(arc
					(start 273.422364 -286.585152)
					(mid 272.761964 -286.585152)
					(end 273.422364 -286.585152)
				)
			)
		)
	)
	(zone
		(layers "In1.Cu" "In2.Cu")
		(hatch none 0.5)
		(connect_pads
			(clearance 0)
		)
		(min_thickness 0.25)
		(keepout
			(tracks not_allowed)
			(vias allowed)
			(pads allowed)
			(copperpour not_allowed)
			(footprints allowed)
		)
		(placement
			(enabled no)
			(sheetname "")
		)
		(fill yes
			(thermal_gap 0.5)
			(thermal_bridge_width 0.5)
			(island_removal_mode 0)
		)
		(polygon
			(pts
				(arc
					(start 51.161696 -11.91768)
					(mid 51.139378 -11.971562)
					(end 51.085496 -11.99388)
				)
				(arc
					(start 50.048922 -11.99388)
					(mid 49.99504 -11.971562)
					(end 49.972722 -11.91768)
				)
				(arc
					(start 49.972722 -10.51814)
					(mid 49.99504 -10.464258)
					(end 50.048922 -10.44194)
				)
				(arc
					(start 51.085496 -10.44194)
					(mid 51.139378 -10.464258)
					(end 51.161696 -10.51814)
				)
			)
		)
	)
	(zone
		(layers "In1.Cu" "In2.Cu")
		(hatch none 0.5)
		(connect_pads
			(clearance 0)
		)
		(min_thickness 0.25)
		(keepout
			(tracks not_allowed)
			(vias allowed)
			(pads allowed)
			(copperpour not_allowed)
			(footprints allowed)
		)
		(placement
			(enabled no)
			(sheetname "")
		)
		(fill yes
			(thermal_gap 0.5)
			(thermal_bridge_width 0.5)
			(island_removal_mode 0)
		)
		(polygon
			(pts
				(arc
					(start 48.114204 -288.285428)
					(mid 47.453804 -288.285428)
					(end 48.114204 -288.285428)
				)
			)
		)
	)
	(zone
		(layers "In1.Cu" "In2.Cu")
		(hatch none 0.5)
		(connect_pads
			(clearance 0)
		)
		(min_thickness 0.25)
		(keepout
			(tracks not_allowed)
			(vias allowed)
			(pads allowed)
			(copperpour not_allowed)
			(footprints allowed)
		)
		(placement
			(enabled no)
			(sheetname "")
		)
		(fill yes
			(thermal_gap 0.5)
			(thermal_bridge_width 0.5)
			(island_removal_mode 0)
		)
		(polygon
			(pts
				(arc
					(start 273.422364 -207.535018)
					(mid 272.761964 -207.535018)
					(end 273.422364 -207.535018)
				)
			)
		)
	)
	(zone
		(layers "In1.Cu" "In2.Cu")
		(hatch none 0.5)
		(connect_pads
			(clearance 0)
		)
		(min_thickness 0.25)
		(keepout
			(tracks not_allowed)
			(vias allowed)
			(pads allowed)
			(copperpour not_allowed)
			(footprints allowed)
		)
		(placement
			(enabled no)
			(sheetname "")
		)
		(fill yes
			(thermal_gap 0.5)
			(thermal_bridge_width 0.5)
			(island_removal_mode 0)
		)
		(polygon
			(pts
				(arc
					(start 29.582364 -300.185328)
					(mid 28.921964 -300.185328)
					(end 29.582364 -300.185328)
				)
			)
		)
	)
	(zone
		(layers "In1.Cu" "In2.Cu")
		(hatch none 0.5)
		(connect_pads
			(clearance 0)
		)
		(min_thickness 0.25)
		(keepout
			(tracks not_allowed)
			(vias allowed)
			(pads allowed)
			(copperpour not_allowed)
			(footprints allowed)
		)
		(placement
			(enabled no)
			(sheetname "")
		)
		(fill yes
			(thermal_gap 0.5)
			(thermal_bridge_width 0.5)
			(island_removal_mode 0)
		)
		(polygon
			(pts
				(arc
					(start 300.15434 -270.43507)
					(mid 299.49394 -270.43507)
					(end 300.15434 -270.43507)
				)
			)
		)
	)
	(zone
		(layers "In1.Cu" "In2.Cu")
		(hatch none 0.5)
		(connect_pads
			(clearance 0)
		)
		(min_thickness 0.25)
		(keepout
			(tracks not_allowed)
			(vias allowed)
			(pads allowed)
			(copperpour not_allowed)
			(footprints allowed)
		)
		(placement
			(enabled no)
			(sheetname "")
		)
		(fill yes
			(thermal_gap 0.5)
			(thermal_bridge_width 0.5)
			(island_removal_mode 0)
		)
		(polygon
			(pts
				(arc
					(start 48.114204 -241.535204)
					(mid 47.453804 -241.535204)
					(end 48.114204 -241.535204)
				)
			)
		)
	)
	(zone
		(layers "In1.Cu" "In2.Cu")
		(hatch none 0.5)
		(connect_pads
			(clearance 0)
		)
		(min_thickness 0.25)
		(keepout
			(tracks not_allowed)
			(vias allowed)
			(pads allowed)
			(copperpour not_allowed)
			(footprints allowed)
		)
		(placement
			(enabled no)
			(sheetname "")
		)
		(fill yes
			(thermal_gap 0.5)
			(thermal_bridge_width 0.5)
			(island_removal_mode 0)
		)
		(polygon
			(pts
				(arc
					(start 435.330346 -251.735082)
					(mid 434.669946 -251.735082)
					(end 435.330346 -251.735082)
				)
			)
		)
	)
	(zone
		(layers "In1.Cu" "In2.Cu")
		(hatch none 0.5)
		(connect_pads
			(clearance 0)
		)
		(min_thickness 0.25)
		(keepout
			(tracks not_allowed)
			(vias allowed)
			(pads allowed)
			(copperpour not_allowed)
			(footprints allowed)
		)
		(placement
			(enabled no)
			(sheetname "")
		)
		(fill yes
			(thermal_gap 0.5)
			(thermal_bridge_width 0.5)
			(island_removal_mode 0)
		)
		(polygon
			(pts
				(arc
					(start 420.242238 -316.335156)
					(mid 419.581838 -316.335156)
					(end 420.242238 -316.335156)
				)
			)
		)
	)
	(zone
		(layers "In1.Cu" "In2.Cu")
		(hatch none 0.5)
		(connect_pads
			(clearance 0)
		)
		(min_thickness 0.25)
		(keepout
			(tracks not_allowed)
			(vias allowed)
			(pads allowed)
			(copperpour not_allowed)
			(footprints allowed)
		)
		(placement
			(enabled no)
			(sheetname "")
		)
		(fill yes
			(thermal_gap 0.5)
			(thermal_bridge_width 0.5)
			(island_removal_mode 0)
		)
		(polygon
			(pts
				(arc
					(start 427.786292 -304.435002)
					(mid 427.125892 -304.435002)
					(end 427.786292 -304.435002)
				)
			)
		)
	)
	(zone
		(layers "In1.Cu" "In2.Cu")
		(hatch none 0.5)
		(connect_pads
			(clearance 0)
		)
		(min_thickness 0.25)
		(keepout
			(tracks not_allowed)
			(vias allowed)
			(pads allowed)
			(copperpour not_allowed)
			(footprints allowed)
		)
		(placement
			(enabled no)
			(sheetname "")
		)
		(fill yes
			(thermal_gap 0.5)
			(thermal_bridge_width 0.5)
			(island_removal_mode 0)
		)
		(polygon
			(pts
				(arc
					(start 273.422364 -237.285022)
					(mid 272.761964 -237.285022)
					(end 273.422364 -237.285022)
				)
			)
		)
	)
	(zone
		(layers "In1.Cu" "In2.Cu")
		(hatch none 0.5)
		(connect_pads
			(clearance 0)
		)
		(min_thickness 0.25)
		(keepout
			(tracks not_allowed)
			(vias allowed)
			(pads allowed)
			(copperpour not_allowed)
			(footprints allowed)
		)
		(placement
			(enabled no)
			(sheetname "")
		)
		(fill yes
			(thermal_gap 0.5)
			(thermal_bridge_width 0.5)
			(island_removal_mode 0)
		)
		(polygon
			(pts
				(arc
					(start 431.88636 -294.235124)
					(mid 431.22596 -294.235124)
					(end 431.88636 -294.235124)
				)
			)
		)
	)
	(zone
		(layers "In1.Cu" "In2.Cu")
		(hatch none 0.5)
		(connect_pads
			(clearance 0)
		)
		(min_thickness 0.25)
		(keepout
			(tracks not_allowed)
			(vias allowed)
			(pads allowed)
			(copperpour not_allowed)
			(footprints allowed)
		)
		(placement
			(enabled no)
			(sheetname "")
		)
		(fill yes
			(thermal_gap 0.5)
			(thermal_bridge_width 0.5)
			(island_removal_mode 0)
		)
		(polygon
			(pts
				(arc
					(start 450.4182 -274.684998)
					(mid 449.7578 -274.684998)
					(end 450.4182 -274.684998)
				)
			)
		)
	)
	(zone
		(layers "In1.Cu" "In2.Cu")
		(hatch none 0.5)
		(connect_pads
			(clearance 0)
		)
		(min_thickness 0.25)
		(keepout
			(tracks not_allowed)
			(vias allowed)
			(pads allowed)
			(copperpour not_allowed)
			(footprints allowed)
		)
		(placement
			(enabled no)
			(sheetname "")
		)
		(fill yes
			(thermal_gap 0.5)
			(thermal_bridge_width 0.5)
			(island_removal_mode 0)
		)
		(polygon
			(pts
				(arc
					(start 292.610286 -197.33514)
					(mid 291.949886 -197.33514)
					(end 292.610286 -197.33514)
				)
			)
		)
	)
	(zone
		(layers "In1.Cu" "In2.Cu")
		(hatch none 0.5)
		(connect_pads
			(clearance 0)
		)
		(min_thickness 0.25)
		(keepout
			(tracks not_allowed)
			(vias allowed)
			(pads allowed)
			(copperpour not_allowed)
			(footprints allowed)
		)
		(placement
			(enabled no)
			(sheetname "")
		)
		(fill yes
			(thermal_gap 0.5)
			(thermal_bridge_width 0.5)
			(island_removal_mode 0)
		)
		(polygon
			(pts
				(arc
					(start 187.390278 -222.835216)
					(mid 186.729878 -222.835216)
					(end 187.390278 -222.835216)
				)
			)
		)
	)
	(zone
		(layers "In1.Cu" "In2.Cu")
		(hatch none 0.5)
		(connect_pads
			(clearance 0)
		)
		(min_thickness 0.25)
		(keepout
			(tracks not_allowed)
			(vias allowed)
			(pads allowed)
			(copperpour not_allowed)
			(footprints allowed)
		)
		(placement
			(enabled no)
			(sheetname "")
		)
		(fill yes
			(thermal_gap 0.5)
			(thermal_bridge_width 0.5)
			(island_removal_mode 0)
		)
		(polygon
			(pts
				(arc
					(start 22.03831 -214.33536)
					(mid 21.37791 -214.33536)
					(end 22.03831 -214.33536)
				)
			)
		)
	)
	(zone
		(layers "In1.Cu" "In2.Cu")
		(hatch none 0.5)
		(connect_pads
			(clearance 0)
		)
		(min_thickness 0.25)
		(keepout
			(tracks not_allowed)
			(vias allowed)
			(pads allowed)
			(copperpour not_allowed)
			(footprints allowed)
		)
		(placement
			(enabled no)
			(sheetname "")
		)
		(fill yes
			(thermal_gap 0.5)
			(thermal_bridge_width 0.5)
			(island_removal_mode 0)
		)
		(polygon
			(pts
				(arc
					(start 396.3416 -11.91768)
					(mid 396.319282 -11.971562)
					(end 396.2654 -11.99388)
				)
				(arc
					(start 395.228826 -11.99388)
					(mid 395.174944 -11.971562)
					(end 395.152626 -11.91768)
				)
				(arc
					(start 395.152626 -10.51814)
					(mid 395.174944 -10.464258)
					(end 395.228826 -10.44194)
				)
				(arc
					(start 396.2654 -10.44194)
					(mid 396.319282 -10.464258)
					(end 396.3416 -10.51814)
				)
			)
		)
	)
	(zone
		(layers "In1.Cu" "In2.Cu")
		(hatch none 0.5)
		(connect_pads
			(clearance 0)
		)
		(min_thickness 0.25)
		(keepout
			(tracks not_allowed)
			(vias allowed)
			(pads allowed)
			(copperpour not_allowed)
			(footprints allowed)
		)
		(placement
			(enabled no)
			(sheetname "")
		)
		(fill yes
			(thermal_gap 0.5)
			(thermal_bridge_width 0.5)
			(island_removal_mode 0)
		)
		(polygon
			(pts
				(arc
					(start 109.66069 -382.27381)
					(mid 109.651454 -382.293734)
					(end 109.648244 -382.315466)
				)
				(arc
					(start 109.648244 -382.51003)
					(mid 109.670562 -382.563912)
					(end 109.724444 -382.58623)
				)
				(arc
					(start 110.410244 -382.58623)
					(mid 110.464126 -382.563912)
					(end 110.486444 -382.51003)
				)
				(arc
					(start 110.486444 -382.315466)
					(mid 110.483276 -382.293722)
					(end 110.473998 -382.27381)
				)
				(arc
					(start 110.281212 -381.977646)
					(mid 110.26899 -381.935962)
					(end 110.281466 -381.894334)
				)
				(arc
					(start 110.473998 -381.60071)
					(mid 110.483234 -381.580786)
					(end 110.486444 -381.559054)
				)
				(arc
					(start 110.486444 -381.36449)
					(mid 110.464126 -381.310608)
					(end 110.410244 -381.28829)
				)
				(arc
					(start 109.724444 -381.28829)
					(mid 109.670562 -381.310608)
					(end 109.648244 -381.36449)
				)
				(arc
					(start 109.648244 -381.560324)
					(mid 109.651412 -381.582068)
					(end 109.66069 -381.60198)
				)
				(arc
					(start 109.853222 -381.895604)
					(mid 109.865624 -381.93726)
					(end 109.853222 -381.978916)
				)
			)
		)
	)
	(zone
		(layers "In1.Cu" "In2.Cu")
		(hatch none 0.5)
		(connect_pads
			(clearance 0)
		)
		(min_thickness 0.25)
		(keepout
			(tracks not_allowed)
			(vias allowed)
			(pads allowed)
			(copperpour not_allowed)
			(footprints allowed)
		)
		(placement
			(enabled no)
			(sheetname "")
		)
		(fill yes
			(thermal_gap 0.5)
			(thermal_bridge_width 0.5)
			(island_removal_mode 0)
		)
		(polygon
			(pts
				(arc
					(start 37.126164 -285.735268)
					(mid 36.465764 -285.735268)
					(end 37.126164 -285.735268)
				)
			)
		)
	)
	(zone
		(layers "In1.Cu" "In2.Cu")
		(hatch none 0.5)
		(connect_pads
			(clearance 0)
		)
		(min_thickness 0.25)
		(keepout
			(tracks not_allowed)
			(vias allowed)
			(pads allowed)
			(copperpour not_allowed)
			(footprints allowed)
		)
		(placement
			(enabled no)
			(sheetname "")
		)
		(fill yes
			(thermal_gap 0.5)
			(thermal_bridge_width 0.5)
			(island_removal_mode 0)
		)
		(polygon
			(pts
				(arc
					(start 306.639976 -417.242244)
					(mid 306.662294 -417.296126)
					(end 306.716176 -417.318444)
				)
				(arc
					(start 306.911756 -417.318444)
					(mid 306.933632 -417.315312)
					(end 306.953666 -417.305998)
				)
				(arc
					(start 307.24729 -417.113466)
					(mid 307.288946 -417.101064)
					(end 307.330602 -417.113466)
				)
				(arc
					(start 307.625496 -417.305998)
					(mid 307.64542 -417.315234)
					(end 307.667152 -417.318444)
				)
				(arc
					(start 307.861716 -417.318444)
					(mid 307.915598 -417.296126)
					(end 307.937916 -417.242244)
				)
				(arc
					(start 307.937916 -416.556444)
					(mid 307.915598 -416.502562)
					(end 307.861716 -416.480244)
				)
				(arc
					(start 307.667152 -416.480244)
					(mid 307.645408 -416.483412)
					(end 307.625496 -416.49269)
				)
				(arc
					(start 307.329332 -416.685476)
					(mid 307.287648 -416.697698)
					(end 307.24602 -416.685222)
				)
				(arc
					(start 306.952396 -416.49269)
					(mid 306.932472 -416.483454)
					(end 306.91074 -416.480244)
				)
				(arc
					(start 306.716176 -416.480244)
					(mid 306.662294 -416.502562)
					(end 306.639976 -416.556444)
				)
			)
		)
	)
	(zone
		(layers "In1.Cu" "In2.Cu")
		(hatch none 0.5)
		(connect_pads
			(clearance 0)
		)
		(min_thickness 0.25)
		(keepout
			(tracks not_allowed)
			(vias allowed)
			(pads allowed)
			(copperpour not_allowed)
			(footprints allowed)
		)
		(placement
			(enabled no)
			(sheetname "")
		)
		(fill yes
			(thermal_gap 0.5)
			(thermal_bridge_width 0.5)
			(island_removal_mode 0)
		)
		(polygon
			(pts
				(arc
					(start 194.934332 -241.535204)
					(mid 194.273932 -241.535204)
					(end 194.934332 -241.535204)
				)
			)
		)
	)
	(zone
		(layers "In1.Cu" "In2.Cu")
		(hatch none 0.5)
		(connect_pads
			(clearance 0)
		)
		(min_thickness 0.25)
		(keepout
			(tracks not_allowed)
			(vias allowed)
			(pads allowed)
			(copperpour not_allowed)
			(footprints allowed)
		)
		(placement
			(enabled no)
			(sheetname "")
		)
		(fill yes
			(thermal_gap 0.5)
			(thermal_bridge_width 0.5)
			(island_removal_mode 0)
		)
		(polygon
			(pts
				(arc
					(start 418.662358 -7.672324)
					(mid 418.684676 -7.618442)
					(end 418.738558 -7.596124)
				)
				(arc
					(start 419.775132 -7.596124)
					(mid 419.829014 -7.618442)
					(end 419.851332 -7.672324)
				)
				(arc
					(start 419.851332 -9.071864)
					(mid 419.829014 -9.125746)
					(end 419.775132 -9.148064)
				)
				(arc
					(start 418.738558 -9.148064)
					(mid 418.684676 -9.125746)
					(end 418.662358 -9.071864)
				)
			)
		)
	)
	(zone
		(layers "In1.Cu" "In2.Cu")
		(hatch none 0.5)
		(connect_pads
			(clearance 0)
		)
		(min_thickness 0.25)
		(keepout
			(tracks not_allowed)
			(vias allowed)
			(pads allowed)
			(copperpour not_allowed)
			(footprints allowed)
		)
		(placement
			(enabled no)
			(sheetname "")
		)
		(fill yes
			(thermal_gap 0.5)
			(thermal_bridge_width 0.5)
			(island_removal_mode 0)
		)
		(polygon
			(pts
				(arc
					(start 52.214272 -266.185396)
					(mid 51.553872 -266.185396)
					(end 52.214272 -266.185396)
				)
			)
		)
	)
	(zone
		(layers "In1.Cu" "In2.Cu")
		(hatch none 0.5)
		(connect_pads
			(clearance 0)
		)
		(min_thickness 0.25)
		(keepout
			(tracks not_allowed)
			(vias allowed)
			(pads allowed)
			(copperpour not_allowed)
			(footprints allowed)
		)
		(placement
			(enabled no)
			(sheetname "")
		)
		(fill yes
			(thermal_gap 0.5)
			(thermal_bridge_width 0.5)
			(island_removal_mode 0)
		)
		(polygon
			(pts
				(arc
					(start 29.582364 -212.635338)
					(mid 28.921964 -212.635338)
					(end 29.582364 -212.635338)
				)
			)
		)
	)
	(zone
		(layers "In1.Cu" "In2.Cu")
		(hatch none 0.5)
		(connect_pads
			(clearance 0)
		)
		(min_thickness 0.25)
		(keepout
			(tracks not_allowed)
			(vias allowed)
			(pads allowed)
			(copperpour not_allowed)
			(footprints allowed)
		)
		(placement
			(enabled no)
			(sheetname "")
		)
		(fill yes
			(thermal_gap 0.5)
			(thermal_bridge_width 0.5)
			(island_removal_mode 0)
		)
		(polygon
			(pts
				(arc
					(start 450.4182 -210.935062)
					(mid 449.7578 -210.935062)
					(end 450.4182 -210.935062)
				)
			)
		)
	)
	(zone
		(layers "In1.Cu" "In2.Cu")
		(hatch none 0.5)
		(connect_pads
			(clearance 0)
		)
		(min_thickness 0.25)
		(keepout
			(tracks not_allowed)
			(vias allowed)
			(pads allowed)
			(copperpour not_allowed)
			(footprints allowed)
		)
		(placement
			(enabled no)
			(sheetname "")
		)
		(fill yes
			(thermal_gap 0.5)
			(thermal_bridge_width 0.5)
			(island_removal_mode 0)
		)
		(polygon
			(pts
				(arc
					(start 44.670218 -236.435392)
					(mid 44.009818 -236.435392)
					(end 44.670218 -236.435392)
				)
			)
		)
	)
	(zone
		(layers "In1.Cu" "In2.Cu")
		(hatch none 0.5)
		(connect_pads
			(clearance 0)
		)
		(min_thickness 0.25)
		(keepout
			(tracks not_allowed)
			(vias allowed)
			(pads allowed)
			(copperpour not_allowed)
			(footprints allowed)
		)
		(placement
			(enabled no)
			(sheetname "")
		)
		(fill yes
			(thermal_gap 0.5)
			(thermal_bridge_width 0.5)
			(island_removal_mode 0)
		)
		(polygon
			(pts
				(arc
					(start 25.482296 -198.185278)
					(mid 24.821896 -198.185278)
					(end 25.482296 -198.185278)
				)
			)
		)
	)
	(zone
		(layers "In1.Cu" "In2.Cu")
		(hatch none 0.5)
		(connect_pads
			(clearance 0)
		)
		(min_thickness 0.25)
		(keepout
			(tracks not_allowed)
			(vias allowed)
			(pads allowed)
			(copperpour not_allowed)
			(footprints allowed)
		)
		(placement
			(enabled no)
			(sheetname "")
		)
		(fill yes
			(thermal_gap 0.5)
			(thermal_bridge_width 0.5)
			(island_removal_mode 0)
		)
		(polygon
			(pts
				(arc
					(start 50.640234 -408.860244)
					(mid 50.662552 -408.914126)
					(end 50.716434 -408.936444)
				)
				(arc
					(start 50.912014 -408.936444)
					(mid 50.93389 -408.933312)
					(end 50.953924 -408.923998)
				)
				(arc
					(start 51.247548 -408.731466)
					(mid 51.289204 -408.719064)
					(end 51.33086 -408.731466)
				)
				(arc
					(start 51.625754 -408.923998)
					(mid 51.645678 -408.933234)
					(end 51.66741 -408.936444)
				)
				(arc
					(start 51.861974 -408.936444)
					(mid 51.915856 -408.914126)
					(end 51.938174 -408.860244)
				)
				(arc
					(start 51.938174 -408.174444)
					(mid 51.915856 -408.120562)
					(end 51.861974 -408.098244)
				)
				(arc
					(start 51.66741 -408.098244)
					(mid 51.645666 -408.101412)
					(end 51.625754 -408.11069)
				)
				(arc
					(start 51.32959 -408.303476)
					(mid 51.287906 -408.315698)
					(end 51.246278 -408.303222)
				)
				(arc
					(start 50.952654 -408.11069)
					(mid 50.93273 -408.101454)
					(end 50.910998 -408.098244)
				)
				(arc
					(start 50.716434 -408.098244)
					(mid 50.662552 -408.120562)
					(end 50.640234 -408.174444)
				)
			)
		)
	)
	(zone
		(layers "In1.Cu" "In2.Cu")
		(hatch none 0.5)
		(connect_pads
			(clearance 0)
		)
		(min_thickness 0.25)
		(keepout
			(tracks not_allowed)
			(vias allowed)
			(pads allowed)
			(copperpour not_allowed)
			(footprints allowed)
		)
		(placement
			(enabled no)
			(sheetname "")
		)
		(fill yes
			(thermal_gap 0.5)
			(thermal_bridge_width 0.5)
			(island_removal_mode 0)
		)
		(polygon
			(pts
				(arc
					(start 191.490346 -298.485306)
					(mid 190.829946 -298.485306)
					(end 191.490346 -298.485306)
				)
			)
		)
	)
	(zone
		(layers "In1.Cu" "In2.Cu")
		(hatch none 0.5)
		(connect_pads
			(clearance 0)
		)
		(min_thickness 0.25)
		(keepout
			(tracks not_allowed)
			(vias allowed)
			(pads allowed)
			(copperpour not_allowed)
			(footprints allowed)
		)
		(placement
			(enabled no)
			(sheetname "")
		)
		(fill yes
			(thermal_gap 0.5)
			(thermal_bridge_width 0.5)
			(island_removal_mode 0)
		)
		(polygon
			(pts
				(arc
					(start 280.966164 -302.73498)
					(mid 280.305764 -302.73498)
					(end 280.966164 -302.73498)
				)
			)
		)
	)
	(zone
		(layers "In1.Cu" "In2.Cu")
		(hatch none 0.5)
		(connect_pads
			(clearance 0)
		)
		(min_thickness 0.25)
		(keepout
			(tracks not_allowed)
			(vias allowed)
			(pads allowed)
			(copperpour not_allowed)
			(footprints allowed)
		)
		(placement
			(enabled no)
			(sheetname "")
		)
		(fill yes
			(thermal_gap 0.5)
			(thermal_bridge_width 0.5)
			(island_removal_mode 0)
		)
		(polygon
			(pts
				(arc
					(start 300.15434 -199.035162)
					(mid 299.49394 -199.035162)
					(end 300.15434 -199.035162)
				)
			)
		)
	)
	(zone
		(layers "In1.Cu" "In2.Cu")
		(hatch none 0.5)
		(connect_pads
			(clearance 0)
		)
		(min_thickness 0.25)
		(keepout
			(tracks not_allowed)
			(vias allowed)
			(pads allowed)
			(copperpour not_allowed)
			(footprints allowed)
		)
		(placement
			(enabled no)
			(sheetname "")
		)
		(fill yes
			(thermal_gap 0.5)
			(thermal_bridge_width 0.5)
			(island_removal_mode 0)
		)
		(polygon
			(pts
				(arc
					(start 22.03831 -317.185294)
					(mid 21.37791 -317.185294)
					(end 22.03831 -317.185294)
				)
			)
		)
	)
	(zone
		(layers "In1.Cu" "In2.Cu")
		(hatch none 0.5)
		(connect_pads
			(clearance 0)
		)
		(min_thickness 0.25)
		(keepout
			(tracks not_allowed)
			(vias allowed)
			(pads allowed)
			(copperpour not_allowed)
			(footprints allowed)
		)
		(placement
			(enabled no)
			(sheetname "")
		)
		(fill yes
			(thermal_gap 0.5)
			(thermal_bridge_width 0.5)
			(island_removal_mode 0)
		)
		(polygon
			(pts
				(arc
					(start 126.929896 -408.860244)
					(mid 126.952214 -408.914126)
					(end 127.006096 -408.936444)
				)
				(arc
					(start 127.201676 -408.936444)
					(mid 127.223552 -408.933312)
					(end 127.243586 -408.923998)
				)
				(arc
					(start 127.53721 -408.731466)
					(mid 127.578866 -408.719064)
					(end 127.620522 -408.731466)
				)
				(arc
					(start 127.915416 -408.923998)
					(mid 127.93534 -408.933234)
					(end 127.957072 -408.936444)
				)
				(arc
					(start 128.151636 -408.936444)
					(mid 128.205518 -408.914126)
					(end 128.227836 -408.860244)
				)
				(arc
					(start 128.227836 -408.174444)
					(mid 128.205518 -408.120562)
					(end 128.151636 -408.098244)
				)
				(arc
					(start 127.957072 -408.098244)
					(mid 127.935328 -408.101412)
					(end 127.915416 -408.11069)
				)
				(arc
					(start 127.619252 -408.303476)
					(mid 127.577568 -408.315698)
					(end 127.53594 -408.303222)
				)
				(arc
					(start 127.242316 -408.11069)
					(mid 127.222392 -408.101454)
					(end 127.20066 -408.098244)
				)
				(arc
					(start 127.006096 -408.098244)
					(mid 126.952214 -408.120562)
					(end 126.929896 -408.174444)
				)
			)
		)
	)
	(zone
		(layers "In1.Cu" "In2.Cu")
		(hatch none 0.5)
		(connect_pads
			(clearance 0)
		)
		(min_thickness 0.25)
		(keepout
			(tracks not_allowed)
			(vias allowed)
			(pads allowed)
			(copperpour not_allowed)
			(footprints allowed)
		)
		(placement
			(enabled no)
			(sheetname "")
		)
		(fill yes
			(thermal_gap 0.5)
			(thermal_bridge_width 0.5)
			(island_removal_mode 0)
		)
		(polygon
			(pts
				(arc
					(start 442.8744 -285.735014)
					(mid 442.214 -285.735014)
					(end 442.8744 -285.735014)
				)
			)
		)
	)
	(zone
		(layers "In1.Cu" "In2.Cu")
		(hatch none 0.5)
		(connect_pads
			(clearance 0)
		)
		(min_thickness 0.25)
		(keepout
			(tracks not_allowed)
			(vias allowed)
			(pads allowed)
			(copperpour not_allowed)
			(footprints allowed)
		)
		(placement
			(enabled no)
			(sheetname "")
		)
		(fill yes
			(thermal_gap 0.5)
			(thermal_bridge_width 0.5)
			(island_removal_mode 0)
		)
		(polygon
			(pts
				(arc
					(start 454.518268 -272.135092)
					(mid 453.857868 -272.135092)
					(end 454.518268 -272.135092)
				)
			)
		)
	)
	(zone
		(layers "In1.Cu" "In2.Cu")
		(hatch none 0.5)
		(connect_pads
			(clearance 0)
		)
		(min_thickness 0.25)
		(keepout
			(tracks not_allowed)
			(vias allowed)
			(pads allowed)
			(copperpour not_allowed)
			(footprints allowed)
		)
		(placement
			(enabled no)
			(sheetname "")
		)
		(fill yes
			(thermal_gap 0.5)
			(thermal_bridge_width 0.5)
			(island_removal_mode 0)
		)
		(polygon
			(pts
				(arc
					(start 292.610286 -233.035094)
					(mid 291.949886 -233.035094)
					(end 292.610286 -233.035094)
				)
			)
		)
	)
	(zone
		(layers "In1.Cu" "In2.Cu")
		(hatch none 0.5)
		(connect_pads
			(clearance 0)
		)
		(min_thickness 0.25)
		(keepout
			(tracks not_allowed)
			(vias allowed)
			(pads allowed)
			(copperpour not_allowed)
			(footprints allowed)
		)
		(placement
			(enabled no)
			(sheetname "")
		)
		(fill yes
			(thermal_gap 0.5)
			(thermal_bridge_width 0.5)
			(island_removal_mode 0)
		)
		(polygon
			(pts
				(arc
					(start 277.522432 -269.585186)
					(mid 276.862032 -269.585186)
					(end 277.522432 -269.585186)
				)
			)
		)
	)
	(zone
		(layers "In1.Cu" "In2.Cu")
		(hatch none 0.5)
		(connect_pads
			(clearance 0)
		)
		(min_thickness 0.25)
		(keepout
			(tracks not_allowed)
			(vias allowed)
			(pads allowed)
			(copperpour not_allowed)
			(footprints allowed)
		)
		(placement
			(enabled no)
			(sheetname "")
		)
		(fill yes
			(thermal_gap 0.5)
			(thermal_bridge_width 0.5)
			(island_removal_mode 0)
		)
		(polygon
			(pts
				(arc
					(start 431.88636 -227.085144)
					(mid 431.22596 -227.085144)
					(end 431.88636 -227.085144)
				)
			)
		)
	)
	(zone
		(layers "In1.Cu" "In2.Cu")
		(hatch none 0.5)
		(connect_pads
			(clearance 0)
		)
		(min_thickness 0.25)
		(keepout
			(tracks not_allowed)
			(vias allowed)
			(pads allowed)
			(copperpour not_allowed)
			(footprints allowed)
		)
		(placement
			(enabled no)
			(sheetname "")
		)
		(fill yes
			(thermal_gap 0.5)
			(thermal_bridge_width 0.5)
			(island_removal_mode 0)
		)
		(polygon
			(pts
				(arc
					(start 179.846224 -199.8853)
					(mid 179.185824 -199.8853)
					(end 179.846224 -199.8853)
				)
			)
		)
	)
	(zone
		(layers "In1.Cu" "In2.Cu")
		(hatch none 0.5)
		(connect_pads
			(clearance 0)
		)
		(min_thickness 0.25)
		(keepout
			(tracks not_allowed)
			(vias allowed)
			(pads allowed)
			(copperpour not_allowed)
			(footprints allowed)
		)
		(placement
			(enabled no)
			(sheetname "")
		)
		(fill yes
			(thermal_gap 0.5)
			(thermal_bridge_width 0.5)
			(island_removal_mode 0)
		)
		(polygon
			(pts
				(arc
					(start 179.846224 -198.185278)
					(mid 179.185824 -198.185278)
					(end 179.846224 -198.185278)
				)
			)
		)
	)
	(zone
		(layers "In1.Cu" "In2.Cu")
		(hatch none 0.5)
		(connect_pads
			(clearance 0)
		)
		(min_thickness 0.25)
		(keepout
			(tracks not_allowed)
			(vias allowed)
			(pads allowed)
			(copperpour not_allowed)
			(footprints allowed)
		)
		(placement
			(enabled no)
			(sheetname "")
		)
		(fill yes
			(thermal_gap 0.5)
			(thermal_bridge_width 0.5)
			(island_removal_mode 0)
		)
		(polygon
			(pts
				(arc
					(start 29.582364 -275.53539)
					(mid 28.921964 -275.53539)
					(end 29.582364 -275.53539)
				)
			)
		)
	)
	(zone
		(layers "In1.Cu" "In2.Cu")
		(hatch none 0.5)
		(connect_pads
			(clearance 0)
		)
		(min_thickness 0.25)
		(keepout
			(tracks not_allowed)
			(vias allowed)
			(pads allowed)
			(copperpour not_allowed)
			(footprints allowed)
		)
		(placement
			(enabled no)
			(sheetname "")
		)
		(fill yes
			(thermal_gap 0.5)
			(thermal_bridge_width 0.5)
			(island_removal_mode 0)
		)
		(polygon
			(pts
				(arc
					(start 199.0344 -208.38541)
					(mid 198.374 -208.38541)
					(end 199.0344 -208.38541)
				)
			)
		)
	)
	(zone
		(layers "In1.Cu" "In2.Cu")
		(hatch none 0.5)
		(connect_pads
			(clearance 0)
		)
		(min_thickness 0.25)
		(keepout
			(tracks not_allowed)
			(vias allowed)
			(pads allowed)
			(copperpour not_allowed)
			(footprints allowed)
		)
		(placement
			(enabled no)
			(sheetname "")
		)
		(fill yes
			(thermal_gap 0.5)
			(thermal_bridge_width 0.5)
			(island_removal_mode 0)
		)
		(polygon
			(pts
				(arc
					(start 202.478132 -205.83525)
					(mid 201.817732 -205.83525)
					(end 202.478132 -205.83525)
				)
			)
		)
	)
	(zone
		(layers "In1.Cu" "In2.Cu")
		(hatch none 0.5)
		(connect_pads
			(clearance 0)
		)
		(min_thickness 0.25)
		(keepout
			(tracks not_allowed)
			(vias allowed)
			(pads allowed)
			(copperpour not_allowed)
			(footprints allowed)
		)
		(placement
			(enabled no)
			(sheetname "")
		)
		(fill yes
			(thermal_gap 0.5)
			(thermal_bridge_width 0.5)
			(island_removal_mode 0)
		)
		(polygon
			(pts
				(arc
					(start 194.934332 -295.9354)
					(mid 194.273932 -295.9354)
					(end 194.934332 -295.9354)
				)
			)
		)
	)
	(zone
		(layers "In1.Cu" "In2.Cu")
		(hatch none 0.5)
		(connect_pads
			(clearance 0)
		)
		(min_thickness 0.25)
		(keepout
			(tracks not_allowed)
			(vias allowed)
			(pads allowed)
			(copperpour not_allowed)
			(footprints allowed)
		)
		(placement
			(enabled no)
			(sheetname "")
		)
		(fill yes
			(thermal_gap 0.5)
			(thermal_bridge_width 0.5)
			(island_removal_mode 0)
		)
		(polygon
			(pts
				(arc
					(start 199.0344 -197.335394)
					(mid 198.374 -197.335394)
					(end 199.0344 -197.335394)
				)
			)
		)
	)
	(zone
		(layers "In1.Cu" "In2.Cu")
		(hatch none 0.5)
		(connect_pads
			(clearance 0)
		)
		(min_thickness 0.25)
		(keepout
			(tracks not_allowed)
			(vias allowed)
			(pads allowed)
			(copperpour not_allowed)
			(footprints allowed)
		)
		(placement
			(enabled no)
			(sheetname "")
		)
		(fill yes
			(thermal_gap 0.5)
			(thermal_bridge_width 0.5)
			(island_removal_mode 0)
		)
		(polygon
			(pts
				(arc
					(start 439.430414 -201.585068)
					(mid 438.770014 -201.585068)
					(end 439.430414 -201.585068)
				)
			)
		)
	)
	(zone
		(layers "In1.Cu" "In2.Cu")
		(hatch none 0.5)
		(connect_pads
			(clearance 0)
		)
		(min_thickness 0.25)
		(keepout
			(tracks not_allowed)
			(vias allowed)
			(pads allowed)
			(copperpour not_allowed)
			(footprints allowed)
		)
		(placement
			(enabled no)
			(sheetname "")
		)
		(fill yes
			(thermal_gap 0.5)
			(thermal_bridge_width 0.5)
			(island_removal_mode 0)
		)
		(polygon
			(pts
				(arc
					(start 176.402238 -236.435392)
					(mid 175.741838 -236.435392)
					(end 176.402238 -236.435392)
				)
			)
		)
	)
	(zone
		(layers "In1.Cu" "In2.Cu")
		(hatch none 0.5)
		(connect_pads
			(clearance 0)
		)
		(min_thickness 0.25)
		(keepout
			(tracks not_allowed)
			(vias allowed)
			(pads allowed)
			(copperpour not_allowed)
			(footprints allowed)
		)
		(placement
			(enabled no)
			(sheetname "")
		)
		(fill yes
			(thermal_gap 0.5)
			(thermal_bridge_width 0.5)
			(island_removal_mode 0)
		)
		(polygon
			(pts
				(arc
					(start 40.57015 -235.585254)
					(mid 39.90975 -235.585254)
					(end 40.57015 -235.585254)
				)
			)
		)
	)
	(zone
		(layers "In1.Cu" "In2.Cu")
		(hatch none 0.5)
		(connect_pads
			(clearance 0)
		)
		(min_thickness 0.25)
		(keepout
			(tracks not_allowed)
			(vias allowed)
			(pads allowed)
			(copperpour not_allowed)
			(footprints allowed)
		)
		(placement
			(enabled no)
			(sheetname "")
		)
		(fill yes
			(thermal_gap 0.5)
			(thermal_bridge_width 0.5)
			(island_removal_mode 0)
		)
		(polygon
			(pts
				(arc
					(start 285.066232 -306.135024)
					(mid 284.405832 -306.135024)
					(end 285.066232 -306.135024)
				)
			)
		)
	)
	(zone
		(layers "In1.Cu" "In2.Cu")
		(hatch none 0.5)
		(connect_pads
			(clearance 0)
		)
		(min_thickness 0.25)
		(keepout
			(tracks not_allowed)
			(vias allowed)
			(pads allowed)
			(copperpour not_allowed)
			(footprints allowed)
		)
		(placement
			(enabled no)
			(sheetname "")
		)
		(fill yes
			(thermal_gap 0.5)
			(thermal_bridge_width 0.5)
			(island_removal_mode 0)
		)
		(polygon
			(pts
				(arc
					(start 285.066232 -267.885164)
					(mid 284.405832 -267.885164)
					(end 285.066232 -267.885164)
				)
			)
		)
	)
	(zone
		(layers "In1.Cu" "In2.Cu")
		(hatch none 0.5)
		(connect_pads
			(clearance 0)
		)
		(min_thickness 0.25)
		(keepout
			(tracks not_allowed)
			(vias allowed)
			(pads allowed)
			(copperpour not_allowed)
			(footprints allowed)
		)
		(placement
			(enabled no)
			(sheetname "")
		)
		(fill yes
			(thermal_gap 0.5)
			(thermal_bridge_width 0.5)
			(island_removal_mode 0)
		)
		(polygon
			(pts
				(arc
					(start 424.342306 -206.685134)
					(mid 423.681906 -206.685134)
					(end 424.342306 -206.685134)
				)
			)
		)
	)
	(zone
		(layers "In1.Cu" "In2.Cu")
		(hatch none 0.5)
		(connect_pads
			(clearance 0)
		)
		(min_thickness 0.25)
		(keepout
			(tracks not_allowed)
			(vias allowed)
			(pads allowed)
			(copperpour not_allowed)
			(footprints allowed)
		)
		(placement
			(enabled no)
			(sheetname "")
		)
		(fill yes
			(thermal_gap 0.5)
			(thermal_bridge_width 0.5)
			(island_removal_mode 0)
		)
		(polygon
			(pts
				(arc
					(start 296.054272 -314.635134)
					(mid 295.393872 -314.635134)
					(end 296.054272 -314.635134)
				)
			)
		)
	)
	(zone
		(layers "In1.Cu" "In2.Cu")
		(hatch none 0.5)
		(connect_pads
			(clearance 0)
		)
		(min_thickness 0.25)
		(keepout
			(tracks not_allowed)
			(vias allowed)
			(pads allowed)
			(copperpour not_allowed)
			(footprints allowed)
		)
		(placement
			(enabled no)
			(sheetname "")
		)
		(fill yes
			(thermal_gap 0.5)
			(thermal_bridge_width 0.5)
			(island_removal_mode 0)
		)
		(polygon
			(pts
				(arc
					(start 427.786292 -246.635016)
					(mid 427.125892 -246.635016)
					(end 427.786292 -246.635016)
				)
			)
		)
	)
	(zone
		(layers "In1.Cu" "In2.Cu")
		(hatch none 0.5)
		(connect_pads
			(clearance 0)
		)
		(min_thickness 0.25)
		(keepout
			(tracks not_allowed)
			(vias allowed)
			(pads allowed)
			(copperpour not_allowed)
			(footprints allowed)
		)
		(placement
			(enabled no)
			(sheetname "")
		)
		(fill yes
			(thermal_gap 0.5)
			(thermal_bridge_width 0.5)
			(island_removal_mode 0)
		)
		(polygon
			(pts
				(arc
					(start 52.214272 -236.435392)
					(mid 51.553872 -236.435392)
					(end 52.214272 -236.435392)
				)
			)
		)
	)
	(zone
		(layers "In1.Cu" "In2.Cu")
		(hatch none 0.5)
		(connect_pads
			(clearance 0)
		)
		(min_thickness 0.25)
		(keepout
			(tracks not_allowed)
			(vias allowed)
			(pads allowed)
			(copperpour not_allowed)
			(footprints allowed)
		)
		(placement
			(enabled no)
			(sheetname "")
		)
		(fill yes
			(thermal_gap 0.5)
			(thermal_bridge_width 0.5)
			(island_removal_mode 0)
		)
		(polygon
			(pts
				(arc
					(start 427.786292 -201.585068)
					(mid 427.125892 -201.585068)
					(end 427.786292 -201.585068)
				)
			)
		)
	)
	(zone
		(layers "In1.Cu" "In2.Cu")
		(hatch none 0.5)
		(connect_pads
			(clearance 0)
		)
		(min_thickness 0.25)
		(keepout
			(tracks not_allowed)
			(vias allowed)
			(pads allowed)
			(copperpour not_allowed)
			(footprints allowed)
		)
		(placement
			(enabled no)
			(sheetname "")
		)
		(fill yes
			(thermal_gap 0.5)
			(thermal_bridge_width 0.5)
			(island_removal_mode 0)
		)
		(polygon
			(pts
				(arc
					(start 48.114204 -207.535272)
					(mid 47.453804 -207.535272)
					(end 48.114204 -207.535272)
				)
			)
		)
	)
	(zone
		(layers "In1.Cu" "In2.Cu")
		(hatch none 0.5)
		(connect_pads
			(clearance 0)
		)
		(min_thickness 0.25)
		(keepout
			(tracks not_allowed)
			(vias allowed)
			(pads allowed)
			(copperpour not_allowed)
			(footprints allowed)
		)
		(placement
			(enabled no)
			(sheetname "")
		)
		(fill yes
			(thermal_gap 0.5)
			(thermal_bridge_width 0.5)
			(island_removal_mode 0)
		)
		(polygon
			(pts
				(arc
					(start 176.402238 -262.785352)
					(mid 175.741838 -262.785352)
					(end 176.402238 -262.785352)
				)
			)
		)
	)
	(zone
		(layers "In1.Cu" "In2.Cu")
		(hatch none 0.5)
		(connect_pads
			(clearance 0)
		)
		(min_thickness 0.25)
		(keepout
			(tracks not_allowed)
			(vias allowed)
			(pads allowed)
			(copperpour not_allowed)
			(footprints allowed)
		)
		(placement
			(enabled no)
			(sheetname "")
		)
		(fill yes
			(thermal_gap 0.5)
			(thermal_bridge_width 0.5)
			(island_removal_mode 0)
		)
		(polygon
			(pts
				(arc
					(start 292.610286 -249.185176)
					(mid 291.949886 -249.185176)
					(end 292.610286 -249.185176)
				)
			)
		)
	)
	(zone
		(layers "In1.Cu" "In2.Cu")
		(hatch none 0.5)
		(connect_pads
			(clearance 0)
		)
		(min_thickness 0.25)
		(keepout
			(tracks not_allowed)
			(vias allowed)
			(pads allowed)
			(copperpour not_allowed)
			(footprints allowed)
		)
		(placement
			(enabled no)
			(sheetname "")
		)
		(fill yes
			(thermal_gap 0.5)
			(thermal_bridge_width 0.5)
			(island_removal_mode 0)
		)
		(polygon
			(pts
				(arc
					(start 288.510218 -312.084974)
					(mid 287.849818 -312.084974)
					(end 288.510218 -312.084974)
				)
			)
		)
	)
	(zone
		(layers "In1.Cu" "In2.Cu")
		(hatch none 0.5)
		(connect_pads
			(clearance 0)
		)
		(min_thickness 0.25)
		(keepout
			(tracks not_allowed)
			(vias allowed)
			(pads allowed)
			(copperpour not_allowed)
			(footprints allowed)
		)
		(placement
			(enabled no)
			(sheetname "")
		)
		(fill yes
			(thermal_gap 0.5)
			(thermal_bridge_width 0.5)
			(island_removal_mode 0)
		)
		(polygon
			(pts
				(arc
					(start 29.582364 -287.43529)
					(mid 28.921964 -287.43529)
					(end 29.582364 -287.43529)
				)
			)
		)
	)
	(zone
		(layers "In1.Cu" "In2.Cu")
		(hatch none 0.5)
		(connect_pads
			(clearance 0)
		)
		(min_thickness 0.25)
		(keepout
			(tracks not_allowed)
			(vias allowed)
			(pads allowed)
			(copperpour not_allowed)
			(footprints allowed)
		)
		(placement
			(enabled no)
			(sheetname "")
		)
		(fill yes
			(thermal_gap 0.5)
			(thermal_bridge_width 0.5)
			(island_removal_mode 0)
		)
		(polygon
			(pts
				(arc
					(start 345.921076 -292.41115)
					(mid 345.616276 -292.71595)
					(end 345.921076 -293.02075)
				)
				(arc
					(start 346.86113 -293.02075)
					(mid 347.16593 -292.71595)
					(end 346.86113 -292.41115)
				)
			)
		)
	)
	(zone
		(layers "In1.Cu" "In2.Cu")
		(hatch none 0.5)
		(connect_pads
			(clearance 0)
		)
		(min_thickness 0.25)
		(keepout
			(tracks not_allowed)
			(vias allowed)
			(pads allowed)
			(copperpour not_allowed)
			(footprints allowed)
		)
		(placement
			(enabled no)
			(sheetname "")
		)
		(fill yes
			(thermal_gap 0.5)
			(thermal_bridge_width 0.5)
			(island_removal_mode 0)
		)
		(polygon
			(pts
				(arc
					(start 199.0344 -273.835368)
					(mid 198.374 -273.835368)
					(end 199.0344 -273.835368)
				)
			)
		)
	)
	(zone
		(layers "In1.Cu" "In2.Cu")
		(hatch none 0.5)
		(connect_pads
			(clearance 0)
		)
		(min_thickness 0.25)
		(keepout
			(tracks not_allowed)
			(vias allowed)
			(pads allowed)
			(copperpour not_allowed)
			(footprints allowed)
		)
		(placement
			(enabled no)
			(sheetname "")
		)
		(fill yes
			(thermal_gap 0.5)
			(thermal_bridge_width 0.5)
			(island_removal_mode 0)
		)
		(polygon
			(pts
				(arc
					(start 187.390278 -229.635304)
					(mid 186.729878 -229.635304)
					(end 187.390278 -229.635304)
				)
			)
		)
	)
	(zone
		(layers "In1.Cu" "In2.Cu")
		(hatch none 0.5)
		(connect_pads
			(clearance 0)
		)
		(min_thickness 0.25)
		(keepout
			(tracks not_allowed)
			(vias allowed)
			(pads allowed)
			(copperpour not_allowed)
			(footprints allowed)
		)
		(placement
			(enabled no)
			(sheetname "")
		)
		(fill yes
			(thermal_gap 0.5)
			(thermal_bridge_width 0.5)
			(island_removal_mode 0)
		)
		(polygon
			(pts
				(arc
					(start 288.510218 -314.635134)
					(mid 287.849818 -314.635134)
					(end 288.510218 -314.635134)
				)
			)
		)
	)
	(zone
		(layers "In1.Cu" "In2.Cu")
		(hatch none 0.5)
		(connect_pads
			(clearance 0)
		)
		(min_thickness 0.25)
		(keepout
			(tracks not_allowed)
			(vias allowed)
			(pads allowed)
			(copperpour not_allowed)
			(footprints allowed)
		)
		(placement
			(enabled no)
			(sheetname "")
		)
		(fill yes
			(thermal_gap 0.5)
			(thermal_bridge_width 0.5)
			(island_removal_mode 0)
		)
		(polygon
			(pts
				(arc
					(start 40.57015 -239.835436)
					(mid 39.90975 -239.835436)
					(end 40.57015 -239.835436)
				)
			)
		)
	)
	(zone
		(layers "In1.Cu" "In2.Cu")
		(hatch none 0.5)
		(connect_pads
			(clearance 0)
		)
		(min_thickness 0.25)
		(keepout
			(tracks not_allowed)
			(vias allowed)
			(pads allowed)
			(copperpour not_allowed)
			(footprints allowed)
		)
		(placement
			(enabled no)
			(sheetname "")
		)
		(fill yes
			(thermal_gap 0.5)
			(thermal_bridge_width 0.5)
			(island_removal_mode 0)
		)
		(polygon
			(pts
				(arc
					(start 288.510218 -310.384952)
					(mid 287.849818 -310.384952)
					(end 288.510218 -310.384952)
				)
			)
		)
	)
	(zone
		(layers "In1.Cu" "In2.Cu")
		(hatch none 0.5)
		(connect_pads
			(clearance 0)
		)
		(min_thickness 0.25)
		(keepout
			(tracks not_allowed)
			(vias allowed)
			(pads allowed)
			(copperpour not_allowed)
			(footprints allowed)
		)
		(placement
			(enabled no)
			(sheetname "")
		)
		(fill yes
			(thermal_gap 0.5)
			(thermal_bridge_width 0.5)
			(island_removal_mode 0)
		)
		(polygon
			(pts
				(arc
					(start 454.518268 -276.38502)
					(mid 453.857868 -276.38502)
					(end 454.518268 -276.38502)
				)
			)
		)
	)
	(zone
		(layers "In1.Cu" "In2.Cu")
		(hatch none 0.5)
		(connect_pads
			(clearance 0)
		)
		(min_thickness 0.25)
		(keepout
			(tracks not_allowed)
			(vias allowed)
			(pads allowed)
			(copperpour not_allowed)
			(footprints allowed)
		)
		(placement
			(enabled no)
			(sheetname "")
		)
		(fill yes
			(thermal_gap 0.5)
			(thermal_bridge_width 0.5)
			(island_removal_mode 0)
		)
		(polygon
			(pts
				(arc
					(start 183.946292 -206.685388)
					(mid 183.285892 -206.685388)
					(end 183.946292 -206.685388)
				)
			)
		)
	)
	(zone
		(layers "In1.Cu" "In2.Cu")
		(hatch none 0.5)
		(connect_pads
			(clearance 0)
		)
		(min_thickness 0.25)
		(keepout
			(tracks not_allowed)
			(vias allowed)
			(pads allowed)
			(copperpour not_allowed)
			(footprints allowed)
		)
		(placement
			(enabled no)
			(sheetname "")
		)
		(fill yes
			(thermal_gap 0.5)
			(thermal_bridge_width 0.5)
			(island_removal_mode 0)
		)
		(polygon
			(pts
				(arc
					(start 202.478132 -222.835216)
					(mid 201.817732 -222.835216)
					(end 202.478132 -222.835216)
				)
			)
		)
	)
	(zone
		(layers "In1.Cu" "In2.Cu")
		(hatch none 0.5)
		(connect_pads
			(clearance 0)
		)
		(min_thickness 0.25)
		(keepout
			(tracks not_allowed)
			(vias allowed)
			(pads allowed)
			(copperpour not_allowed)
			(footprints allowed)
		)
		(placement
			(enabled no)
			(sheetname "")
		)
		(fill yes
			(thermal_gap 0.5)
			(thermal_bridge_width 0.5)
			(island_removal_mode 0)
		)
		(polygon
			(pts
				(arc
					(start 277.522432 -210.935062)
					(mid 276.862032 -210.935062)
					(end 277.522432 -210.935062)
				)
			)
		)
	)
	(zone
		(layers "In1.Cu" "In2.Cu")
		(hatch none 0.5)
		(connect_pads
			(clearance 0)
		)
		(min_thickness 0.25)
		(keepout
			(tracks not_allowed)
			(vias allowed)
			(pads allowed)
			(copperpour not_allowed)
			(footprints allowed)
		)
		(placement
			(enabled no)
			(sheetname "")
		)
		(fill yes
			(thermal_gap 0.5)
			(thermal_bridge_width 0.5)
			(island_removal_mode 0)
		)
		(polygon
			(pts
				(arc
					(start 194.934332 -310.385206)
					(mid 194.273932 -310.385206)
					(end 194.934332 -310.385206)
				)
			)
		)
	)
	(zone
		(layers "In1.Cu" "In2.Cu")
		(hatch none 0.5)
		(connect_pads
			(clearance 0)
		)
		(min_thickness 0.25)
		(keepout
			(tracks not_allowed)
			(vias allowed)
			(pads allowed)
			(copperpour not_allowed)
			(footprints allowed)
		)
		(placement
			(enabled no)
			(sheetname "")
		)
		(fill yes
			(thermal_gap 0.5)
			(thermal_bridge_width 0.5)
			(island_removal_mode 0)
		)
		(polygon
			(pts
				(arc
					(start 199.0344 -244.085364)
					(mid 198.374 -244.085364)
					(end 199.0344 -244.085364)
				)
			)
		)
	)
	(zone
		(layers "In1.Cu" "In2.Cu")
		(hatch none 0.5)
		(connect_pads
			(clearance 0)
		)
		(min_thickness 0.25)
		(keepout
			(tracks not_allowed)
			(vias allowed)
			(pads allowed)
			(copperpour not_allowed)
			(footprints allowed)
		)
		(placement
			(enabled no)
			(sheetname "")
		)
		(fill yes
			(thermal_gap 0.5)
			(thermal_bridge_width 0.5)
			(island_removal_mode 0)
		)
		(polygon
			(pts
				(arc
					(start 439.430414 -210.085178)
					(mid 438.770014 -210.085178)
					(end 439.430414 -210.085178)
				)
			)
		)
	)
	(zone
		(layers "In1.Cu" "In2.Cu")
		(hatch none 0.5)
		(connect_pads
			(clearance 0)
		)
		(min_thickness 0.25)
		(keepout
			(tracks not_allowed)
			(vias allowed)
			(pads allowed)
			(copperpour not_allowed)
			(footprints allowed)
		)
		(placement
			(enabled no)
			(sheetname "")
		)
		(fill yes
			(thermal_gap 0.5)
			(thermal_bridge_width 0.5)
			(island_removal_mode 0)
		)
		(polygon
			(pts
				(arc
					(start 292.610286 -295.085008)
					(mid 291.949886 -295.085008)
					(end 292.610286 -295.085008)
				)
			)
		)
	)
	(zone
		(layers "In1.Cu" "In2.Cu")
		(hatch none 0.5)
		(connect_pads
			(clearance 0)
		)
		(min_thickness 0.25)
		(keepout
			(tracks not_allowed)
			(vias allowed)
			(pads allowed)
			(copperpour not_allowed)
			(footprints allowed)
		)
		(placement
			(enabled no)
			(sheetname "")
		)
		(fill yes
			(thermal_gap 0.5)
			(thermal_bridge_width 0.5)
			(island_removal_mode 0)
		)
		(polygon
			(pts
				(arc
					(start 202.478132 -204.135228)
					(mid 201.817732 -204.135228)
					(end 202.478132 -204.135228)
				)
			)
		)
	)
	(zone
		(layers "In1.Cu" "In2.Cu")
		(hatch none 0.5)
		(connect_pads
			(clearance 0)
		)
		(min_thickness 0.25)
		(keepout
			(tracks not_allowed)
			(vias allowed)
			(pads allowed)
			(copperpour not_allowed)
			(footprints allowed)
		)
		(placement
			(enabled no)
			(sheetname "")
		)
		(fill yes
			(thermal_gap 0.5)
			(thermal_bridge_width 0.5)
			(island_removal_mode 0)
		)
		(polygon
			(pts
				(arc
					(start 22.03831 -229.635304)
					(mid 21.37791 -229.635304)
					(end 22.03831 -229.635304)
				)
			)
		)
	)
	(zone
		(layers "In1.Cu" "In2.Cu")
		(hatch none 0.5)
		(connect_pads
			(clearance 0)
		)
		(min_thickness 0.25)
		(keepout
			(tracks not_allowed)
			(vias allowed)
			(pads allowed)
			(copperpour not_allowed)
			(footprints allowed)
		)
		(placement
			(enabled no)
			(sheetname "")
		)
		(fill yes
			(thermal_gap 0.5)
			(thermal_bridge_width 0.5)
			(island_removal_mode 0)
		)
		(polygon
			(pts
				(arc
					(start 176.402238 -301.88535)
					(mid 175.741838 -301.88535)
					(end 176.402238 -301.88535)
				)
			)
		)
	)
	(zone
		(layers "In1.Cu" "In2.Cu")
		(hatch none 0.5)
		(connect_pads
			(clearance 0)
		)
		(min_thickness 0.25)
		(keepout
			(tracks not_allowed)
			(vias allowed)
			(pads allowed)
			(copperpour not_allowed)
			(footprints allowed)
		)
		(placement
			(enabled no)
			(sheetname "")
		)
		(fill yes
			(thermal_gap 0.5)
			(thermal_bridge_width 0.5)
			(island_removal_mode 0)
		)
		(polygon
			(pts
				(arc
					(start 431.88636 -200.735184)
					(mid 431.22596 -200.735184)
					(end 431.88636 -200.735184)
				)
			)
		)
	)
	(zone
		(layers "In1.Cu" "In2.Cu")
		(hatch none 0.5)
		(connect_pads
			(clearance 0)
		)
		(min_thickness 0.25)
		(keepout
			(tracks not_allowed)
			(vias allowed)
			(pads allowed)
			(copperpour not_allowed)
			(footprints allowed)
		)
		(placement
			(enabled no)
			(sheetname "")
		)
		(fill yes
			(thermal_gap 0.5)
			(thermal_bridge_width 0.5)
			(island_removal_mode 0)
		)
		(polygon
			(pts
				(arc
					(start 442.8744 -295.935146)
					(mid 442.214 -295.935146)
					(end 442.8744 -295.935146)
				)
			)
		)
	)
	(zone
		(layers "In1.Cu" "In2.Cu")
		(hatch none 0.5)
		(connect_pads
			(clearance 0)
		)
		(min_thickness 0.25)
		(keepout
			(tracks not_allowed)
			(vias allowed)
			(pads allowed)
			(copperpour not_allowed)
			(footprints allowed)
		)
		(placement
			(enabled no)
			(sheetname "")
		)
		(fill yes
			(thermal_gap 0.5)
			(thermal_bridge_width 0.5)
			(island_removal_mode 0)
		)
		(polygon
			(pts
				(arc
					(start 22.03831 -201.585322)
					(mid 21.37791 -201.585322)
					(end 22.03831 -201.585322)
				)
			)
		)
	)
	(zone
		(layers "In1.Cu" "In2.Cu")
		(hatch none 0.5)
		(connect_pads
			(clearance 0)
		)
		(min_thickness 0.25)
		(keepout
			(tracks not_allowed)
			(vias allowed)
			(pads allowed)
			(copperpour not_allowed)
			(footprints allowed)
		)
		(placement
			(enabled no)
			(sheetname "")
		)
		(fill yes
			(thermal_gap 0.5)
			(thermal_bridge_width 0.5)
			(island_removal_mode 0)
		)
		(polygon
			(pts
				(arc
					(start 273.422364 -226.235006)
					(mid 272.761964 -226.235006)
					(end 273.422364 -226.235006)
				)
			)
		)
	)
	(zone
		(layers "In1.Cu" "In2.Cu")
		(hatch none 0.5)
		(connect_pads
			(clearance 0)
		)
		(min_thickness 0.25)
		(keepout
			(tracks not_allowed)
			(vias allowed)
			(pads allowed)
			(copperpour not_allowed)
			(footprints allowed)
		)
		(placement
			(enabled no)
			(sheetname "")
		)
		(fill yes
			(thermal_gap 0.5)
			(thermal_bridge_width 0.5)
			(island_removal_mode 0)
		)
		(polygon
			(pts
				(arc
					(start 454.518268 -242.385088)
					(mid 453.857868 -242.385088)
					(end 454.518268 -242.385088)
				)
			)
		)
	)
	(zone
		(layers "In1.Cu" "In2.Cu")
		(hatch none 0.5)
		(connect_pads
			(clearance 0)
		)
		(min_thickness 0.25)
		(keepout
			(tracks not_allowed)
			(vias allowed)
			(pads allowed)
			(copperpour not_allowed)
			(footprints allowed)
		)
		(placement
			(enabled no)
			(sheetname "")
		)
		(fill yes
			(thermal_gap 0.5)
			(thermal_bridge_width 0.5)
			(island_removal_mode 0)
		)
		(polygon
			(pts
				(arc
					(start 191.490346 -221.985332)
					(mid 190.829946 -221.985332)
					(end 191.490346 -221.985332)
				)
			)
		)
	)
	(zone
		(layers "In1.Cu" "In2.Cu")
		(hatch none 0.5)
		(connect_pads
			(clearance 0)
		)
		(min_thickness 0.25)
		(keepout
			(tracks not_allowed)
			(vias allowed)
			(pads allowed)
			(copperpour not_allowed)
			(footprints allowed)
		)
		(placement
			(enabled no)
			(sheetname "")
		)
		(fill yes
			(thermal_gap 0.5)
			(thermal_bridge_width 0.5)
			(island_removal_mode 0)
		)
		(polygon
			(pts
				(arc
					(start 439.430414 -292.535102)
					(mid 438.770014 -292.535102)
					(end 439.430414 -292.535102)
				)
			)
		)
	)
	(zone
		(layers "In1.Cu" "In2.Cu")
		(hatch none 0.5)
		(connect_pads
			(clearance 0)
		)
		(min_thickness 0.25)
		(keepout
			(tracks not_allowed)
			(vias allowed)
			(pads allowed)
			(copperpour not_allowed)
			(footprints allowed)
		)
		(placement
			(enabled no)
			(sheetname "")
		)
		(fill yes
			(thermal_gap 0.5)
			(thermal_bridge_width 0.5)
			(island_removal_mode 0)
		)
		(polygon
			(pts
				(arc
					(start 22.03831 -254.285242)
					(mid 21.37791 -254.285242)
					(end 22.03831 -254.285242)
				)
			)
		)
	)
	(zone
		(layers "In1.Cu" "In2.Cu")
		(hatch none 0.5)
		(connect_pads
			(clearance 0)
		)
		(min_thickness 0.25)
		(keepout
			(tracks not_allowed)
			(vias allowed)
			(pads allowed)
			(copperpour not_allowed)
			(footprints allowed)
		)
		(placement
			(enabled no)
			(sheetname "")
		)
		(fill yes
			(thermal_gap 0.5)
			(thermal_bridge_width 0.5)
			(island_removal_mode 0)
		)
		(polygon
			(pts
				(arc
					(start 450.4182 -254.284988)
					(mid 449.7578 -254.284988)
					(end 450.4182 -254.284988)
				)
			)
		)
	)
	(zone
		(layers "In1.Cu" "In2.Cu")
		(hatch none 0.5)
		(connect_pads
			(clearance 0)
		)
		(min_thickness 0.25)
		(keepout
			(tracks not_allowed)
			(vias allowed)
			(pads allowed)
			(copperpour not_allowed)
			(footprints allowed)
		)
		(placement
			(enabled no)
			(sheetname "")
		)
		(fill yes
			(thermal_gap 0.5)
			(thermal_bridge_width 0.5)
			(island_removal_mode 0)
		)
		(polygon
			(pts
				(arc
					(start 237.158784 -53.672994)
					(mid 237.212666 -53.695312)
					(end 237.234984 -53.749194)
				)
				(arc
					(start 237.234984 -54.780942)
					(mid 237.212666 -54.834824)
					(end 237.158784 -54.857142)
				)
				(arc
					(start 236.041184 -54.857142)
					(mid 235.987302 -54.834824)
					(end 235.964984 -54.780942)
				)
				(arc
					(start 235.964984 -53.749194)
					(mid 235.987302 -53.695312)
					(end 236.041184 -53.672994)
				)
			)
		)
	)
	(zone
		(layers "In1.Cu" "In2.Cu")
		(hatch none 0.5)
		(connect_pads
			(clearance 0)
		)
		(min_thickness 0.25)
		(keepout
			(tracks not_allowed)
			(vias allowed)
			(pads allowed)
			(copperpour not_allowed)
			(footprints allowed)
		)
		(placement
			(enabled no)
			(sheetname "")
		)
		(fill yes
			(thermal_gap 0.5)
			(thermal_bridge_width 0.5)
			(island_removal_mode 0)
		)
		(polygon
			(pts
				(arc
					(start 17.938242 -221.135194)
					(mid 17.277842 -221.135194)
					(end 17.938242 -221.135194)
				)
			)
		)
	)
	(zone
		(layers "In1.Cu" "In2.Cu")
		(hatch none 0.5)
		(connect_pads
			(clearance 0)
		)
		(min_thickness 0.25)
		(keepout
			(tracks not_allowed)
			(vias allowed)
			(pads allowed)
			(copperpour not_allowed)
			(footprints allowed)
		)
		(placement
			(enabled no)
			(sheetname "")
		)
		(fill yes
			(thermal_gap 0.5)
			(thermal_bridge_width 0.5)
			(island_removal_mode 0)
		)
		(polygon
			(pts
				(arc
					(start 17.938242 -280.635202)
					(mid 17.277842 -280.635202)
					(end 17.938242 -280.635202)
				)
			)
		)
	)
	(zone
		(layers "In1.Cu" "In2.Cu")
		(hatch none 0.5)
		(connect_pads
			(clearance 0)
		)
		(min_thickness 0.25)
		(keepout
			(tracks not_allowed)
			(vias allowed)
			(pads allowed)
			(copperpour not_allowed)
			(footprints allowed)
		)
		(placement
			(enabled no)
			(sheetname "")
		)
		(fill yes
			(thermal_gap 0.5)
			(thermal_bridge_width 0.5)
			(island_removal_mode 0)
		)
		(polygon
			(pts
				(arc
					(start 387.305042 -381.824484)
					(mid 387.324966 -381.83372)
					(end 387.346698 -381.83693)
				)
				(arc
					(start 387.541262 -381.83693)
					(mid 387.595144 -381.814612)
					(end 387.617462 -381.76073)
				)
				(arc
					(start 387.617462 -381.07493)
					(mid 387.595144 -381.021048)
					(end 387.541262 -380.99873)
				)
				(arc
					(start 387.346698 -380.99873)
					(mid 387.324954 -381.001898)
					(end 387.305042 -381.011176)
				)
				(arc
					(start 387.008878 -381.203962)
					(mid 386.967194 -381.216184)
					(end 386.925566 -381.203708)
				)
				(arc
					(start 386.631942 -381.011176)
					(mid 386.612018 -381.00194)
					(end 386.590286 -380.99873)
				)
				(arc
					(start 386.395722 -380.99873)
					(mid 386.34184 -381.021048)
					(end 386.319522 -381.07493)
				)
				(arc
					(start 386.319522 -381.76073)
					(mid 386.34184 -381.814612)
					(end 386.395722 -381.83693)
				)
				(arc
					(start 386.591556 -381.83693)
					(mid 386.6133 -381.833762)
					(end 386.633212 -381.824484)
				)
				(arc
					(start 386.926836 -381.631952)
					(mid 386.968492 -381.61955)
					(end 387.010148 -381.631952)
				)
			)
		)
	)
	(zone
		(layers "In1.Cu" "In2.Cu")
		(hatch none 0.5)
		(connect_pads
			(clearance 0)
		)
		(min_thickness 0.25)
		(keepout
			(tracks not_allowed)
			(vias allowed)
			(pads allowed)
			(copperpour not_allowed)
			(footprints allowed)
		)
		(placement
			(enabled no)
			(sheetname "")
		)
		(fill yes
			(thermal_gap 0.5)
			(thermal_bridge_width 0.5)
			(island_removal_mode 0)
		)
		(polygon
			(pts
				(arc
					(start 29.582364 -281.48534)
					(mid 28.921964 -281.48534)
					(end 29.582364 -281.48534)
				)
			)
		)
	)
	(zone
		(layers "In1.Cu" "In2.Cu")
		(hatch none 0.5)
		(connect_pads
			(clearance 0)
		)
		(min_thickness 0.25)
		(keepout
			(tracks not_allowed)
			(vias allowed)
			(pads allowed)
			(copperpour not_allowed)
			(footprints allowed)
		)
		(placement
			(enabled no)
			(sheetname "")
		)
		(fill yes
			(thermal_gap 0.5)
			(thermal_bridge_width 0.5)
			(island_removal_mode 0)
		)
		(polygon
			(pts
				(arc
					(start 48.114204 -308.685438)
					(mid 47.453804 -308.685438)
					(end 48.114204 -308.685438)
				)
			)
		)
	)
	(zone
		(layers "In1.Cu" "In2.Cu")
		(hatch none 0.5)
		(connect_pads
			(clearance 0)
		)
		(min_thickness 0.25)
		(keepout
			(tracks not_allowed)
			(vias allowed)
			(pads allowed)
			(copperpour not_allowed)
			(footprints allowed)
		)
		(placement
			(enabled no)
			(sheetname "")
		)
		(fill yes
			(thermal_gap 0.5)
			(thermal_bridge_width 0.5)
			(island_removal_mode 0)
		)
		(polygon
			(pts
				(arc
					(start 194.934332 -243.235226)
					(mid 194.273932 -243.235226)
					(end 194.934332 -243.235226)
				)
			)
		)
	)
	(zone
		(layers "In1.Cu" "In2.Cu")
		(hatch none 0.5)
		(connect_pads
			(clearance 0)
		)
		(min_thickness 0.25)
		(keepout
			(tracks not_allowed)
			(vias allowed)
			(pads allowed)
			(copperpour not_allowed)
			(footprints allowed)
		)
		(placement
			(enabled no)
			(sheetname "")
		)
		(fill yes
			(thermal_gap 0.5)
			(thermal_bridge_width 0.5)
			(island_removal_mode 0)
		)
		(polygon
			(pts
				(arc
					(start 40.57015 -221.135194)
					(mid 39.90975 -221.135194)
					(end 40.57015 -221.135194)
				)
			)
		)
	)
	(zone
		(layers "In1.Cu" "In2.Cu")
		(hatch none 0.5)
		(connect_pads
			(clearance 0)
		)
		(min_thickness 0.25)
		(keepout
			(tracks not_allowed)
			(vias allowed)
			(pads allowed)
			(copperpour not_allowed)
			(footprints allowed)
		)
		(placement
			(enabled no)
			(sheetname "")
		)
		(fill yes
			(thermal_gap 0.5)
			(thermal_bridge_width 0.5)
			(island_removal_mode 0)
		)
		(polygon
			(pts
				(arc
					(start 280.966164 -220.285056)
					(mid 280.305764 -220.285056)
					(end 280.966164 -220.285056)
				)
			)
		)
	)
	(zone
		(layers "In1.Cu" "In2.Cu")
		(hatch none 0.5)
		(connect_pads
			(clearance 0)
		)
		(min_thickness 0.25)
		(keepout
			(tracks not_allowed)
			(vias allowed)
			(pads allowed)
			(copperpour not_allowed)
			(footprints allowed)
		)
		(placement
			(enabled no)
			(sheetname "")
		)
		(fill yes
			(thermal_gap 0.5)
			(thermal_bridge_width 0.5)
			(island_removal_mode 0)
		)
		(polygon
			(pts
				(arc
					(start 269.978378 -311.23509)
					(mid 269.317978 -311.23509)
					(end 269.978378 -311.23509)
				)
			)
		)
	)
	(zone
		(layers "In1.Cu" "In2.Cu")
		(hatch none 0.5)
		(connect_pads
			(clearance 0)
		)
		(min_thickness 0.25)
		(keepout
			(tracks not_allowed)
			(vias allowed)
			(pads allowed)
			(copperpour not_allowed)
			(footprints allowed)
		)
		(placement
			(enabled no)
			(sheetname "")
		)
		(fill yes
			(thermal_gap 0.5)
			(thermal_bridge_width 0.5)
			(island_removal_mode 0)
		)
		(polygon
			(pts
				(arc
					(start 191.490346 -306.135278)
					(mid 190.829946 -306.135278)
					(end 191.490346 -306.135278)
				)
			)
		)
	)
	(zone
		(layers "In1.Cu" "In2.Cu")
		(hatch none 0.5)
		(connect_pads
			(clearance 0)
		)
		(min_thickness 0.25)
		(keepout
			(tracks not_allowed)
			(vias allowed)
			(pads allowed)
			(copperpour not_allowed)
			(footprints allowed)
		)
		(placement
			(enabled no)
			(sheetname "")
		)
		(fill yes
			(thermal_gap 0.5)
			(thermal_bridge_width 0.5)
			(island_removal_mode 0)
		)
		(polygon
			(pts
				(arc
					(start 101.862128 -380.265178)
					(mid 101.852892 -380.285102)
					(end 101.849682 -380.306834)
				)
				(arc
					(start 101.849682 -380.501398)
					(mid 101.872 -380.55528)
					(end 101.925882 -380.577598)
				)
				(arc
					(start 102.611682 -380.577598)
					(mid 102.665564 -380.55528)
					(end 102.687882 -380.501398)
				)
				(arc
					(start 102.687882 -380.306834)
					(mid 102.684714 -380.28509)
					(end 102.675436 -380.265178)
				)
				(arc
					(start 102.48265 -379.969014)
					(mid 102.470428 -379.92733)
					(end 102.482904 -379.885702)
				)
				(arc
					(start 102.675436 -379.592078)
					(mid 102.684672 -379.572154)
					(end 102.687882 -379.550422)
				)
				(arc
					(start 102.687882 -379.355858)
					(mid 102.665564 -379.301976)
					(end 102.611682 -379.279658)
				)
				(arc
					(start 101.925882 -379.279658)
					(mid 101.872 -379.301976)
					(end 101.849682 -379.355858)
				)
				(arc
					(start 101.849682 -379.551692)
					(mid 101.85285 -379.573436)
					(end 101.862128 -379.593348)
				)
				(arc
					(start 102.05466 -379.886972)
					(mid 102.067062 -379.928628)
					(end 102.05466 -379.970284)
				)
			)
		)
	)
	(zone
		(layers "In1.Cu" "In2.Cu")
		(hatch none 0.5)
		(connect_pads
			(clearance 0)
		)
		(min_thickness 0.25)
		(keepout
			(tracks not_allowed)
			(vias allowed)
			(pads allowed)
			(copperpour not_allowed)
			(footprints allowed)
		)
		(placement
			(enabled no)
			(sheetname "")
		)
		(fill yes
			(thermal_gap 0.5)
			(thermal_bridge_width 0.5)
			(island_removal_mode 0)
		)
		(polygon
			(pts
				(arc
					(start 280.966164 -288.285174)
					(mid 280.305764 -288.285174)
					(end 280.966164 -288.285174)
				)
			)
		)
	)
	(zone
		(layers "In1.Cu" "In2.Cu")
		(hatch none 0.5)
		(connect_pads
			(clearance 0)
		)
		(min_thickness 0.25)
		(keepout
			(tracks not_allowed)
			(vias allowed)
			(pads allowed)
			(copperpour not_allowed)
			(footprints allowed)
		)
		(placement
			(enabled no)
			(sheetname "")
		)
		(fill yes
			(thermal_gap 0.5)
			(thermal_bridge_width 0.5)
			(island_removal_mode 0)
		)
		(polygon
			(pts
				(arc
					(start 202.478132 -233.885232)
					(mid 201.817732 -233.885232)
					(end 202.478132 -233.885232)
				)
			)
		)
	)
	(zone
		(layers "In1.Cu" "In2.Cu")
		(hatch none 0.5)
		(connect_pads
			(clearance 0)
		)
		(min_thickness 0.25)
		(keepout
			(tracks not_allowed)
			(vias allowed)
			(pads allowed)
			(copperpour not_allowed)
			(footprints allowed)
		)
		(placement
			(enabled no)
			(sheetname "")
		)
		(fill yes
			(thermal_gap 0.5)
			(thermal_bridge_width 0.5)
			(island_removal_mode 0)
		)
		(polygon
			(pts
				(arc
					(start 285.066232 -245.785132)
					(mid 284.405832 -245.785132)
					(end 285.066232 -245.785132)
				)
			)
		)
	)
	(zone
		(layers "In1.Cu" "In2.Cu")
		(hatch none 0.5)
		(connect_pads
			(clearance 0)
		)
		(min_thickness 0.25)
		(keepout
			(tracks not_allowed)
			(vias allowed)
			(pads allowed)
			(copperpour not_allowed)
			(footprints allowed)
		)
		(placement
			(enabled no)
			(sheetname "")
		)
		(fill yes
			(thermal_gap 0.5)
			(thermal_bridge_width 0.5)
			(island_removal_mode 0)
		)
		(polygon
			(pts
				(arc
					(start 420.242238 -253.435104)
					(mid 419.581838 -253.435104)
					(end 420.242238 -253.435104)
				)
			)
		)
	)
	(zone
		(layers "In1.Cu" "In2.Cu")
		(hatch none 0.5)
		(connect_pads
			(clearance 0)
		)
		(min_thickness 0.25)
		(keepout
			(tracks not_allowed)
			(vias allowed)
			(pads allowed)
			(copperpour not_allowed)
			(footprints allowed)
		)
		(placement
			(enabled no)
			(sheetname "")
		)
		(fill yes
			(thermal_gap 0.5)
			(thermal_bridge_width 0.5)
			(island_removal_mode 0)
		)
		(polygon
			(pts
				(arc
					(start 280.966164 -253.435104)
					(mid 280.305764 -253.435104)
					(end 280.966164 -253.435104)
				)
			)
		)
	)
	(zone
		(layers "In1.Cu" "In2.Cu")
		(hatch none 0.5)
		(connect_pads
			(clearance 0)
		)
		(min_thickness 0.25)
		(keepout
			(tracks not_allowed)
			(vias allowed)
			(pads allowed)
			(copperpour not_allowed)
			(footprints allowed)
		)
		(placement
			(enabled no)
			(sheetname "")
		)
		(fill yes
			(thermal_gap 0.5)
			(thermal_bridge_width 0.5)
			(island_removal_mode 0)
		)
		(polygon
			(pts
				(arc
					(start 300.15434 -279.785064)
					(mid 299.49394 -279.785064)
					(end 300.15434 -279.785064)
				)
			)
		)
	)
	(zone
		(layers "In1.Cu" "In2.Cu")
		(hatch none 0.5)
		(connect_pads
			(clearance 0)
		)
		(min_thickness 0.25)
		(keepout
			(tracks not_allowed)
			(vias allowed)
			(pads allowed)
			(copperpour not_allowed)
			(footprints allowed)
		)
		(placement
			(enabled no)
			(sheetname "")
		)
		(fill yes
			(thermal_gap 0.5)
			(thermal_bridge_width 0.5)
			(island_removal_mode 0)
		)
		(polygon
			(pts
				(arc
					(start 300.15434 -289.135058)
					(mid 299.49394 -289.135058)
					(end 300.15434 -289.135058)
				)
			)
		)
	)
	(zone
		(layers "In1.Cu" "In2.Cu")
		(hatch none 0.5)
		(connect_pads
			(clearance 0)
		)
		(min_thickness 0.25)
		(keepout
			(tracks not_allowed)
			(vias allowed)
			(pads allowed)
			(copperpour not_allowed)
			(footprints allowed)
		)
		(placement
			(enabled no)
			(sheetname "")
		)
		(fill yes
			(thermal_gap 0.5)
			(thermal_bridge_width 0.5)
			(island_removal_mode 0)
		)
		(polygon
			(pts
				(arc
					(start 187.390278 -250.035314)
					(mid 186.729878 -250.035314)
					(end 187.390278 -250.035314)
				)
			)
		)
	)
	(zone
		(layers "In1.Cu" "In2.Cu")
		(hatch none 0.5)
		(connect_pads
			(clearance 0)
		)
		(min_thickness 0.25)
		(keepout
			(tracks not_allowed)
			(vias allowed)
			(pads allowed)
			(copperpour not_allowed)
			(footprints allowed)
		)
		(placement
			(enabled no)
			(sheetname "")
		)
		(fill yes
			(thermal_gap 0.5)
			(thermal_bridge_width 0.5)
			(island_removal_mode 0)
		)
		(polygon
			(pts
				(arc
					(start 29.582364 -221.985332)
					(mid 28.921964 -221.985332)
					(end 29.582364 -221.985332)
				)
			)
		)
	)
	(zone
		(layers "In1.Cu" "In2.Cu")
		(hatch none 0.5)
		(connect_pads
			(clearance 0)
		)
		(min_thickness 0.25)
		(keepout
			(tracks not_allowed)
			(vias allowed)
			(pads allowed)
			(copperpour not_allowed)
			(footprints allowed)
		)
		(placement
			(enabled no)
			(sheetname "")
		)
		(fill yes
			(thermal_gap 0.5)
			(thermal_bridge_width 0.5)
			(island_removal_mode 0)
		)
		(polygon
			(pts
				(arc
					(start 439.430414 -214.335106)
					(mid 438.770014 -214.335106)
					(end 439.430414 -214.335106)
				)
			)
		)
	)
	(zone
		(layers "In1.Cu" "In2.Cu")
		(hatch none 0.5)
		(connect_pads
			(clearance 0)
		)
		(min_thickness 0.25)
		(keepout
			(tracks not_allowed)
			(vias allowed)
			(pads allowed)
			(copperpour not_allowed)
			(footprints allowed)
		)
		(placement
			(enabled no)
			(sheetname "")
		)
		(fill yes
			(thermal_gap 0.5)
			(thermal_bridge_width 0.5)
			(island_removal_mode 0)
		)
		(polygon
			(pts
				(arc
					(start 97.981008 -292.411404)
					(mid 97.676208 -292.716204)
					(end 97.981008 -293.021004)
				)
				(arc
					(start 98.921062 -293.021004)
					(mid 99.225862 -292.716204)
					(end 98.921062 -292.411404)
				)
			)
		)
	)
	(zone
		(layers "In1.Cu" "In2.Cu")
		(hatch none 0.5)
		(connect_pads
			(clearance 0)
		)
		(min_thickness 0.25)
		(keepout
			(tracks not_allowed)
			(vias allowed)
			(pads allowed)
			(copperpour not_allowed)
			(footprints allowed)
		)
		(placement
			(enabled no)
			(sheetname "")
		)
		(fill yes
			(thermal_gap 0.5)
			(thermal_bridge_width 0.5)
			(island_removal_mode 0)
		)
		(polygon
			(pts
				(arc
					(start 292.610286 -229.63505)
					(mid 291.949886 -229.63505)
					(end 292.610286 -229.63505)
				)
			)
		)
	)
	(zone
		(layers "In1.Cu" "In2.Cu")
		(hatch none 0.5)
		(connect_pads
			(clearance 0)
		)
		(min_thickness 0.25)
		(keepout
			(tracks not_allowed)
			(vias allowed)
			(pads allowed)
			(copperpour not_allowed)
			(footprints allowed)
		)
		(placement
			(enabled no)
			(sheetname "")
		)
		(fill yes
			(thermal_gap 0.5)
			(thermal_bridge_width 0.5)
			(island_removal_mode 0)
		)
		(polygon
			(pts
				(arc
					(start 194.934332 -218.585288)
					(mid 194.273932 -218.585288)
					(end 194.934332 -218.585288)
				)
			)
		)
	)
	(zone
		(layers "In1.Cu" "In2.Cu")
		(hatch none 0.5)
		(connect_pads
			(clearance 0)
		)
		(min_thickness 0.25)
		(keepout
			(tracks not_allowed)
			(vias allowed)
			(pads allowed)
			(copperpour not_allowed)
			(footprints allowed)
		)
		(placement
			(enabled no)
			(sheetname "")
		)
		(fill yes
			(thermal_gap 0.5)
			(thermal_bridge_width 0.5)
			(island_removal_mode 0)
		)
		(polygon
			(pts
				(arc
					(start 450.4182 -318.035178)
					(mid 449.7578 -318.035178)
					(end 450.4182 -318.035178)
				)
			)
		)
	)
	(zone
		(layers "In1.Cu" "In2.Cu")
		(hatch none 0.5)
		(connect_pads
			(clearance 0)
		)
		(min_thickness 0.25)
		(keepout
			(tracks not_allowed)
			(vias allowed)
			(pads allowed)
			(copperpour not_allowed)
			(footprints allowed)
		)
		(placement
			(enabled no)
			(sheetname "")
		)
		(fill yes
			(thermal_gap 0.5)
			(thermal_bridge_width 0.5)
			(island_removal_mode 0)
		)
		(polygon
			(pts
				(arc
					(start 93.525594 -408.860244)
					(mid 93.547912 -408.914126)
					(end 93.601794 -408.936444)
				)
				(arc
					(start 93.797374 -408.936444)
					(mid 93.81925 -408.933312)
					(end 93.839284 -408.923998)
				)
				(arc
					(start 94.132908 -408.731466)
					(mid 94.174564 -408.719064)
					(end 94.21622 -408.731466)
				)
				(arc
					(start 94.511114 -408.923998)
					(mid 94.531038 -408.933234)
					(end 94.55277 -408.936444)
				)
				(arc
					(start 94.747334 -408.936444)
					(mid 94.801216 -408.914126)
					(end 94.823534 -408.860244)
				)
				(arc
					(start 94.823534 -408.174444)
					(mid 94.801216 -408.120562)
					(end 94.747334 -408.098244)
				)
				(arc
					(start 94.55277 -408.098244)
					(mid 94.531026 -408.101412)
					(end 94.511114 -408.11069)
				)
				(arc
					(start 94.21495 -408.303476)
					(mid 94.173266 -408.315698)
					(end 94.131638 -408.303222)
				)
				(arc
					(start 93.838014 -408.11069)
					(mid 93.81809 -408.101454)
					(end 93.796358 -408.098244)
				)
				(arc
					(start 93.601794 -408.098244)
					(mid 93.547912 -408.120562)
					(end 93.525594 -408.174444)
				)
			)
		)
	)
	(zone
		(layers "In1.Cu" "In2.Cu")
		(hatch none 0.5)
		(connect_pads
			(clearance 0)
		)
		(min_thickness 0.25)
		(keepout
			(tracks not_allowed)
			(vias allowed)
			(pads allowed)
			(copperpour not_allowed)
			(footprints allowed)
		)
		(placement
			(enabled no)
			(sheetname "")
		)
		(fill yes
			(thermal_gap 0.5)
			(thermal_bridge_width 0.5)
			(island_removal_mode 0)
		)
		(polygon
			(pts
				(arc
					(start 296.054272 -215.18499)
					(mid 295.393872 -215.18499)
					(end 296.054272 -215.18499)
				)
			)
		)
	)
	(zone
		(layers "In1.Cu" "In2.Cu")
		(hatch none 0.5)
		(connect_pads
			(clearance 0)
		)
		(min_thickness 0.25)
		(keepout
			(tracks not_allowed)
			(vias allowed)
			(pads allowed)
			(copperpour not_allowed)
			(footprints allowed)
		)
		(placement
			(enabled no)
			(sheetname "")
		)
		(fill yes
			(thermal_gap 0.5)
			(thermal_bridge_width 0.5)
			(island_removal_mode 0)
		)
		(polygon
			(pts
				(arc
					(start 424.342306 -236.435138)
					(mid 423.681906 -236.435138)
					(end 424.342306 -236.435138)
				)
			)
		)
	)
	(zone
		(layers "In1.Cu" "In2.Cu")
		(hatch none 0.5)
		(connect_pads
			(clearance 0)
		)
		(min_thickness 0.25)
		(keepout
			(tracks not_allowed)
			(vias allowed)
			(pads allowed)
			(copperpour not_allowed)
			(footprints allowed)
		)
		(placement
			(enabled no)
			(sheetname "")
		)
		(fill yes
			(thermal_gap 0.5)
			(thermal_bridge_width 0.5)
			(island_removal_mode 0)
		)
		(polygon
			(pts
				(arc
					(start 450.4182 -233.884978)
					(mid 449.7578 -233.884978)
					(end 450.4182 -233.884978)
				)
			)
		)
	)
	(zone
		(layers "In1.Cu" "In2.Cu")
		(hatch none 0.5)
		(connect_pads
			(clearance 0)
		)
		(min_thickness 0.25)
		(keepout
			(tracks not_allowed)
			(vias allowed)
			(pads allowed)
			(copperpour not_allowed)
			(footprints allowed)
		)
		(placement
			(enabled no)
			(sheetname "")
		)
		(fill yes
			(thermal_gap 0.5)
			(thermal_bridge_width 0.5)
			(island_removal_mode 0)
		)
		(polygon
			(pts
				(arc
					(start 277.522432 -301.885096)
					(mid 276.862032 -301.885096)
					(end 277.522432 -301.885096)
				)
			)
		)
	)
	(zone
		(layers "In1.Cu" "In2.Cu")
		(hatch none 0.5)
		(connect_pads
			(clearance 0)
		)
		(min_thickness 0.25)
		(keepout
			(tracks not_allowed)
			(vias allowed)
			(pads allowed)
			(copperpour not_allowed)
			(footprints allowed)
		)
		(placement
			(enabled no)
			(sheetname "")
		)
		(fill yes
			(thermal_gap 0.5)
			(thermal_bridge_width 0.5)
			(island_removal_mode 0)
		)
		(polygon
			(pts
				(arc
					(start 280.966164 -204.134974)
					(mid 280.305764 -204.134974)
					(end 280.966164 -204.134974)
				)
			)
		)
	)
	(zone
		(layers "In1.Cu" "In2.Cu")
		(hatch none 0.5)
		(connect_pads
			(clearance 0)
		)
		(min_thickness 0.25)
		(keepout
			(tracks not_allowed)
			(vias allowed)
			(pads allowed)
			(copperpour not_allowed)
			(footprints allowed)
		)
		(placement
			(enabled no)
			(sheetname "")
		)
		(fill yes
			(thermal_gap 0.5)
			(thermal_bridge_width 0.5)
			(island_removal_mode 0)
		)
		(polygon
			(pts
				(arc
					(start 172.30217 -280.635202)
					(mid 171.64177 -280.635202)
					(end 172.30217 -280.635202)
				)
			)
		)
	)
	(zone
		(layers "In1.Cu" "In2.Cu")
		(hatch none 0.5)
		(connect_pads
			(clearance 0)
		)
		(min_thickness 0.25)
		(keepout
			(tracks not_allowed)
			(vias allowed)
			(pads allowed)
			(copperpour not_allowed)
			(footprints allowed)
		)
		(placement
			(enabled no)
			(sheetname "")
		)
		(fill yes
			(thermal_gap 0.5)
			(thermal_bridge_width 0.5)
			(island_removal_mode 0)
		)
		(polygon
			(pts
				(arc
					(start 424.342306 -245.785132)
					(mid 423.681906 -245.785132)
					(end 424.342306 -245.785132)
				)
			)
		)
	)
	(zone
		(layers "In1.Cu" "In2.Cu")
		(hatch none 0.5)
		(connect_pads
			(clearance 0)
		)
		(min_thickness 0.25)
		(keepout
			(tracks not_allowed)
			(vias allowed)
			(pads allowed)
			(copperpour not_allowed)
			(footprints allowed)
		)
		(placement
			(enabled no)
			(sheetname "")
		)
		(fill yes
			(thermal_gap 0.5)
			(thermal_bridge_width 0.5)
			(island_removal_mode 0)
		)
		(polygon
			(pts
				(arc
					(start 292.610286 -311.23509)
					(mid 291.949886 -311.23509)
					(end 292.610286 -311.23509)
				)
			)
		)
	)
	(zone
		(layers "In1.Cu" "In2.Cu")
		(hatch none 0.5)
		(connect_pads
			(clearance 0)
		)
		(min_thickness 0.25)
		(keepout
			(tracks not_allowed)
			(vias allowed)
			(pads allowed)
			(copperpour not_allowed)
			(footprints allowed)
		)
		(placement
			(enabled no)
			(sheetname "")
		)
		(fill yes
			(thermal_gap 0.5)
			(thermal_bridge_width 0.5)
			(island_removal_mode 0)
		)
		(polygon
			(pts
				(arc
					(start 199.0344 -228.78542)
					(mid 198.374 -228.78542)
					(end 199.0344 -228.78542)
				)
			)
		)
	)
	(zone
		(layers "In1.Cu" "In2.Cu")
		(hatch none 0.5)
		(connect_pads
			(clearance 0)
		)
		(min_thickness 0.25)
		(keepout
			(tracks not_allowed)
			(vias allowed)
			(pads allowed)
			(copperpour not_allowed)
			(footprints allowed)
		)
		(placement
			(enabled no)
			(sheetname "")
		)
		(fill yes
			(thermal_gap 0.5)
			(thermal_bridge_width 0.5)
			(island_removal_mode 0)
		)
		(polygon
			(pts
				(arc
					(start 44.670218 -203.285344)
					(mid 44.009818 -203.285344)
					(end 44.670218 -203.285344)
				)
			)
		)
	)
	(zone
		(layers "In1.Cu" "In2.Cu")
		(hatch none 0.5)
		(connect_pads
			(clearance 0)
		)
		(min_thickness 0.25)
		(keepout
			(tracks not_allowed)
			(vias allowed)
			(pads allowed)
			(copperpour not_allowed)
			(footprints allowed)
		)
		(placement
			(enabled no)
			(sheetname "")
		)
		(fill yes
			(thermal_gap 0.5)
			(thermal_bridge_width 0.5)
			(island_removal_mode 0)
		)
		(polygon
			(pts
				(arc
					(start 446.974468 -309.535068)
					(mid 446.314068 -309.535068)
					(end 446.974468 -309.535068)
				)
			)
		)
	)
	(zone
		(layers "In1.Cu" "In2.Cu")
		(hatch none 0.5)
		(connect_pads
			(clearance 0)
		)
		(min_thickness 0.25)
		(keepout
			(tracks not_allowed)
			(vias allowed)
			(pads allowed)
			(copperpour not_allowed)
			(footprints allowed)
		)
		(placement
			(enabled no)
			(sheetname "")
		)
		(fill yes
			(thermal_gap 0.5)
			(thermal_bridge_width 0.5)
			(island_removal_mode 0)
		)
		(polygon
			(pts
				(arc
					(start 199.0344 -206.685388)
					(mid 198.374 -206.685388)
					(end 199.0344 -206.685388)
				)
			)
		)
	)
	(zone
		(layers "In1.Cu" "In2.Cu")
		(hatch none 0.5)
		(connect_pads
			(clearance 0)
		)
		(min_thickness 0.25)
		(keepout
			(tracks not_allowed)
			(vias allowed)
			(pads allowed)
			(copperpour not_allowed)
			(footprints allowed)
		)
		(placement
			(enabled no)
			(sheetname "")
		)
		(fill yes
			(thermal_gap 0.5)
			(thermal_bridge_width 0.5)
			(island_removal_mode 0)
		)
		(polygon
			(pts
				(arc
					(start 183.946292 -285.735268)
					(mid 183.285892 -285.735268)
					(end 183.946292 -285.735268)
				)
			)
		)
	)
	(zone
		(layers "In1.Cu" "In2.Cu")
		(hatch none 0.5)
		(connect_pads
			(clearance 0)
		)
		(min_thickness 0.25)
		(keepout
			(tracks not_allowed)
			(vias allowed)
			(pads allowed)
			(copperpour not_allowed)
			(footprints allowed)
		)
		(placement
			(enabled no)
			(sheetname "")
		)
		(fill yes
			(thermal_gap 0.5)
			(thermal_bridge_width 0.5)
			(island_removal_mode 0)
		)
		(polygon
			(pts
				(arc
					(start 450.4182 -267.035026)
					(mid 449.7578 -267.035026)
					(end 450.4182 -267.035026)
				)
			)
		)
	)
	(zone
		(layers "In1.Cu" "In2.Cu")
		(hatch none 0.5)
		(connect_pads
			(clearance 0)
		)
		(min_thickness 0.25)
		(keepout
			(tracks not_allowed)
			(vias allowed)
			(pads allowed)
			(copperpour not_allowed)
			(footprints allowed)
		)
		(placement
			(enabled no)
			(sheetname "")
		)
		(fill yes
			(thermal_gap 0.5)
			(thermal_bridge_width 0.5)
			(island_removal_mode 0)
		)
		(polygon
			(pts
				(arc
					(start 29.582364 -264.485374)
					(mid 28.921964 -264.485374)
					(end 29.582364 -264.485374)
				)
			)
		)
	)
	(zone
		(layers "In1.Cu" "In2.Cu")
		(hatch none 0.5)
		(connect_pads
			(clearance 0)
		)
		(min_thickness 0.25)
		(keepout
			(tracks not_allowed)
			(vias allowed)
			(pads allowed)
			(copperpour not_allowed)
			(footprints allowed)
		)
		(placement
			(enabled no)
			(sheetname "")
		)
		(fill yes
			(thermal_gap 0.5)
			(thermal_bridge_width 0.5)
			(island_removal_mode 0)
		)
		(polygon
			(pts
				(arc
					(start 454.518268 -279.785064)
					(mid 453.857868 -279.785064)
					(end 454.518268 -279.785064)
				)
			)
		)
	)
	(zone
		(layers "In1.Cu" "In2.Cu")
		(hatch none 0.5)
		(connect_pads
			(clearance 0)
		)
		(min_thickness 0.25)
		(keepout
			(tracks not_allowed)
			(vias allowed)
			(pads allowed)
			(copperpour not_allowed)
			(footprints allowed)
		)
		(placement
			(enabled no)
			(sheetname "")
		)
		(fill yes
			(thermal_gap 0.5)
			(thermal_bridge_width 0.5)
			(island_removal_mode 0)
		)
		(polygon
			(pts
				(arc
					(start 183.946292 -284.885384)
					(mid 183.285892 -284.885384)
					(end 183.946292 -284.885384)
				)
			)
		)
	)
	(zone
		(layers "In1.Cu" "In2.Cu")
		(hatch none 0.5)
		(connect_pads
			(clearance 0)
		)
		(min_thickness 0.25)
		(keepout
			(tracks not_allowed)
			(vias allowed)
			(pads allowed)
			(copperpour not_allowed)
			(footprints allowed)
		)
		(placement
			(enabled no)
			(sheetname "")
		)
		(fill yes
			(thermal_gap 0.5)
			(thermal_bridge_width 0.5)
			(island_removal_mode 0)
		)
		(polygon
			(pts
				(arc
					(start 199.0344 -312.935366)
					(mid 198.374 -312.935366)
					(end 199.0344 -312.935366)
				)
			)
		)
	)
	(zone
		(layers "In1.Cu" "In2.Cu")
		(hatch none 0.5)
		(connect_pads
			(clearance 0)
		)
		(min_thickness 0.25)
		(keepout
			(tracks not_allowed)
			(vias allowed)
			(pads allowed)
			(copperpour not_allowed)
			(footprints allowed)
		)
		(placement
			(enabled no)
			(sheetname "")
		)
		(fill yes
			(thermal_gap 0.5)
			(thermal_bridge_width 0.5)
			(island_removal_mode 0)
		)
		(polygon
			(pts
				(arc
					(start 37.126164 -295.085262)
					(mid 36.465764 -295.085262)
					(end 37.126164 -295.085262)
				)
			)
		)
	)
	(zone
		(layers "In1.Cu" "In2.Cu")
		(hatch none 0.5)
		(connect_pads
			(clearance 0)
		)
		(min_thickness 0.25)
		(keepout
			(tracks not_allowed)
			(vias allowed)
			(pads allowed)
			(copperpour not_allowed)
			(footprints allowed)
		)
		(placement
			(enabled no)
			(sheetname "")
		)
		(fill yes
			(thermal_gap 0.5)
			(thermal_bridge_width 0.5)
			(island_removal_mode 0)
		)
		(polygon
			(pts
				(arc
					(start 202.478132 -243.235226)
					(mid 201.817732 -243.235226)
					(end 202.478132 -243.235226)
				)
			)
		)
	)
	(zone
		(layers "In1.Cu" "In2.Cu")
		(hatch none 0.5)
		(connect_pads
			(clearance 0)
		)
		(min_thickness 0.25)
		(keepout
			(tracks not_allowed)
			(vias allowed)
			(pads allowed)
			(copperpour not_allowed)
			(footprints allowed)
		)
		(placement
			(enabled no)
			(sheetname "")
		)
		(fill yes
			(thermal_gap 0.5)
			(thermal_bridge_width 0.5)
			(island_removal_mode 0)
		)
		(polygon
			(pts
				(arc
					(start 202.478132 -276.385274)
					(mid 201.817732 -276.385274)
					(end 202.478132 -276.385274)
				)
			)
		)
	)
	(zone
		(layers "In1.Cu" "In2.Cu")
		(hatch none 0.5)
		(connect_pads
			(clearance 0)
		)
		(min_thickness 0.25)
		(keepout
			(tracks not_allowed)
			(vias allowed)
			(pads allowed)
			(copperpour not_allowed)
			(footprints allowed)
		)
		(placement
			(enabled no)
			(sheetname "")
		)
		(fill yes
			(thermal_gap 0.5)
			(thermal_bridge_width 0.5)
			(island_removal_mode 0)
		)
		(polygon
			(pts
				(arc
					(start 183.946292 -300.185328)
					(mid 183.285892 -300.185328)
					(end 183.946292 -300.185328)
				)
			)
		)
	)
	(zone
		(layers "In1.Cu" "In2.Cu")
		(hatch none 0.5)
		(connect_pads
			(clearance 0)
		)
		(min_thickness 0.25)
		(keepout
			(tracks not_allowed)
			(vias allowed)
			(pads allowed)
			(copperpour not_allowed)
			(footprints allowed)
		)
		(placement
			(enabled no)
			(sheetname "")
		)
		(fill yes
			(thermal_gap 0.5)
			(thermal_bridge_width 0.5)
			(island_removal_mode 0)
		)
		(polygon
			(pts
				(arc
					(start 424.342306 -204.985112)
					(mid 423.681906 -204.985112)
					(end 424.342306 -204.985112)
				)
			)
		)
	)
	(zone
		(layers "In1.Cu" "In2.Cu")
		(hatch none 0.5)
		(connect_pads
			(clearance 0)
		)
		(min_thickness 0.25)
		(keepout
			(tracks not_allowed)
			(vias allowed)
			(pads allowed)
			(copperpour not_allowed)
			(footprints allowed)
		)
		(placement
			(enabled no)
			(sheetname "")
		)
		(fill yes
			(thermal_gap 0.5)
			(thermal_bridge_width 0.5)
			(island_removal_mode 0)
		)
		(polygon
			(pts
				(arc
					(start 29.582364 -197.335394)
					(mid 28.921964 -197.335394)
					(end 29.582364 -197.335394)
				)
			)
		)
	)
	(zone
		(layers "In1.Cu" "In2.Cu")
		(hatch none 0.5)
		(connect_pads
			(clearance 0)
		)
		(min_thickness 0.25)
		(keepout
			(tracks not_allowed)
			(vias allowed)
			(pads allowed)
			(copperpour not_allowed)
			(footprints allowed)
		)
		(placement
			(enabled no)
			(sheetname "")
		)
		(fill yes
			(thermal_gap 0.5)
			(thermal_bridge_width 0.5)
			(island_removal_mode 0)
		)
		(polygon
			(pts
				(arc
					(start 431.88636 -264.48512)
					(mid 431.22596 -264.48512)
					(end 431.88636 -264.48512)
				)
			)
		)
	)
	(zone
		(layers "In1.Cu" "In2.Cu")
		(hatch none 0.5)
		(connect_pads
			(clearance 0)
		)
		(min_thickness 0.25)
		(keepout
			(tracks not_allowed)
			(vias allowed)
			(pads allowed)
			(copperpour not_allowed)
			(footprints allowed)
		)
		(placement
			(enabled no)
			(sheetname "")
		)
		(fill yes
			(thermal_gap 0.5)
			(thermal_bridge_width 0.5)
			(island_removal_mode 0)
		)
		(polygon
			(pts
				(arc
					(start 454.518268 -281.485086)
					(mid 453.857868 -281.485086)
					(end 454.518268 -281.485086)
				)
			)
		)
	)
	(zone
		(layers "In1.Cu" "In2.Cu")
		(hatch none 0.5)
		(connect_pads
			(clearance 0)
		)
		(min_thickness 0.25)
		(keepout
			(tracks not_allowed)
			(vias allowed)
			(pads allowed)
			(copperpour not_allowed)
			(footprints allowed)
		)
		(placement
			(enabled no)
			(sheetname "")
		)
		(fill yes
			(thermal_gap 0.5)
			(thermal_bridge_width 0.5)
			(island_removal_mode 0)
		)
		(polygon
			(pts
				(arc
					(start 179.846224 -263.635236)
					(mid 179.185824 -263.635236)
					(end 179.846224 -263.635236)
				)
			)
		)
	)
	(zone
		(layers "In1.Cu" "In2.Cu")
		(hatch none 0.5)
		(connect_pads
			(clearance 0)
		)
		(min_thickness 0.25)
		(keepout
			(tracks not_allowed)
			(vias allowed)
			(pads allowed)
			(copperpour not_allowed)
			(footprints allowed)
		)
		(placement
			(enabled no)
			(sheetname "")
		)
		(fill yes
			(thermal_gap 0.5)
			(thermal_bridge_width 0.5)
			(island_removal_mode 0)
		)
		(polygon
			(pts
				(arc
					(start 131.852416 -12.952222)
					(mid 131.874734 -12.89834)
					(end 131.928616 -12.876022)
				)
				(arc
					(start 132.96519 -12.876022)
					(mid 133.019072 -12.89834)
					(end 133.04139 -12.952222)
				)
				(arc
					(start 133.04139 -14.351762)
					(mid 133.019072 -14.405644)
					(end 132.96519 -14.427962)
				)
				(arc
					(start 131.928616 -14.427962)
					(mid 131.874734 -14.405644)
					(end 131.852416 -14.351762)
				)
			)
		)
	)
	(zone
		(layers "In1.Cu" "In2.Cu")
		(hatch none 0.5)
		(connect_pads
			(clearance 0)
		)
		(min_thickness 0.25)
		(keepout
			(tracks not_allowed)
			(vias allowed)
			(pads allowed)
			(copperpour not_allowed)
			(footprints allowed)
		)
		(placement
			(enabled no)
			(sheetname "")
		)
		(fill yes
			(thermal_gap 0.5)
			(thermal_bridge_width 0.5)
			(island_removal_mode 0)
		)
		(polygon
			(pts
				(arc
					(start 454.518268 -206.685134)
					(mid 453.857868 -206.685134)
					(end 454.518268 -206.685134)
				)
			)
		)
	)
	(zone
		(layers "In1.Cu" "In2.Cu")
		(hatch none 0.5)
		(connect_pads
			(clearance 0)
		)
		(min_thickness 0.25)
		(keepout
			(tracks not_allowed)
			(vias allowed)
			(pads allowed)
			(copperpour not_allowed)
			(footprints allowed)
		)
		(placement
			(enabled no)
			(sheetname "")
		)
		(fill yes
			(thermal_gap 0.5)
			(thermal_bridge_width 0.5)
			(island_removal_mode 0)
		)
		(polygon
			(pts
				(arc
					(start 25.482296 -243.235226)
					(mid 24.821896 -243.235226)
					(end 25.482296 -243.235226)
				)
			)
		)
	)
	(zone
		(layers "In1.Cu" "In2.Cu")
		(hatch none 0.5)
		(connect_pads
			(clearance 0)
		)
		(min_thickness 0.25)
		(keepout
			(tracks not_allowed)
			(vias allowed)
			(pads allowed)
			(copperpour not_allowed)
			(footprints allowed)
		)
		(placement
			(enabled no)
			(sheetname "")
		)
		(fill yes
			(thermal_gap 0.5)
			(thermal_bridge_width 0.5)
			(island_removal_mode 0)
		)
		(polygon
			(pts
				(arc
					(start 194.934332 -224.535238)
					(mid 194.273932 -224.535238)
					(end 194.934332 -224.535238)
				)
			)
		)
	)
	(zone
		(layers "In1.Cu" "In2.Cu")
		(hatch none 0.5)
		(connect_pads
			(clearance 0)
		)
		(min_thickness 0.25)
		(keepout
			(tracks not_allowed)
			(vias allowed)
			(pads allowed)
			(copperpour not_allowed)
			(footprints allowed)
		)
		(placement
			(enabled no)
			(sheetname "")
		)
		(fill yes
			(thermal_gap 0.5)
			(thermal_bridge_width 0.5)
			(island_removal_mode 0)
		)
		(polygon
			(pts
				(arc
					(start 115.988846 -375.906284)
					(mid 116.00877 -375.91552)
					(end 116.030502 -375.91873)
				)
				(arc
					(start 116.225066 -375.91873)
					(mid 116.278948 -375.896412)
					(end 116.301266 -375.84253)
				)
				(arc
					(start 116.301266 -375.15673)
					(mid 116.278948 -375.102848)
					(end 116.225066 -375.08053)
				)
				(arc
					(start 116.030502 -375.08053)
					(mid 116.008758 -375.083698)
					(end 115.988846 -375.092976)
				)
				(arc
					(start 115.692682 -375.285762)
					(mid 115.650998 -375.297984)
					(end 115.60937 -375.285508)
				)
				(arc
					(start 115.315746 -375.092976)
					(mid 115.295822 -375.08374)
					(end 115.27409 -375.08053)
				)
				(arc
					(start 115.079526 -375.08053)
					(mid 115.025644 -375.102848)
					(end 115.003326 -375.15673)
				)
				(arc
					(start 115.003326 -375.84253)
					(mid 115.025644 -375.896412)
					(end 115.079526 -375.91873)
				)
				(arc
					(start 115.27536 -375.91873)
					(mid 115.297104 -375.915562)
					(end 115.317016 -375.906284)
				)
				(arc
					(start 115.61064 -375.713752)
					(mid 115.652296 -375.70135)
					(end 115.693952 -375.713752)
				)
			)
		)
	)
	(zone
		(layers "In1.Cu" "In2.Cu")
		(hatch none 0.5)
		(connect_pads
			(clearance 0)
		)
		(min_thickness 0.25)
		(keepout
			(tracks not_allowed)
			(vias allowed)
			(pads allowed)
			(copperpour not_allowed)
			(footprints allowed)
		)
		(placement
			(enabled no)
			(sheetname "")
		)
		(fill yes
			(thermal_gap 0.5)
			(thermal_bridge_width 0.5)
			(island_removal_mode 0)
		)
		(polygon
			(pts
				(arc
					(start 277.522432 -242.385088)
					(mid 276.862032 -242.385088)
					(end 277.522432 -242.385088)
				)
			)
		)
	)
	(zone
		(layers "In1.Cu" "In2.Cu")
		(hatch none 0.5)
		(connect_pads
			(clearance 0)
		)
		(min_thickness 0.25)
		(keepout
			(tracks not_allowed)
			(vias allowed)
			(pads allowed)
			(copperpour not_allowed)
			(footprints allowed)
		)
		(placement
			(enabled no)
			(sheetname "")
		)
		(fill yes
			(thermal_gap 0.5)
			(thermal_bridge_width 0.5)
			(island_removal_mode 0)
		)
		(polygon
			(pts
				(arc
					(start 191.490346 -204.985366)
					(mid 190.829946 -204.985366)
					(end 191.490346 -204.985366)
				)
			)
		)
	)
	(zone
		(layers "In1.Cu" "In2.Cu")
		(hatch none 0.5)
		(connect_pads
			(clearance 0)
		)
		(min_thickness 0.25)
		(keepout
			(tracks not_allowed)
			(vias allowed)
			(pads allowed)
			(copperpour not_allowed)
			(footprints allowed)
		)
		(placement
			(enabled no)
			(sheetname "")
		)
		(fill yes
			(thermal_gap 0.5)
			(thermal_bridge_width 0.5)
			(island_removal_mode 0)
		)
		(polygon
			(pts
				(arc
					(start 22.03831 -197.335394)
					(mid 21.37791 -197.335394)
					(end 22.03831 -197.335394)
				)
			)
		)
	)
	(zone
		(layers "In1.Cu" "In2.Cu")
		(hatch none 0.5)
		(connect_pads
			(clearance 0)
		)
		(min_thickness 0.25)
		(keepout
			(tracks not_allowed)
			(vias allowed)
			(pads allowed)
			(copperpour not_allowed)
			(footprints allowed)
		)
		(placement
			(enabled no)
			(sheetname "")
		)
		(fill yes
			(thermal_gap 0.5)
			(thermal_bridge_width 0.5)
			(island_removal_mode 0)
		)
		(polygon
			(pts
				(arc
					(start 199.0344 -269.58544)
					(mid 198.374 -269.58544)
					(end 199.0344 -269.58544)
				)
			)
		)
	)
	(zone
		(layers "In1.Cu" "In2.Cu")
		(hatch none 0.5)
		(connect_pads
			(clearance 0)
		)
		(min_thickness 0.25)
		(keepout
			(tracks not_allowed)
			(vias allowed)
			(pads allowed)
			(copperpour not_allowed)
			(footprints allowed)
		)
		(placement
			(enabled no)
			(sheetname "")
		)
		(fill yes
			(thermal_gap 0.5)
			(thermal_bridge_width 0.5)
			(island_removal_mode 0)
		)
		(polygon
			(pts
				(arc
					(start 29.582364 -249.18543)
					(mid 28.921964 -249.18543)
					(end 29.582364 -249.18543)
				)
			)
		)
	)
	(zone
		(layers "In1.Cu" "In2.Cu")
		(hatch none 0.5)
		(connect_pads
			(clearance 0)
		)
		(min_thickness 0.25)
		(keepout
			(tracks not_allowed)
			(vias allowed)
			(pads allowed)
			(copperpour not_allowed)
			(footprints allowed)
		)
		(placement
			(enabled no)
			(sheetname "")
		)
		(fill yes
			(thermal_gap 0.5)
			(thermal_bridge_width 0.5)
			(island_removal_mode 0)
		)
		(polygon
			(pts
				(arc
					(start 108.094018 -31.669736)
					(mid 108.108897 -31.633815)
					(end 108.144818 -31.618936)
				)
				(arc
					(start 108.652818 -31.618936)
					(mid 108.688739 -31.633815)
					(end 108.703618 -31.669736)
				)
				(arc
					(start 108.703618 -32.326072)
					(mid 108.688739 -32.361993)
					(end 108.652818 -32.376872)
				)
				(arc
					(start 108.144818 -32.376872)
					(mid 108.108897 -32.361993)
					(end 108.094018 -32.326072)
				)
			)
		)
	)
	(zone
		(layers "In1.Cu" "In2.Cu")
		(hatch none 0.5)
		(connect_pads
			(clearance 0)
		)
		(min_thickness 0.25)
		(keepout
			(tracks not_allowed)
			(vias allowed)
			(pads allowed)
			(copperpour not_allowed)
			(footprints allowed)
		)
		(placement
			(enabled no)
			(sheetname "")
		)
		(fill yes
			(thermal_gap 0.5)
			(thermal_bridge_width 0.5)
			(island_removal_mode 0)
		)
		(polygon
			(pts
				(arc
					(start 394.541502 -11.91768)
					(mid 394.519184 -11.971562)
					(end 394.465302 -11.99388)
				)
				(arc
					(start 393.428728 -11.99388)
					(mid 393.374846 -11.971562)
					(end 393.352528 -11.91768)
				)
				(arc
					(start 393.352528 -10.51814)
					(mid 393.374846 -10.464258)
					(end 393.428728 -10.44194)
				)
				(arc
					(start 394.465302 -10.44194)
					(mid 394.519184 -10.464258)
					(end 394.541502 -10.51814)
				)
			)
		)
	)
	(zone
		(layers "In1.Cu" "In2.Cu")
		(hatch none 0.5)
		(connect_pads
			(clearance 0)
		)
		(min_thickness 0.25)
		(keepout
			(tracks not_allowed)
			(vias allowed)
			(pads allowed)
			(copperpour not_allowed)
			(footprints allowed)
		)
		(placement
			(enabled no)
			(sheetname "")
		)
		(fill yes
			(thermal_gap 0.5)
			(thermal_bridge_width 0.5)
			(island_removal_mode 0)
		)
		(polygon
			(pts
				(arc
					(start 273.422364 -297.635168)
					(mid 272.761964 -297.635168)
					(end 273.422364 -297.635168)
				)
			)
		)
	)
	(zone
		(layers "In1.Cu" "In2.Cu")
		(hatch none 0.5)
		(connect_pads
			(clearance 0)
		)
		(min_thickness 0.25)
		(keepout
			(tracks not_allowed)
			(vias allowed)
			(pads allowed)
			(copperpour not_allowed)
			(footprints allowed)
		)
		(placement
			(enabled no)
			(sheetname "")
		)
		(fill yes
			(thermal_gap 0.5)
			(thermal_bridge_width 0.5)
			(island_removal_mode 0)
		)
		(polygon
			(pts
				(arc
					(start 418.061394 -16.443198)
					(mid 418.083712 -16.49708)
					(end 418.137594 -16.519398)
				)
				(arc
					(start 418.333174 -16.519398)
					(mid 418.35505 -16.516266)
					(end 418.375084 -16.506952)
				)
				(arc
					(start 418.668708 -16.31442)
					(mid 418.710364 -16.302018)
					(end 418.75202 -16.31442)
				)
				(arc
					(start 419.046914 -16.506952)
					(mid 419.066838 -16.516188)
					(end 419.08857 -16.519398)
				)
				(arc
					(start 419.283134 -16.519398)
					(mid 419.337016 -16.49708)
					(end 419.359334 -16.443198)
				)
				(arc
					(start 419.359334 -15.757398)
					(mid 419.337016 -15.703516)
					(end 419.283134 -15.681198)
				)
				(arc
					(start 419.08857 -15.681198)
					(mid 419.066826 -15.684366)
					(end 419.046914 -15.693644)
				)
				(arc
					(start 418.75075 -15.88643)
					(mid 418.709066 -15.898652)
					(end 418.667438 -15.886176)
				)
				(arc
					(start 418.373814 -15.693644)
					(mid 418.35389 -15.684408)
					(end 418.332158 -15.681198)
				)
				(arc
					(start 418.137594 -15.681198)
					(mid 418.083712 -15.703516)
					(end 418.061394 -15.757398)
				)
			)
		)
	)
	(zone
		(layers "In1.Cu" "In2.Cu")
		(hatch none 0.5)
		(connect_pads
			(clearance 0)
		)
		(min_thickness 0.25)
		(keepout
			(tracks not_allowed)
			(vias allowed)
			(pads allowed)
			(copperpour not_allowed)
			(footprints allowed)
		)
		(placement
			(enabled no)
			(sheetname "")
		)
		(fill yes
			(thermal_gap 0.5)
			(thermal_bridge_width 0.5)
			(island_removal_mode 0)
		)
		(polygon
			(pts
				(arc
					(start 442.8744 -301.034958)
					(mid 442.214 -301.034958)
					(end 442.8744 -301.034958)
				)
			)
		)
	)
	(zone
		(layers "In1.Cu" "In2.Cu")
		(hatch none 0.5)
		(connect_pads
			(clearance 0)
		)
		(min_thickness 0.25)
		(keepout
			(tracks not_allowed)
			(vias allowed)
			(pads allowed)
			(copperpour not_allowed)
			(footprints allowed)
		)
		(placement
			(enabled no)
			(sheetname "")
		)
		(fill yes
			(thermal_gap 0.5)
			(thermal_bridge_width 0.5)
			(island_removal_mode 0)
		)
		(polygon
			(pts
				(arc
					(start 277.522432 -261.085076)
					(mid 276.862032 -261.085076)
					(end 277.522432 -261.085076)
				)
			)
		)
	)
	(zone
		(layers "In1.Cu" "In2.Cu")
		(hatch none 0.5)
		(connect_pads
			(clearance 0)
		)
		(min_thickness 0.25)
		(keepout
			(tracks not_allowed)
			(vias allowed)
			(pads allowed)
			(copperpour not_allowed)
			(footprints allowed)
		)
		(placement
			(enabled no)
			(sheetname "")
		)
		(fill yes
			(thermal_gap 0.5)
			(thermal_bridge_width 0.5)
			(island_removal_mode 0)
		)
		(polygon
			(pts
				(arc
					(start 22.03831 -231.335326)
					(mid 21.37791 -231.335326)
					(end 22.03831 -231.335326)
				)
			)
		)
	)
	(zone
		(layers "In1.Cu" "In2.Cu")
		(hatch none 0.5)
		(connect_pads
			(clearance 0)
		)
		(min_thickness 0.25)
		(keepout
			(tracks not_allowed)
			(vias allowed)
			(pads allowed)
			(copperpour not_allowed)
			(footprints allowed)
		)
		(placement
			(enabled no)
			(sheetname "")
		)
		(fill yes
			(thermal_gap 0.5)
			(thermal_bridge_width 0.5)
			(island_removal_mode 0)
		)
		(polygon
			(pts
				(arc
					(start 139.182856 -408.860244)
					(mid 139.205174 -408.914126)
					(end 139.259056 -408.936444)
				)
				(arc
					(start 139.454636 -408.936444)
					(mid 139.476512 -408.933312)
					(end 139.496546 -408.923998)
				)
				(arc
					(start 139.79017 -408.731466)
					(mid 139.831826 -408.719064)
					(end 139.873482 -408.731466)
				)
				(arc
					(start 140.168376 -408.923998)
					(mid 140.1883 -408.933234)
					(end 140.210032 -408.936444)
				)
				(arc
					(start 140.404596 -408.936444)
					(mid 140.458478 -408.914126)
					(end 140.480796 -408.860244)
				)
				(arc
					(start 140.480796 -408.174444)
					(mid 140.458478 -408.120562)
					(end 140.404596 -408.098244)
				)
				(arc
					(start 140.210032 -408.098244)
					(mid 140.188288 -408.101412)
					(end 140.168376 -408.11069)
				)
				(arc
					(start 139.872212 -408.303476)
					(mid 139.830528 -408.315698)
					(end 139.7889 -408.303222)
				)
				(arc
					(start 139.495276 -408.11069)
					(mid 139.475352 -408.101454)
					(end 139.45362 -408.098244)
				)
				(arc
					(start 139.259056 -408.098244)
					(mid 139.205174 -408.120562)
					(end 139.182856 -408.174444)
				)
			)
		)
	)
	(zone
		(layers "In1.Cu" "In2.Cu")
		(hatch none 0.5)
		(connect_pads
			(clearance 0)
		)
		(min_thickness 0.25)
		(keepout
			(tracks not_allowed)
			(vias allowed)
			(pads allowed)
			(copperpour not_allowed)
			(footprints allowed)
		)
		(placement
			(enabled no)
			(sheetname "")
		)
		(fill yes
			(thermal_gap 0.5)
			(thermal_bridge_width 0.5)
			(island_removal_mode 0)
		)
		(polygon
			(pts
				(arc
					(start 37.126164 -240.68532)
					(mid 36.465764 -240.68532)
					(end 37.126164 -240.68532)
				)
			)
		)
	)
	(zone
		(layers "In1.Cu" "In2.Cu")
		(hatch none 0.5)
		(connect_pads
			(clearance 0)
		)
		(min_thickness 0.25)
		(keepout
			(tracks not_allowed)
			(vias allowed)
			(pads allowed)
			(copperpour not_allowed)
			(footprints allowed)
		)
		(placement
			(enabled no)
			(sheetname "")
		)
		(fill yes
			(thermal_gap 0.5)
			(thermal_bridge_width 0.5)
			(island_removal_mode 0)
		)
		(polygon
			(pts
				(arc
					(start 33.026096 -248.335292)
					(mid 32.365696 -248.335292)
					(end 33.026096 -248.335292)
				)
			)
		)
	)
	(zone
		(layers "In1.Cu" "In2.Cu")
		(hatch none 0.5)
		(connect_pads
			(clearance 0)
		)
		(min_thickness 0.25)
		(keepout
			(tracks not_allowed)
			(vias allowed)
			(pads allowed)
			(copperpour not_allowed)
			(footprints allowed)
		)
		(placement
			(enabled no)
			(sheetname "")
		)
		(fill yes
			(thermal_gap 0.5)
			(thermal_bridge_width 0.5)
			(island_removal_mode 0)
		)
		(polygon
			(pts
				(arc
					(start 48.114204 -229.635304)
					(mid 47.453804 -229.635304)
					(end 48.114204 -229.635304)
				)
			)
		)
	)
	(zone
		(layers "In1.Cu" "In2.Cu")
		(hatch none 0.5)
		(connect_pads
			(clearance 0)
		)
		(min_thickness 0.25)
		(keepout
			(tracks not_allowed)
			(vias allowed)
			(pads allowed)
			(copperpour not_allowed)
			(footprints allowed)
		)
		(placement
			(enabled no)
			(sheetname "")
		)
		(fill yes
			(thermal_gap 0.5)
			(thermal_bridge_width 0.5)
			(island_removal_mode 0)
		)
		(polygon
			(pts
				(arc
					(start 277.522432 -223.6851)
					(mid 276.862032 -223.6851)
					(end 277.522432 -223.6851)
				)
			)
		)
	)
	(zone
		(layers "In1.Cu" "In2.Cu")
		(hatch none 0.5)
		(connect_pads
			(clearance 0)
		)
		(min_thickness 0.25)
		(keepout
			(tracks not_allowed)
			(vias allowed)
			(pads allowed)
			(copperpour not_allowed)
			(footprints allowed)
		)
		(placement
			(enabled no)
			(sheetname "")
		)
		(fill yes
			(thermal_gap 0.5)
			(thermal_bridge_width 0.5)
			(island_removal_mode 0)
		)
		(polygon
			(pts
				(arc
					(start 52.214272 -279.785318)
					(mid 51.553872 -279.785318)
					(end 52.214272 -279.785318)
				)
			)
		)
	)
	(zone
		(layers "In1.Cu" "In2.Cu")
		(hatch none 0.5)
		(connect_pads
			(clearance 0)
		)
		(min_thickness 0.25)
		(keepout
			(tracks not_allowed)
			(vias allowed)
			(pads allowed)
			(copperpour not_allowed)
			(footprints allowed)
		)
		(placement
			(enabled no)
			(sheetname "")
		)
		(fill yes
			(thermal_gap 0.5)
			(thermal_bridge_width 0.5)
			(island_removal_mode 0)
		)
		(polygon
			(pts
				(arc
					(start 439.430414 -254.284988)
					(mid 438.770014 -254.284988)
					(end 439.430414 -254.284988)
				)
			)
		)
	)
	(zone
		(layers "In1.Cu" "In2.Cu")
		(hatch none 0.5)
		(connect_pads
			(clearance 0)
		)
		(min_thickness 0.25)
		(keepout
			(tracks not_allowed)
			(vias allowed)
			(pads allowed)
			(copperpour not_allowed)
			(footprints allowed)
		)
		(placement
			(enabled no)
			(sheetname "")
		)
		(fill yes
			(thermal_gap 0.5)
			(thermal_bridge_width 0.5)
			(island_removal_mode 0)
		)
		(polygon
			(pts
				(arc
					(start 22.03831 -279.785318)
					(mid 21.37791 -279.785318)
					(end 22.03831 -279.785318)
				)
			)
		)
	)
	(zone
		(layers "In1.Cu" "In2.Cu")
		(hatch none 0.5)
		(connect_pads
			(clearance 0)
		)
		(min_thickness 0.25)
		(keepout
			(tracks not_allowed)
			(vias allowed)
			(pads allowed)
			(copperpour not_allowed)
			(footprints allowed)
		)
		(placement
			(enabled no)
			(sheetname "")
		)
		(fill yes
			(thermal_gap 0.5)
			(thermal_bridge_width 0.5)
			(island_removal_mode 0)
		)
		(polygon
			(pts
				(arc
					(start 191.490346 -276.385274)
					(mid 190.829946 -276.385274)
					(end 191.490346 -276.385274)
				)
			)
		)
	)
	(zone
		(layers "In1.Cu" "In2.Cu")
		(hatch none 0.5)
		(connect_pads
			(clearance 0)
		)
		(min_thickness 0.25)
		(keepout
			(tracks not_allowed)
			(vias allowed)
			(pads allowed)
			(copperpour not_allowed)
			(footprints allowed)
		)
		(placement
			(enabled no)
			(sheetname "")
		)
		(fill yes
			(thermal_gap 0.5)
			(thermal_bridge_width 0.5)
			(island_removal_mode 0)
		)
		(polygon
			(pts
				(arc
					(start 172.30217 -243.235226)
					(mid 171.64177 -243.235226)
					(end 172.30217 -243.235226)
				)
			)
		)
	)
	(zone
		(layers "In1.Cu" "In2.Cu")
		(hatch none 0.5)
		(connect_pads
			(clearance 0)
		)
		(min_thickness 0.25)
		(keepout
			(tracks not_allowed)
			(vias allowed)
			(pads allowed)
			(copperpour not_allowed)
			(footprints allowed)
		)
		(placement
			(enabled no)
			(sheetname "")
		)
		(fill yes
			(thermal_gap 0.5)
			(thermal_bridge_width 0.5)
			(island_removal_mode 0)
		)
		(polygon
			(pts
				(arc
					(start 269.978378 -223.6851)
					(mid 269.317978 -223.6851)
					(end 269.978378 -223.6851)
				)
			)
		)
	)
	(zone
		(layers "In1.Cu" "In2.Cu")
		(hatch none 0.5)
		(connect_pads
			(clearance 0)
		)
		(min_thickness 0.25)
		(keepout
			(tracks not_allowed)
			(vias allowed)
			(pads allowed)
			(copperpour not_allowed)
			(footprints allowed)
		)
		(placement
			(enabled no)
			(sheetname "")
		)
		(fill yes
			(thermal_gap 0.5)
			(thermal_bridge_width 0.5)
			(island_removal_mode 0)
		)
		(polygon
			(pts
				(arc
					(start 431.88636 -238.985044)
					(mid 431.22596 -238.985044)
					(end 431.88636 -238.985044)
				)
			)
		)
	)
	(zone
		(layers "In1.Cu" "In2.Cu")
		(hatch none 0.5)
		(connect_pads
			(clearance 0)
		)
		(min_thickness 0.25)
		(keepout
			(tracks not_allowed)
			(vias allowed)
			(pads allowed)
			(copperpour not_allowed)
			(footprints allowed)
		)
		(placement
			(enabled no)
			(sheetname "")
		)
		(fill yes
			(thermal_gap 0.5)
			(thermal_bridge_width 0.5)
			(island_removal_mode 0)
		)
		(polygon
			(pts
				(arc
					(start 129.603246 -375.906284)
					(mid 129.62317 -375.91552)
					(end 129.644902 -375.91873)
				)
				(arc
					(start 129.839466 -375.91873)
					(mid 129.893348 -375.896412)
					(end 129.915666 -375.84253)
				)
				(arc
					(start 129.915666 -375.15673)
					(mid 129.893348 -375.102848)
					(end 129.839466 -375.08053)
				)
				(arc
					(start 129.644902 -375.08053)
					(mid 129.623158 -375.083698)
					(end 129.603246 -375.092976)
				)
				(arc
					(start 129.307082 -375.285762)
					(mid 129.265398 -375.297984)
					(end 129.22377 -375.285508)
				)
				(arc
					(start 128.930146 -375.092976)
					(mid 128.910222 -375.08374)
					(end 128.88849 -375.08053)
				)
				(arc
					(start 128.693926 -375.08053)
					(mid 128.640044 -375.102848)
					(end 128.617726 -375.15673)
				)
				(arc
					(start 128.617726 -375.84253)
					(mid 128.640044 -375.896412)
					(end 128.693926 -375.91873)
				)
				(arc
					(start 128.88976 -375.91873)
					(mid 128.911504 -375.915562)
					(end 128.931416 -375.906284)
				)
				(arc
					(start 129.22504 -375.713752)
					(mid 129.266696 -375.70135)
					(end 129.308352 -375.713752)
				)
			)
		)
	)
	(zone
		(layers "In1.Cu" "In2.Cu")
		(hatch none 0.5)
		(connect_pads
			(clearance 0)
		)
		(min_thickness 0.25)
		(keepout
			(tracks not_allowed)
			(vias allowed)
			(pads allowed)
			(copperpour not_allowed)
			(footprints allowed)
		)
		(placement
			(enabled no)
			(sheetname "")
		)
		(fill yes
			(thermal_gap 0.5)
			(thermal_bridge_width 0.5)
			(island_removal_mode 0)
		)
		(polygon
			(pts
				(arc
					(start 48.114204 -313.78525)
					(mid 47.453804 -313.78525)
					(end 48.114204 -313.78525)
				)
			)
		)
	)
	(zone
		(layers "In1.Cu" "In2.Cu")
		(hatch none 0.5)
		(connect_pads
			(clearance 0)
		)
		(min_thickness 0.25)
		(keepout
			(tracks not_allowed)
			(vias allowed)
			(pads allowed)
			(copperpour not_allowed)
			(footprints allowed)
		)
		(placement
			(enabled no)
			(sheetname "")
		)
		(fill yes
			(thermal_gap 0.5)
			(thermal_bridge_width 0.5)
			(island_removal_mode 0)
		)
		(polygon
			(pts
				(arc
					(start 292.610286 -290.83508)
					(mid 291.949886 -290.83508)
					(end 292.610286 -290.83508)
				)
			)
		)
	)
	(zone
		(layers "In1.Cu" "In2.Cu")
		(hatch none 0.5)
		(connect_pads
			(clearance 0)
		)
		(min_thickness 0.25)
		(keepout
			(tracks not_allowed)
			(vias allowed)
			(pads allowed)
			(copperpour not_allowed)
			(footprints allowed)
		)
		(placement
			(enabled no)
			(sheetname "")
		)
		(fill yes
			(thermal_gap 0.5)
			(thermal_bridge_width 0.5)
			(island_removal_mode 0)
		)
		(polygon
			(pts
				(arc
					(start 300.15434 -206.685134)
					(mid 299.49394 -206.685134)
					(end 300.15434 -206.685134)
				)
			)
		)
	)
	(zone
		(layers "In1.Cu" "In2.Cu")
		(hatch none 0.5)
		(connect_pads
			(clearance 0)
		)
		(min_thickness 0.25)
		(keepout
			(tracks not_allowed)
			(vias allowed)
			(pads allowed)
			(copperpour not_allowed)
			(footprints allowed)
		)
		(placement
			(enabled no)
			(sheetname "")
		)
		(fill yes
			(thermal_gap 0.5)
			(thermal_bridge_width 0.5)
			(island_removal_mode 0)
		)
		(polygon
			(pts
				(arc
					(start 269.978378 -287.435036)
					(mid 269.317978 -287.435036)
					(end 269.978378 -287.435036)
				)
			)
		)
	)
	(zone
		(layers "In1.Cu" "In2.Cu")
		(hatch none 0.5)
		(connect_pads
			(clearance 0)
		)
		(min_thickness 0.25)
		(keepout
			(tracks not_allowed)
			(vias allowed)
			(pads allowed)
			(copperpour not_allowed)
			(footprints allowed)
		)
		(placement
			(enabled no)
			(sheetname "")
		)
		(fill yes
			(thermal_gap 0.5)
			(thermal_bridge_width 0.5)
			(island_removal_mode 0)
		)
		(polygon
			(pts
				(arc
					(start 454.518268 -216.035128)
					(mid 453.857868 -216.035128)
					(end 454.518268 -216.035128)
				)
			)
		)
	)
	(zone
		(layers "In1.Cu" "In2.Cu")
		(hatch none 0.5)
		(connect_pads
			(clearance 0)
		)
		(min_thickness 0.25)
		(keepout
			(tracks not_allowed)
			(vias allowed)
			(pads allowed)
			(copperpour not_allowed)
			(footprints allowed)
		)
		(placement
			(enabled no)
			(sheetname "")
		)
		(fill yes
			(thermal_gap 0.5)
			(thermal_bridge_width 0.5)
			(island_removal_mode 0)
		)
		(polygon
			(pts
				(arc
					(start 37.126164 -231.335326)
					(mid 36.465764 -231.335326)
					(end 37.126164 -231.335326)
				)
			)
		)
	)
	(zone
		(layers "In1.Cu" "In2.Cu")
		(hatch none 0.5)
		(connect_pads
			(clearance 0)
		)
		(min_thickness 0.25)
		(keepout
			(tracks not_allowed)
			(vias allowed)
			(pads allowed)
			(copperpour not_allowed)
			(footprints allowed)
		)
		(placement
			(enabled no)
			(sheetname "")
		)
		(fill yes
			(thermal_gap 0.5)
			(thermal_bridge_width 0.5)
			(island_removal_mode 0)
		)
		(polygon
			(pts
				(arc
					(start 191.490346 -238.135414)
					(mid 190.829946 -238.135414)
					(end 191.490346 -238.135414)
				)
			)
		)
	)
	(zone
		(layers "In1.Cu" "In2.Cu")
		(hatch none 0.5)
		(connect_pads
			(clearance 0)
		)
		(min_thickness 0.25)
		(keepout
			(tracks not_allowed)
			(vias allowed)
			(pads allowed)
			(copperpour not_allowed)
			(footprints allowed)
		)
		(placement
			(enabled no)
			(sheetname "")
		)
		(fill yes
			(thermal_gap 0.5)
			(thermal_bridge_width 0.5)
			(island_removal_mode 0)
		)
		(polygon
			(pts
				(arc
					(start 194.934332 -250.035314)
					(mid 194.273932 -250.035314)
					(end 194.934332 -250.035314)
				)
			)
		)
	)
	(zone
		(layers "In1.Cu" "In2.Cu")
		(hatch none 0.5)
		(connect_pads
			(clearance 0)
		)
		(min_thickness 0.25)
		(keepout
			(tracks not_allowed)
			(vias allowed)
			(pads allowed)
			(copperpour not_allowed)
			(footprints allowed)
		)
		(placement
			(enabled no)
			(sheetname "")
		)
		(fill yes
			(thermal_gap 0.5)
			(thermal_bridge_width 0.5)
			(island_removal_mode 0)
		)
		(polygon
			(pts
				(arc
					(start 273.422364 -199.885046)
					(mid 272.761964 -199.885046)
					(end 273.422364 -199.885046)
				)
			)
		)
	)
	(zone
		(layers "In1.Cu" "In2.Cu")
		(hatch none 0.5)
		(connect_pads
			(clearance 0)
		)
		(min_thickness 0.25)
		(keepout
			(tracks not_allowed)
			(vias allowed)
			(pads allowed)
			(copperpour not_allowed)
			(footprints allowed)
		)
		(placement
			(enabled no)
			(sheetname "")
		)
		(fill yes
			(thermal_gap 0.5)
			(thermal_bridge_width 0.5)
			(island_removal_mode 0)
		)
		(polygon
			(pts
				(arc
					(start 442.8744 -213.484968)
					(mid 442.214 -213.484968)
					(end 442.8744 -213.484968)
				)
			)
		)
	)
	(zone
		(layers "In1.Cu" "In2.Cu")
		(hatch none 0.5)
		(connect_pads
			(clearance 0)
		)
		(min_thickness 0.25)
		(keepout
			(tracks not_allowed)
			(vias allowed)
			(pads allowed)
			(copperpour not_allowed)
			(footprints allowed)
		)
		(placement
			(enabled no)
			(sheetname "")
		)
		(fill yes
			(thermal_gap 0.5)
			(thermal_bridge_width 0.5)
			(island_removal_mode 0)
		)
		(polygon
			(pts
				(arc
					(start 17.938242 -251.735336)
					(mid 17.277842 -251.735336)
					(end 17.938242 -251.735336)
				)
			)
		)
	)
	(zone
		(layers "In1.Cu" "In2.Cu")
		(hatch none 0.5)
		(connect_pads
			(clearance 0)
		)
		(min_thickness 0.25)
		(keepout
			(tracks not_allowed)
			(vias allowed)
			(pads allowed)
			(copperpour not_allowed)
			(footprints allowed)
		)
		(placement
			(enabled no)
			(sheetname "")
		)
		(fill yes
			(thermal_gap 0.5)
			(thermal_bridge_width 0.5)
			(island_removal_mode 0)
		)
		(polygon
			(pts
				(arc
					(start 179.846224 -213.485222)
					(mid 179.185824 -213.485222)
					(end 179.846224 -213.485222)
				)
			)
		)
	)
	(zone
		(layers "In1.Cu" "In2.Cu")
		(hatch none 0.5)
		(connect_pads
			(clearance 0)
		)
		(min_thickness 0.25)
		(keepout
			(tracks not_allowed)
			(vias allowed)
			(pads allowed)
			(copperpour not_allowed)
			(footprints allowed)
		)
		(placement
			(enabled no)
			(sheetname "")
		)
		(fill yes
			(thermal_gap 0.5)
			(thermal_bridge_width 0.5)
			(island_removal_mode 0)
		)
		(polygon
			(pts
				(arc
					(start 202.478132 -210.935316)
					(mid 201.817732 -210.935316)
					(end 202.478132 -210.935316)
				)
			)
		)
	)
	(zone
		(layers "In1.Cu" "In2.Cu")
		(hatch none 0.5)
		(connect_pads
			(clearance 0)
		)
		(min_thickness 0.25)
		(keepout
			(tracks not_allowed)
			(vias allowed)
			(pads allowed)
			(copperpour not_allowed)
			(footprints allowed)
		)
		(placement
			(enabled no)
			(sheetname "")
		)
		(fill yes
			(thermal_gap 0.5)
			(thermal_bridge_width 0.5)
			(island_removal_mode 0)
		)
		(polygon
			(pts
				(arc
					(start 392.119612 -417.242244)
					(mid 392.14193 -417.296126)
					(end 392.195812 -417.318444)
				)
				(arc
					(start 392.391392 -417.318444)
					(mid 392.413268 -417.315312)
					(end 392.433302 -417.305998)
				)
				(arc
					(start 392.726926 -417.113466)
					(mid 392.768582 -417.101064)
					(end 392.810238 -417.113466)
				)
				(arc
					(start 393.105132 -417.305998)
					(mid 393.125056 -417.315234)
					(end 393.146788 -417.318444)
				)
				(arc
					(start 393.341352 -417.318444)
					(mid 393.395234 -417.296126)
					(end 393.417552 -417.242244)
				)
				(arc
					(start 393.417552 -416.556444)
					(mid 393.395234 -416.502562)
					(end 393.341352 -416.480244)
				)
				(arc
					(start 393.146788 -416.480244)
					(mid 393.125044 -416.483412)
					(end 393.105132 -416.49269)
				)
				(arc
					(start 392.808968 -416.685476)
					(mid 392.767284 -416.697698)
					(end 392.725656 -416.685222)
				)
				(arc
					(start 392.432032 -416.49269)
					(mid 392.412108 -416.483454)
					(end 392.390376 -416.480244)
				)
				(arc
					(start 392.195812 -416.480244)
					(mid 392.14193 -416.502562)
					(end 392.119612 -416.556444)
				)
			)
		)
	)
	(zone
		(layers "In1.Cu" "In2.Cu")
		(hatch none 0.5)
		(connect_pads
			(clearance 0)
		)
		(min_thickness 0.25)
		(keepout
			(tracks not_allowed)
			(vias allowed)
			(pads allowed)
			(copperpour not_allowed)
			(footprints allowed)
		)
		(placement
			(enabled no)
			(sheetname "")
		)
		(fill yes
			(thermal_gap 0.5)
			(thermal_bridge_width 0.5)
			(island_removal_mode 0)
		)
		(polygon
			(pts
				(arc
					(start 33.026096 -291.685218)
					(mid 32.365696 -291.685218)
					(end 33.026096 -291.685218)
				)
			)
		)
	)
	(zone
		(layers "In1.Cu" "In2.Cu")
		(hatch none 0.5)
		(connect_pads
			(clearance 0)
		)
		(min_thickness 0.25)
		(keepout
			(tracks not_allowed)
			(vias allowed)
			(pads allowed)
			(copperpour not_allowed)
			(footprints allowed)
		)
		(placement
			(enabled no)
			(sheetname "")
		)
		(fill yes
			(thermal_gap 0.5)
			(thermal_bridge_width 0.5)
			(island_removal_mode 0)
		)
		(polygon
			(pts
				(arc
					(start 187.390278 -239.835436)
					(mid 186.729878 -239.835436)
					(end 187.390278 -239.835436)
				)
			)
		)
	)
	(zone
		(layers "In1.Cu" "In2.Cu")
		(hatch none 0.5)
		(connect_pads
			(clearance 0)
		)
		(min_thickness 0.25)
		(keepout
			(tracks not_allowed)
			(vias allowed)
			(pads allowed)
			(copperpour not_allowed)
			(footprints allowed)
		)
		(placement
			(enabled no)
			(sheetname "")
		)
		(fill yes
			(thermal_gap 0.5)
			(thermal_bridge_width 0.5)
			(island_removal_mode 0)
		)
		(polygon
			(pts
				(arc
					(start 277.522432 -317.18504)
					(mid 276.862032 -317.18504)
					(end 277.522432 -317.18504)
				)
			)
		)
	)
	(zone
		(layers "In1.Cu" "In2.Cu")
		(hatch none 0.5)
		(connect_pads
			(clearance 0)
		)
		(min_thickness 0.25)
		(keepout
			(tracks not_allowed)
			(vias allowed)
			(pads allowed)
			(copperpour not_allowed)
			(footprints allowed)
		)
		(placement
			(enabled no)
			(sheetname "")
		)
		(fill yes
			(thermal_gap 0.5)
			(thermal_bridge_width 0.5)
			(island_removal_mode 0)
		)
		(polygon
			(pts
				(arc
					(start 431.88636 -262.785098)
					(mid 431.22596 -262.785098)
					(end 431.88636 -262.785098)
				)
			)
		)
	)
	(zone
		(layers "In1.Cu" "In2.Cu")
		(hatch none 0.5)
		(connect_pads
			(clearance 0)
		)
		(min_thickness 0.25)
		(keepout
			(tracks not_allowed)
			(vias allowed)
			(pads allowed)
			(copperpour not_allowed)
			(footprints allowed)
		)
		(placement
			(enabled no)
			(sheetname "")
		)
		(fill yes
			(thermal_gap 0.5)
			(thermal_bridge_width 0.5)
			(island_removal_mode 0)
		)
		(polygon
			(pts
				(arc
					(start 29.582364 -266.185396)
					(mid 28.921964 -266.185396)
					(end 29.582364 -266.185396)
				)
			)
		)
	)
	(zone
		(layers "In1.Cu" "In2.Cu")
		(hatch none 0.5)
		(connect_pads
			(clearance 0)
		)
		(min_thickness 0.25)
		(keepout
			(tracks not_allowed)
			(vias allowed)
			(pads allowed)
			(copperpour not_allowed)
			(footprints allowed)
		)
		(placement
			(enabled no)
			(sheetname "")
		)
		(fill yes
			(thermal_gap 0.5)
			(thermal_bridge_width 0.5)
			(island_removal_mode 0)
		)
		(polygon
			(pts
				(arc
					(start 296.054272 -293.384986)
					(mid 295.393872 -293.384986)
					(end 296.054272 -293.384986)
				)
			)
		)
	)
	(zone
		(layers "In1.Cu" "In2.Cu")
		(hatch none 0.5)
		(connect_pads
			(clearance 0)
		)
		(min_thickness 0.25)
		(keepout
			(tracks not_allowed)
			(vias allowed)
			(pads allowed)
			(copperpour not_allowed)
			(footprints allowed)
		)
		(placement
			(enabled no)
			(sheetname "")
		)
		(fill yes
			(thermal_gap 0.5)
			(thermal_bridge_width 0.5)
			(island_removal_mode 0)
		)
		(polygon
			(pts
				(arc
					(start 416.625532 -417.242244)
					(mid 416.64785 -417.296126)
					(end 416.701732 -417.318444)
				)
				(arc
					(start 416.897312 -417.318444)
					(mid 416.919188 -417.315312)
					(end 416.939222 -417.305998)
				)
				(arc
					(start 417.232846 -417.113466)
					(mid 417.274502 -417.101064)
					(end 417.316158 -417.113466)
				)
				(arc
					(start 417.611052 -417.305998)
					(mid 417.630976 -417.315234)
					(end 417.652708 -417.318444)
				)
				(arc
					(start 417.847272 -417.318444)
					(mid 417.901154 -417.296126)
					(end 417.923472 -417.242244)
				)
				(arc
					(start 417.923472 -416.556444)
					(mid 417.901154 -416.502562)
					(end 417.847272 -416.480244)
				)
				(arc
					(start 417.652708 -416.480244)
					(mid 417.630964 -416.483412)
					(end 417.611052 -416.49269)
				)
				(arc
					(start 417.314888 -416.685476)
					(mid 417.273204 -416.697698)
					(end 417.231576 -416.685222)
				)
				(arc
					(start 416.937952 -416.49269)
					(mid 416.918028 -416.483454)
					(end 416.896296 -416.480244)
				)
				(arc
					(start 416.701732 -416.480244)
					(mid 416.64785 -416.502562)
					(end 416.625532 -416.556444)
				)
			)
		)
	)
	(zone
		(layers "In1.Cu" "In2.Cu")
		(hatch none 0.5)
		(connect_pads
			(clearance 0)
		)
		(min_thickness 0.25)
		(keepout
			(tracks not_allowed)
			(vias allowed)
			(pads allowed)
			(copperpour not_allowed)
			(footprints allowed)
		)
		(placement
			(enabled no)
			(sheetname "")
		)
		(fill yes
			(thermal_gap 0.5)
			(thermal_bridge_width 0.5)
			(island_removal_mode 0)
		)
		(polygon
			(pts
				(arc
					(start 446.974468 -200.735184)
					(mid 446.314068 -200.735184)
					(end 446.974468 -200.735184)
				)
			)
		)
	)
	(zone
		(layers "In1.Cu" "In2.Cu")
		(hatch none 0.5)
		(connect_pads
			(clearance 0)
		)
		(min_thickness 0.25)
		(keepout
			(tracks not_allowed)
			(vias allowed)
			(pads allowed)
			(copperpour not_allowed)
			(footprints allowed)
		)
		(placement
			(enabled no)
			(sheetname "")
		)
		(fill yes
			(thermal_gap 0.5)
			(thermal_bridge_width 0.5)
			(island_removal_mode 0)
		)
		(polygon
			(pts
				(arc
					(start 269.978378 -270.43507)
					(mid 269.317978 -270.43507)
					(end 269.978378 -270.43507)
				)
			)
		)
	)
	(zone
		(layers "In1.Cu" "In2.Cu")
		(hatch none 0.5)
		(connect_pads
			(clearance 0)
		)
		(min_thickness 0.25)
		(keepout
			(tracks not_allowed)
			(vias allowed)
			(pads allowed)
			(copperpour not_allowed)
			(footprints allowed)
		)
		(placement
			(enabled no)
			(sheetname "")
		)
		(fill yes
			(thermal_gap 0.5)
			(thermal_bridge_width 0.5)
			(island_removal_mode 0)
		)
		(polygon
			(pts
				(arc
					(start 22.03831 -275.53539)
					(mid 21.37791 -275.53539)
					(end 22.03831 -275.53539)
				)
			)
		)
	)
	(zone
		(layers "In1.Cu" "In2.Cu")
		(hatch none 0.5)
		(connect_pads
			(clearance 0)
		)
		(min_thickness 0.25)
		(keepout
			(tracks not_allowed)
			(vias allowed)
			(pads allowed)
			(copperpour not_allowed)
			(footprints allowed)
		)
		(placement
			(enabled no)
			(sheetname "")
		)
		(fill yes
			(thermal_gap 0.5)
			(thermal_bridge_width 0.5)
			(island_removal_mode 0)
		)
		(polygon
			(pts
				(arc
					(start 202.478132 -310.385206)
					(mid 201.817732 -310.385206)
					(end 202.478132 -310.385206)
				)
			)
		)
	)
	(zone
		(layers "In1.Cu" "In2.Cu")
		(hatch none 0.5)
		(connect_pads
			(clearance 0)
		)
		(min_thickness 0.25)
		(keepout
			(tracks not_allowed)
			(vias allowed)
			(pads allowed)
			(copperpour not_allowed)
			(footprints allowed)
		)
		(placement
			(enabled no)
			(sheetname "")
		)
		(fill yes
			(thermal_gap 0.5)
			(thermal_bridge_width 0.5)
			(island_removal_mode 0)
		)
		(polygon
			(pts
				(arc
					(start 191.490346 -229.635304)
					(mid 190.829946 -229.635304)
					(end 191.490346 -229.635304)
				)
			)
		)
	)
	(zone
		(layers "In1.Cu" "In2.Cu")
		(hatch none 0.5)
		(connect_pads
			(clearance 0)
		)
		(min_thickness 0.25)
		(keepout
			(tracks not_allowed)
			(vias allowed)
			(pads allowed)
			(copperpour not_allowed)
			(footprints allowed)
		)
		(placement
			(enabled no)
			(sheetname "")
		)
		(fill yes
			(thermal_gap 0.5)
			(thermal_bridge_width 0.5)
			(island_removal_mode 0)
		)
		(polygon
			(pts
				(arc
					(start 37.126164 -313.78525)
					(mid 36.465764 -313.78525)
					(end 37.126164 -313.78525)
				)
			)
		)
	)
	(zone
		(layers "In1.Cu" "In2.Cu")
		(hatch none 0.5)
		(connect_pads
			(clearance 0)
		)
		(min_thickness 0.25)
		(keepout
			(tracks not_allowed)
			(vias allowed)
			(pads allowed)
			(copperpour not_allowed)
			(footprints allowed)
		)
		(placement
			(enabled no)
			(sheetname "")
		)
		(fill yes
			(thermal_gap 0.5)
			(thermal_bridge_width 0.5)
			(island_removal_mode 0)
		)
		(polygon
			(pts
				(arc
					(start 420.242238 -209.23504)
					(mid 419.581838 -209.23504)
					(end 420.242238 -209.23504)
				)
			)
		)
	)
	(zone
		(layers "In1.Cu" "In2.Cu")
		(hatch none 0.5)
		(connect_pads
			(clearance 0)
		)
		(min_thickness 0.25)
		(keepout
			(tracks not_allowed)
			(vias allowed)
			(pads allowed)
			(copperpour not_allowed)
			(footprints allowed)
		)
		(placement
			(enabled no)
			(sheetname "")
		)
		(fill yes
			(thermal_gap 0.5)
			(thermal_bridge_width 0.5)
			(island_removal_mode 0)
		)
		(polygon
			(pts
				(arc
					(start 17.938242 -295.9354)
					(mid 17.277842 -295.9354)
					(end 17.938242 -295.9354)
				)
			)
		)
	)
	(zone
		(layers "In1.Cu" "In2.Cu")
		(hatch none 0.5)
		(connect_pads
			(clearance 0)
		)
		(min_thickness 0.25)
		(keepout
			(tracks not_allowed)
			(vias allowed)
			(pads allowed)
			(copperpour not_allowed)
			(footprints allowed)
		)
		(placement
			(enabled no)
			(sheetname "")
		)
		(fill yes
			(thermal_gap 0.5)
			(thermal_bridge_width 0.5)
			(island_removal_mode 0)
		)
		(polygon
			(pts
				(arc
					(start 199.0344 -238.135414)
					(mid 198.374 -238.135414)
					(end 199.0344 -238.135414)
				)
			)
		)
	)
	(zone
		(layers "In1.Cu" "In2.Cu")
		(hatch none 0.5)
		(connect_pads
			(clearance 0)
		)
		(min_thickness 0.25)
		(keepout
			(tracks not_allowed)
			(vias allowed)
			(pads allowed)
			(copperpour not_allowed)
			(footprints allowed)
		)
		(placement
			(enabled no)
			(sheetname "")
		)
		(fill yes
			(thermal_gap 0.5)
			(thermal_bridge_width 0.5)
			(island_removal_mode 0)
		)
		(polygon
			(pts
				(arc
					(start 17.938242 -211.7852)
					(mid 17.277842 -211.7852)
					(end 17.938242 -211.7852)
				)
			)
		)
	)
	(zone
		(layers "In1.Cu" "In2.Cu")
		(hatch none 0.5)
		(connect_pads
			(clearance 0)
		)
		(min_thickness 0.25)
		(keepout
			(tracks not_allowed)
			(vias allowed)
			(pads allowed)
			(copperpour not_allowed)
			(footprints allowed)
		)
		(placement
			(enabled no)
			(sheetname "")
		)
		(fill yes
			(thermal_gap 0.5)
			(thermal_bridge_width 0.5)
			(island_removal_mode 0)
		)
		(polygon
			(pts
				(arc
					(start 37.126164 -267.885418)
					(mid 36.465764 -267.885418)
					(end 37.126164 -267.885418)
				)
			)
		)
	)
	(zone
		(layers "In1.Cu" "In2.Cu")
		(hatch none 0.5)
		(connect_pads
			(clearance 0)
		)
		(min_thickness 0.25)
		(keepout
			(tracks not_allowed)
			(vias allowed)
			(pads allowed)
			(copperpour not_allowed)
			(footprints allowed)
		)
		(placement
			(enabled no)
			(sheetname "")
		)
		(fill yes
			(thermal_gap 0.5)
			(thermal_bridge_width 0.5)
			(island_removal_mode 0)
		)
		(polygon
			(pts
				(arc
					(start 431.88636 -301.885096)
					(mid 431.22596 -301.885096)
					(end 431.88636 -301.885096)
				)
			)
		)
	)
	(zone
		(layers "In1.Cu" "In2.Cu")
		(hatch none 0.5)
		(connect_pads
			(clearance 0)
		)
		(min_thickness 0.25)
		(keepout
			(tracks not_allowed)
			(vias allowed)
			(pads allowed)
			(copperpour not_allowed)
			(footprints allowed)
		)
		(placement
			(enabled no)
			(sheetname "")
		)
		(fill yes
			(thermal_gap 0.5)
			(thermal_bridge_width 0.5)
			(island_removal_mode 0)
		)
		(polygon
			(pts
				(arc
					(start 439.430414 -303.585118)
					(mid 438.770014 -303.585118)
					(end 439.430414 -303.585118)
				)
			)
		)
	)
	(zone
		(layers "In1.Cu" "In2.Cu")
		(hatch none 0.5)
		(connect_pads
			(clearance 0)
		)
		(min_thickness 0.25)
		(keepout
			(tracks not_allowed)
			(vias allowed)
			(pads allowed)
			(copperpour not_allowed)
			(footprints allowed)
		)
		(placement
			(enabled no)
			(sheetname "")
		)
		(fill yes
			(thermal_gap 0.5)
			(thermal_bridge_width 0.5)
			(island_removal_mode 0)
		)
		(polygon
			(pts
				(arc
					(start 414.72739 -379.360684)
					(mid 414.747314 -379.36992)
					(end 414.769046 -379.37313)
				)
				(arc
					(start 414.96361 -379.37313)
					(mid 415.017492 -379.350812)
					(end 415.03981 -379.29693)
				)
				(arc
					(start 415.03981 -378.61113)
					(mid 415.017492 -378.557248)
					(end 414.96361 -378.53493)
				)
				(arc
					(start 414.769046 -378.53493)
					(mid 414.747302 -378.538098)
					(end 414.72739 -378.547376)
				)
				(arc
					(start 414.431226 -378.740162)
					(mid 414.389542 -378.752384)
					(end 414.347914 -378.739908)
				)
				(arc
					(start 414.05429 -378.547376)
					(mid 414.034366 -378.53814)
					(end 414.012634 -378.53493)
				)
				(arc
					(start 413.81807 -378.53493)
					(mid 413.764188 -378.557248)
					(end 413.74187 -378.61113)
				)
				(arc
					(start 413.74187 -379.29693)
					(mid 413.764188 -379.350812)
					(end 413.81807 -379.37313)
				)
				(arc
					(start 414.013904 -379.37313)
					(mid 414.035648 -379.369962)
					(end 414.05556 -379.360684)
				)
				(arc
					(start 414.349184 -379.168152)
					(mid 414.39084 -379.15575)
					(end 414.432496 -379.168152)
				)
			)
		)
	)
	(zone
		(layers "In1.Cu" "In2.Cu")
		(hatch none 0.5)
		(connect_pads
			(clearance 0)
		)
		(min_thickness 0.25)
		(keepout
			(tracks not_allowed)
			(vias allowed)
			(pads allowed)
			(copperpour not_allowed)
			(footprints allowed)
		)
		(placement
			(enabled no)
			(sheetname "")
		)
		(fill yes
			(thermal_gap 0.5)
			(thermal_bridge_width 0.5)
			(island_removal_mode 0)
		)
		(polygon
			(pts
				(arc
					(start 199.0344 -254.285242)
					(mid 198.374 -254.285242)
					(end 199.0344 -254.285242)
				)
			)
		)
	)
	(zone
		(layers "In1.Cu" "In2.Cu")
		(hatch none 0.5)
		(connect_pads
			(clearance 0)
		)
		(min_thickness 0.25)
		(keepout
			(tracks not_allowed)
			(vias allowed)
			(pads allowed)
			(copperpour not_allowed)
			(footprints allowed)
		)
		(placement
			(enabled no)
			(sheetname "")
		)
		(fill yes
			(thermal_gap 0.5)
			(thermal_bridge_width 0.5)
			(island_removal_mode 0)
		)
		(polygon
			(pts
				(arc
					(start 202.478132 -253.435358)
					(mid 201.817732 -253.435358)
					(end 202.478132 -253.435358)
				)
			)
		)
	)
	(zone
		(layers "In1.Cu" "In2.Cu")
		(hatch none 0.5)
		(connect_pads
			(clearance 0)
		)
		(min_thickness 0.25)
		(keepout
			(tracks not_allowed)
			(vias allowed)
			(pads allowed)
			(copperpour not_allowed)
			(footprints allowed)
		)
		(placement
			(enabled no)
			(sheetname "")
		)
		(fill yes
			(thermal_gap 0.5)
			(thermal_bridge_width 0.5)
			(island_removal_mode 0)
		)
		(polygon
			(pts
				(arc
					(start 232.558844 -51.872896)
					(mid 232.612726 -51.895214)
					(end 232.635044 -51.949096)
				)
				(arc
					(start 232.635044 -52.980844)
					(mid 232.612726 -53.034726)
					(end 232.558844 -53.057044)
				)
				(arc
					(start 231.441244 -53.057044)
					(mid 231.387362 -53.034726)
					(end 231.365044 -52.980844)
				)
				(arc
					(start 231.365044 -51.949096)
					(mid 231.387362 -51.895214)
					(end 231.441244 -51.872896)
				)
			)
		)
	)
	(zone
		(layers "In1.Cu" "In2.Cu")
		(hatch none 0.5)
		(connect_pads
			(clearance 0)
		)
		(min_thickness 0.25)
		(keepout
			(tracks not_allowed)
			(vias allowed)
			(pads allowed)
			(copperpour not_allowed)
			(footprints allowed)
		)
		(placement
			(enabled no)
			(sheetname "")
		)
		(fill yes
			(thermal_gap 0.5)
			(thermal_bridge_width 0.5)
			(island_removal_mode 0)
		)
		(polygon
			(pts
				(arc
					(start 179.846224 -239.835436)
					(mid 179.185824 -239.835436)
					(end 179.846224 -239.835436)
				)
			)
		)
	)
	(zone
		(layers "In1.Cu" "In2.Cu")
		(hatch none 0.5)
		(connect_pads
			(clearance 0)
		)
		(min_thickness 0.25)
		(keepout
			(tracks not_allowed)
			(vias allowed)
			(pads allowed)
			(copperpour not_allowed)
			(footprints allowed)
		)
		(placement
			(enabled no)
			(sheetname "")
		)
		(fill yes
			(thermal_gap 0.5)
			(thermal_bridge_width 0.5)
			(island_removal_mode 0)
		)
		(polygon
			(pts
				(arc
					(start 328.082656 -417.242244)
					(mid 328.104974 -417.296126)
					(end 328.158856 -417.318444)
				)
				(arc
					(start 328.354436 -417.318444)
					(mid 328.376312 -417.315312)
					(end 328.396346 -417.305998)
				)
				(arc
					(start 328.68997 -417.113466)
					(mid 328.731626 -417.101064)
					(end 328.773282 -417.113466)
				)
				(arc
					(start 329.068176 -417.305998)
					(mid 329.0881 -417.315234)
					(end 329.109832 -417.318444)
				)
				(arc
					(start 329.304396 -417.318444)
					(mid 329.358278 -417.296126)
					(end 329.380596 -417.242244)
				)
				(arc
					(start 329.380596 -416.556444)
					(mid 329.358278 -416.502562)
					(end 329.304396 -416.480244)
				)
				(arc
					(start 329.109832 -416.480244)
					(mid 329.088088 -416.483412)
					(end 329.068176 -416.49269)
				)
				(arc
					(start 328.772012 -416.685476)
					(mid 328.730328 -416.697698)
					(end 328.6887 -416.685222)
				)
				(arc
					(start 328.395076 -416.49269)
					(mid 328.375152 -416.483454)
					(end 328.35342 -416.480244)
				)
				(arc
					(start 328.158856 -416.480244)
					(mid 328.104974 -416.502562)
					(end 328.082656 -416.556444)
				)
			)
		)
	)
	(zone
		(layers "In1.Cu" "In2.Cu")
		(hatch none 0.5)
		(connect_pads
			(clearance 0)
		)
		(min_thickness 0.25)
		(keepout
			(tracks not_allowed)
			(vias allowed)
			(pads allowed)
			(copperpour not_allowed)
			(footprints allowed)
		)
		(placement
			(enabled no)
			(sheetname "")
		)
		(fill yes
			(thermal_gap 0.5)
			(thermal_bridge_width 0.5)
			(island_removal_mode 0)
		)
		(polygon
			(pts
				(arc
					(start 450.4182 -221.13494)
					(mid 449.7578 -221.13494)
					(end 450.4182 -221.13494)
				)
			)
		)
	)
	(zone
		(layers "In1.Cu" "In2.Cu")
		(hatch none 0.5)
		(connect_pads
			(clearance 0)
		)
		(min_thickness 0.25)
		(keepout
			(tracks not_allowed)
			(vias allowed)
			(pads allowed)
			(copperpour not_allowed)
			(footprints allowed)
		)
		(placement
			(enabled no)
			(sheetname "")
		)
		(fill yes
			(thermal_gap 0.5)
			(thermal_bridge_width 0.5)
			(island_removal_mode 0)
		)
		(polygon
			(pts
				(arc
					(start 442.8744 -267.035026)
					(mid 442.214 -267.035026)
					(end 442.8744 -267.035026)
				)
			)
		)
	)
	(zone
		(layers "In1.Cu" "In2.Cu")
		(hatch none 0.5)
		(connect_pads
			(clearance 0)
		)
		(min_thickness 0.25)
		(keepout
			(tracks not_allowed)
			(vias allowed)
			(pads allowed)
			(copperpour not_allowed)
			(footprints allowed)
		)
		(placement
			(enabled no)
			(sheetname "")
		)
		(fill yes
			(thermal_gap 0.5)
			(thermal_bridge_width 0.5)
			(island_removal_mode 0)
		)
		(polygon
			(pts
				(arc
					(start 285.066232 -252.584966)
					(mid 284.405832 -252.584966)
					(end 285.066232 -252.584966)
				)
			)
		)
	)
	(zone
		(layers "In1.Cu" "In2.Cu")
		(hatch none 0.5)
		(connect_pads
			(clearance 0)
		)
		(min_thickness 0.25)
		(keepout
			(tracks not_allowed)
			(vias allowed)
			(pads allowed)
			(copperpour not_allowed)
			(footprints allowed)
		)
		(placement
			(enabled no)
			(sheetname "")
		)
		(fill yes
			(thermal_gap 0.5)
			(thermal_bridge_width 0.5)
			(island_removal_mode 0)
		)
		(polygon
			(pts
				(arc
					(start 454.518268 -312.935112)
					(mid 453.857868 -312.935112)
					(end 454.518268 -312.935112)
				)
			)
		)
	)
	(zone
		(layers "In1.Cu" "In2.Cu")
		(hatch none 0.5)
		(connect_pads
			(clearance 0)
		)
		(min_thickness 0.25)
		(keepout
			(tracks not_allowed)
			(vias allowed)
			(pads allowed)
			(copperpour not_allowed)
			(footprints allowed)
		)
		(placement
			(enabled no)
			(sheetname "")
		)
		(fill yes
			(thermal_gap 0.5)
			(thermal_bridge_width 0.5)
			(island_removal_mode 0)
		)
		(polygon
			(pts
				(arc
					(start 454.518268 -236.435138)
					(mid 453.857868 -236.435138)
					(end 454.518268 -236.435138)
				)
			)
		)
	)
	(zone
		(layers "In1.Cu" "In2.Cu")
		(hatch none 0.5)
		(connect_pads
			(clearance 0)
		)
		(min_thickness 0.25)
		(keepout
			(tracks not_allowed)
			(vias allowed)
			(pads allowed)
			(copperpour not_allowed)
			(footprints allowed)
		)
		(placement
			(enabled no)
			(sheetname "")
		)
		(fill yes
			(thermal_gap 0.5)
			(thermal_bridge_width 0.5)
			(island_removal_mode 0)
		)
		(polygon
			(pts
				(arc
					(start 33.026096 -308.685438)
					(mid 32.365696 -308.685438)
					(end 33.026096 -308.685438)
				)
			)
		)
	)
	(zone
		(layers "In1.Cu" "In2.Cu")
		(hatch none 0.5)
		(connect_pads
			(clearance 0)
		)
		(min_thickness 0.25)
		(keepout
			(tracks not_allowed)
			(vias allowed)
			(pads allowed)
			(copperpour not_allowed)
			(footprints allowed)
		)
		(placement
			(enabled no)
			(sheetname "")
		)
		(fill yes
			(thermal_gap 0.5)
			(thermal_bridge_width 0.5)
			(island_removal_mode 0)
		)
		(polygon
			(pts
				(arc
					(start 194.934332 -230.485442)
					(mid 194.273932 -230.485442)
					(end 194.934332 -230.485442)
				)
			)
		)
	)
	(zone
		(layers "In1.Cu" "In2.Cu")
		(hatch none 0.5)
		(connect_pads
			(clearance 0)
		)
		(min_thickness 0.25)
		(keepout
			(tracks not_allowed)
			(vias allowed)
			(pads allowed)
			(copperpour not_allowed)
			(footprints allowed)
		)
		(placement
			(enabled no)
			(sheetname "")
		)
		(fill yes
			(thermal_gap 0.5)
			(thermal_bridge_width 0.5)
			(island_removal_mode 0)
		)
		(polygon
			(pts
				(arc
					(start 292.610286 -223.6851)
					(mid 291.949886 -223.6851)
					(end 292.610286 -223.6851)
				)
			)
		)
	)
	(zone
		(layers "In1.Cu" "In2.Cu")
		(hatch none 0.5)
		(connect_pads
			(clearance 0)
		)
		(min_thickness 0.25)
		(keepout
			(tracks not_allowed)
			(vias allowed)
			(pads allowed)
			(copperpour not_allowed)
			(footprints allowed)
		)
		(placement
			(enabled no)
			(sheetname "")
		)
		(fill yes
			(thermal_gap 0.5)
			(thermal_bridge_width 0.5)
			(island_removal_mode 0)
		)
		(polygon
			(pts
				(arc
					(start 413.262318 -7.672324)
					(mid 413.284636 -7.618442)
					(end 413.338518 -7.596124)
				)
				(arc
					(start 414.375092 -7.596124)
					(mid 414.428974 -7.618442)
					(end 414.451292 -7.672324)
				)
				(arc
					(start 414.451292 -9.071864)
					(mid 414.428974 -9.125746)
					(end 414.375092 -9.148064)
				)
				(arc
					(start 413.338518 -9.148064)
					(mid 413.284636 -9.125746)
					(end 413.262318 -9.071864)
				)
			)
		)
	)
	(zone
		(layers "In1.Cu" "In2.Cu")
		(hatch none 0.5)
		(connect_pads
			(clearance 0)
		)
		(min_thickness 0.25)
		(keepout
			(tracks not_allowed)
			(vias allowed)
			(pads allowed)
			(copperpour not_allowed)
			(footprints allowed)
		)
		(placement
			(enabled no)
			(sheetname "")
		)
		(fill yes
			(thermal_gap 0.5)
			(thermal_bridge_width 0.5)
			(island_removal_mode 0)
		)
		(polygon
			(pts
				(arc
					(start 237.158784 -55.472838)
					(mid 237.212666 -55.495156)
					(end 237.234984 -55.549038)
				)
				(arc
					(start 237.234984 -56.580786)
					(mid 237.212666 -56.634668)
					(end 237.158784 -56.656986)
				)
				(arc
					(start 236.041184 -56.656986)
					(mid 235.987302 -56.634668)
					(end 235.964984 -56.580786)
				)
				(arc
					(start 235.964984 -55.549038)
					(mid 235.987302 -55.495156)
					(end 236.041184 -55.472838)
				)
			)
		)
	)
	(zone
		(layers "In1.Cu" "In2.Cu")
		(hatch none 0.5)
		(connect_pads
			(clearance 0)
		)
		(min_thickness 0.25)
		(keepout
			(tracks not_allowed)
			(vias allowed)
			(pads allowed)
			(copperpour not_allowed)
			(footprints allowed)
		)
		(placement
			(enabled no)
			(sheetname "")
		)
		(fill yes
			(thermal_gap 0.5)
			(thermal_bridge_width 0.5)
			(island_removal_mode 0)
		)
		(polygon
			(pts
				(arc
					(start 423.649394 -16.443198)
					(mid 423.671712 -16.49708)
					(end 423.725594 -16.519398)
				)
				(arc
					(start 423.921174 -16.519398)
					(mid 423.94305 -16.516266)
					(end 423.963084 -16.506952)
				)
				(arc
					(start 424.256708 -16.31442)
					(mid 424.298364 -16.302018)
					(end 424.34002 -16.31442)
				)
				(arc
					(start 424.634914 -16.506952)
					(mid 424.654838 -16.516188)
					(end 424.67657 -16.519398)
				)
				(arc
					(start 424.871134 -16.519398)
					(mid 424.925016 -16.49708)
					(end 424.947334 -16.443198)
				)
				(arc
					(start 424.947334 -15.757398)
					(mid 424.925016 -15.703516)
					(end 424.871134 -15.681198)
				)
				(arc
					(start 424.67657 -15.681198)
					(mid 424.654826 -15.684366)
					(end 424.634914 -15.693644)
				)
				(arc
					(start 424.33875 -15.88643)
					(mid 424.297066 -15.898652)
					(end 424.255438 -15.886176)
				)
				(arc
					(start 423.961814 -15.693644)
					(mid 423.94189 -15.684408)
					(end 423.920158 -15.681198)
				)
				(arc
					(start 423.725594 -15.681198)
					(mid 423.671712 -15.703516)
					(end 423.649394 -15.757398)
				)
			)
		)
	)
	(zone
		(layers "In1.Cu" "In2.Cu")
		(hatch none 0.5)
		(connect_pads
			(clearance 0)
		)
		(min_thickness 0.25)
		(keepout
			(tracks not_allowed)
			(vias allowed)
			(pads allowed)
			(copperpour not_allowed)
			(footprints allowed)
		)
		(placement
			(enabled no)
			(sheetname "")
		)
		(fill yes
			(thermal_gap 0.5)
			(thermal_bridge_width 0.5)
			(island_removal_mode 0)
		)
		(polygon
			(pts
				(arc
					(start 431.88636 -217.73515)
					(mid 431.22596 -217.73515)
					(end 431.88636 -217.73515)
				)
			)
		)
	)
	(zone
		(layers "In1.Cu" "In2.Cu")
		(hatch none 0.5)
		(connect_pads
			(clearance 0)
		)
		(min_thickness 0.25)
		(keepout
			(tracks not_allowed)
			(vias allowed)
			(pads allowed)
			(copperpour not_allowed)
			(footprints allowed)
		)
		(placement
			(enabled no)
			(sheetname "")
		)
		(fill yes
			(thermal_gap 0.5)
			(thermal_bridge_width 0.5)
			(island_removal_mode 0)
		)
		(polygon
			(pts
				(arc
					(start 183.946292 -294.235378)
					(mid 183.285892 -294.235378)
					(end 183.946292 -294.235378)
				)
			)
		)
	)
	(zone
		(layers "In1.Cu" "In2.Cu")
		(hatch none 0.5)
		(connect_pads
			(clearance 0)
		)
		(min_thickness 0.25)
		(keepout
			(tracks not_allowed)
			(vias allowed)
			(pads allowed)
			(copperpour not_allowed)
			(footprints allowed)
		)
		(placement
			(enabled no)
			(sheetname "")
		)
		(fill yes
			(thermal_gap 0.5)
			(thermal_bridge_width 0.5)
			(island_removal_mode 0)
		)
		(polygon
			(pts
				(arc
					(start 439.430414 -264.48512)
					(mid 438.770014 -264.48512)
					(end 439.430414 -264.48512)
				)
			)
		)
	)
	(zone
		(layers "In1.Cu" "In2.Cu")
		(hatch none 0.5)
		(connect_pads
			(clearance 0)
		)
		(min_thickness 0.25)
		(keepout
			(tracks not_allowed)
			(vias allowed)
			(pads allowed)
			(copperpour not_allowed)
			(footprints allowed)
		)
		(placement
			(enabled no)
			(sheetname "")
		)
		(fill yes
			(thermal_gap 0.5)
			(thermal_bridge_width 0.5)
			(island_removal_mode 0)
		)
		(polygon
			(pts
				(arc
					(start 179.846224 -280.635202)
					(mid 179.185824 -280.635202)
					(end 179.846224 -280.635202)
				)
			)
		)
	)
	(zone
		(layers "In1.Cu" "In2.Cu")
		(hatch none 0.5)
		(connect_pads
			(clearance 0)
		)
		(min_thickness 0.25)
		(keepout
			(tracks not_allowed)
			(vias allowed)
			(pads allowed)
			(copperpour not_allowed)
			(footprints allowed)
		)
		(placement
			(enabled no)
			(sheetname "")
		)
		(fill yes
			(thermal_gap 0.5)
			(thermal_bridge_width 0.5)
			(island_removal_mode 0)
		)
		(polygon
			(pts
				(arc
					(start 439.430414 -278.085042)
					(mid 438.770014 -278.085042)
					(end 439.430414 -278.085042)
				)
			)
		)
	)
	(zone
		(layers "In1.Cu" "In2.Cu")
		(hatch none 0.5)
		(connect_pads
			(clearance 0)
		)
		(min_thickness 0.25)
		(keepout
			(tracks not_allowed)
			(vias allowed)
			(pads allowed)
			(copperpour not_allowed)
			(footprints allowed)
		)
		(placement
			(enabled no)
			(sheetname "")
		)
		(fill yes
			(thermal_gap 0.5)
			(thermal_bridge_width 0.5)
			(island_removal_mode 0)
		)
		(polygon
			(pts
				(arc
					(start 179.846224 -216.885266)
					(mid 179.185824 -216.885266)
					(end 179.846224 -216.885266)
				)
			)
		)
	)
	(zone
		(layers "In1.Cu" "In2.Cu")
		(hatch none 0.5)
		(connect_pads
			(clearance 0)
		)
		(min_thickness 0.25)
		(keepout
			(tracks not_allowed)
			(vias allowed)
			(pads allowed)
			(copperpour not_allowed)
			(footprints allowed)
		)
		(placement
			(enabled no)
			(sheetname "")
		)
		(fill yes
			(thermal_gap 0.5)
			(thermal_bridge_width 0.5)
			(island_removal_mode 0)
		)
		(polygon
			(pts
				(arc
					(start 280.966164 -308.685184)
					(mid 280.305764 -308.685184)
					(end 280.966164 -308.685184)
				)
			)
		)
	)
	(zone
		(layers "In1.Cu" "In2.Cu")
		(hatch none 0.5)
		(connect_pads
			(clearance 0)
		)
		(min_thickness 0.25)
		(keepout
			(tracks not_allowed)
			(vias allowed)
			(pads allowed)
			(copperpour not_allowed)
			(footprints allowed)
		)
		(placement
			(enabled no)
			(sheetname "")
		)
		(fill yes
			(thermal_gap 0.5)
			(thermal_bridge_width 0.5)
			(island_removal_mode 0)
		)
		(polygon
			(pts
				(arc
					(start 439.430414 -252.584966)
					(mid 438.770014 -252.584966)
					(end 439.430414 -252.584966)
				)
			)
		)
	)
	(zone
		(layers "In1.Cu" "In2.Cu")
		(hatch none 0.5)
		(connect_pads
			(clearance 0)
		)
		(min_thickness 0.25)
		(keepout
			(tracks not_allowed)
			(vias allowed)
			(pads allowed)
			(copperpour not_allowed)
			(footprints allowed)
		)
		(placement
			(enabled no)
			(sheetname "")
		)
		(fill yes
			(thermal_gap 0.5)
			(thermal_bridge_width 0.5)
			(island_removal_mode 0)
		)
		(polygon
			(pts
				(arc
					(start 435.330346 -267.035026)
					(mid 434.669946 -267.035026)
					(end 435.330346 -267.035026)
				)
			)
		)
	)
	(zone
		(layers "In1.Cu" "In2.Cu")
		(hatch none 0.5)
		(connect_pads
			(clearance 0)
		)
		(min_thickness 0.25)
		(keepout
			(tracks not_allowed)
			(vias allowed)
			(pads allowed)
			(copperpour not_allowed)
			(footprints allowed)
		)
		(placement
			(enabled no)
			(sheetname "")
		)
		(fill yes
			(thermal_gap 0.5)
			(thermal_bridge_width 0.5)
			(island_removal_mode 0)
		)
		(polygon
			(pts
				(arc
					(start 277.522432 -238.13516)
					(mid 276.862032 -238.13516)
					(end 277.522432 -238.13516)
				)
			)
		)
	)
	(zone
		(layers "In1.Cu" "In2.Cu")
		(hatch none 0.5)
		(connect_pads
			(clearance 0)
		)
		(min_thickness 0.25)
		(keepout
			(tracks not_allowed)
			(vias allowed)
			(pads allowed)
			(copperpour not_allowed)
			(footprints allowed)
		)
		(placement
			(enabled no)
			(sheetname "")
		)
		(fill yes
			(thermal_gap 0.5)
			(thermal_bridge_width 0.5)
			(island_removal_mode 0)
		)
		(polygon
			(pts
				(arc
					(start 48.114204 -248.335292)
					(mid 47.453804 -248.335292)
					(end 48.114204 -248.335292)
				)
			)
		)
	)
	(zone
		(layers "In1.Cu" "In2.Cu")
		(hatch none 0.5)
		(connect_pads
			(clearance 0)
		)
		(min_thickness 0.25)
		(keepout
			(tracks not_allowed)
			(vias allowed)
			(pads allowed)
			(copperpour not_allowed)
			(footprints allowed)
		)
		(placement
			(enabled no)
			(sheetname "")
		)
		(fill yes
			(thermal_gap 0.5)
			(thermal_bridge_width 0.5)
			(island_removal_mode 0)
		)
		(polygon
			(pts
				(arc
					(start 446.974468 -236.435138)
					(mid 446.314068 -236.435138)
					(end 446.974468 -236.435138)
				)
			)
		)
	)
	(zone
		(layers "In1.Cu" "In2.Cu")
		(hatch none 0.5)
		(connect_pads
			(clearance 0)
		)
		(min_thickness 0.25)
		(keepout
			(tracks not_allowed)
			(vias allowed)
			(pads allowed)
			(copperpour not_allowed)
			(footprints allowed)
		)
		(placement
			(enabled no)
			(sheetname "")
		)
		(fill yes
			(thermal_gap 0.5)
			(thermal_bridge_width 0.5)
			(island_removal_mode 0)
		)
		(polygon
			(pts
				(arc
					(start 446.974468 -306.135024)
					(mid 446.314068 -306.135024)
					(end 446.974468 -306.135024)
				)
			)
		)
	)
	(zone
		(layers "In1.Cu" "In2.Cu")
		(hatch none 0.5)
		(connect_pads
			(clearance 0)
		)
		(min_thickness 0.25)
		(keepout
			(tracks not_allowed)
			(vias allowed)
			(pads allowed)
			(copperpour not_allowed)
			(footprints allowed)
		)
		(placement
			(enabled no)
			(sheetname "")
		)
		(fill yes
			(thermal_gap 0.5)
			(thermal_bridge_width 0.5)
			(island_removal_mode 0)
		)
		(polygon
			(pts
				(arc
					(start 277.522432 -275.535136)
					(mid 276.862032 -275.535136)
					(end 277.522432 -275.535136)
				)
			)
		)
	)
	(zone
		(layers "In1.Cu" "In2.Cu")
		(hatch none 0.5)
		(connect_pads
			(clearance 0)
		)
		(min_thickness 0.25)
		(keepout
			(tracks not_allowed)
			(vias allowed)
			(pads allowed)
			(copperpour not_allowed)
			(footprints allowed)
		)
		(placement
			(enabled no)
			(sheetname "")
		)
		(fill yes
			(thermal_gap 0.5)
			(thermal_bridge_width 0.5)
			(island_removal_mode 0)
		)
		(polygon
			(pts
				(arc
					(start 25.482296 -280.635202)
					(mid 24.821896 -280.635202)
					(end 25.482296 -280.635202)
				)
			)
		)
	)
	(zone
		(layers "In1.Cu" "In2.Cu")
		(hatch none 0.5)
		(connect_pads
			(clearance 0)
		)
		(min_thickness 0.25)
		(keepout
			(tracks not_allowed)
			(vias allowed)
			(pads allowed)
			(copperpour not_allowed)
			(footprints allowed)
		)
		(placement
			(enabled no)
			(sheetname "")
		)
		(fill yes
			(thermal_gap 0.5)
			(thermal_bridge_width 0.5)
			(island_removal_mode 0)
		)
		(polygon
			(pts
				(arc
					(start 179.846224 -304.435256)
					(mid 179.185824 -304.435256)
					(end 179.846224 -304.435256)
				)
			)
		)
	)
	(zone
		(layers "In1.Cu" "In2.Cu")
		(hatch none 0.5)
		(connect_pads
			(clearance 0)
		)
		(min_thickness 0.25)
		(keepout
			(tracks not_allowed)
			(vias allowed)
			(pads allowed)
			(copperpour not_allowed)
			(footprints allowed)
		)
		(placement
			(enabled no)
			(sheetname "")
		)
		(fill yes
			(thermal_gap 0.5)
			(thermal_bridge_width 0.5)
			(island_removal_mode 0)
		)
		(polygon
			(pts
				(arc
					(start 176.402238 -307.8353)
					(mid 175.741838 -307.8353)
					(end 176.402238 -307.8353)
				)
			)
		)
	)
	(zone
		(layers "In1.Cu" "In2.Cu")
		(hatch none 0.5)
		(connect_pads
			(clearance 0)
		)
		(min_thickness 0.25)
		(keepout
			(tracks not_allowed)
			(vias allowed)
			(pads allowed)
			(copperpour not_allowed)
			(footprints allowed)
		)
		(placement
			(enabled no)
			(sheetname "")
		)
		(fill yes
			(thermal_gap 0.5)
			(thermal_bridge_width 0.5)
			(island_removal_mode 0)
		)
		(polygon
			(pts
				(arc
					(start 37.126164 -245.785386)
					(mid 36.465764 -245.785386)
					(end 37.126164 -245.785386)
				)
			)
		)
	)
	(zone
		(layers "In1.Cu" "In2.Cu")
		(hatch none 0.5)
		(connect_pads
			(clearance 0)
		)
		(min_thickness 0.25)
		(keepout
			(tracks not_allowed)
			(vias allowed)
			(pads allowed)
			(copperpour not_allowed)
			(footprints allowed)
		)
		(placement
			(enabled no)
			(sheetname "")
		)
		(fill yes
			(thermal_gap 0.5)
			(thermal_bridge_width 0.5)
			(island_removal_mode 0)
		)
		(polygon
			(pts
				(arc
					(start 420.242238 -244.934994)
					(mid 419.581838 -244.934994)
					(end 420.242238 -244.934994)
				)
			)
		)
	)
	(zone
		(layers "In1.Cu" "In2.Cu")
		(hatch none 0.5)
		(connect_pads
			(clearance 0)
		)
		(min_thickness 0.25)
		(keepout
			(tracks not_allowed)
			(vias allowed)
			(pads allowed)
			(copperpour not_allowed)
			(footprints allowed)
		)
		(placement
			(enabled no)
			(sheetname "")
		)
		(fill yes
			(thermal_gap 0.5)
			(thermal_bridge_width 0.5)
			(island_removal_mode 0)
		)
		(polygon
			(pts
				(arc
					(start 187.390278 -244.935248)
					(mid 186.729878 -244.935248)
					(end 187.390278 -244.935248)
				)
			)
		)
	)
	(zone
		(layers "In1.Cu" "In2.Cu")
		(hatch none 0.5)
		(connect_pads
			(clearance 0)
		)
		(min_thickness 0.25)
		(keepout
			(tracks not_allowed)
			(vias allowed)
			(pads allowed)
			(copperpour not_allowed)
			(footprints allowed)
		)
		(placement
			(enabled no)
			(sheetname "")
		)
		(fill yes
			(thermal_gap 0.5)
			(thermal_bridge_width 0.5)
			(island_removal_mode 0)
		)
		(polygon
			(pts
				(arc
					(start 232.558844 -55.472838)
					(mid 232.612726 -55.495156)
					(end 232.635044 -55.549038)
				)
				(arc
					(start 232.635044 -56.580786)
					(mid 232.612726 -56.634668)
					(end 232.558844 -56.656986)
				)
				(arc
					(start 231.441244 -56.656986)
					(mid 231.387362 -56.634668)
					(end 231.365044 -56.580786)
				)
				(arc
					(start 231.365044 -55.549038)
					(mid 231.387362 -55.495156)
					(end 231.441244 -55.472838)
				)
			)
		)
	)
	(zone
		(layers "In1.Cu" "In2.Cu")
		(hatch none 0.5)
		(connect_pads
			(clearance 0)
		)
		(min_thickness 0.25)
		(keepout
			(tracks not_allowed)
			(vias allowed)
			(pads allowed)
			(copperpour not_allowed)
			(footprints allowed)
		)
		(placement
			(enabled no)
			(sheetname "")
		)
		(fill yes
			(thermal_gap 0.5)
			(thermal_bridge_width 0.5)
			(island_removal_mode 0)
		)
		(polygon
			(pts
				(arc
					(start 300.15434 -219.435172)
					(mid 299.49394 -219.435172)
					(end 300.15434 -219.435172)
				)
			)
		)
	)
	(zone
		(layers "In1.Cu" "In2.Cu")
		(hatch none 0.5)
		(connect_pads
			(clearance 0)
		)
		(min_thickness 0.25)
		(keepout
			(tracks not_allowed)
			(vias allowed)
			(pads allowed)
			(copperpour not_allowed)
			(footprints allowed)
		)
		(placement
			(enabled no)
			(sheetname "")
		)
		(fill yes
			(thermal_gap 0.5)
			(thermal_bridge_width 0.5)
			(island_removal_mode 0)
		)
		(polygon
			(pts
				(arc
					(start 45.485304 -370.978684)
					(mid 45.505228 -370.98792)
					(end 45.52696 -370.99113)
				)
				(arc
					(start 45.721524 -370.99113)
					(mid 45.775406 -370.968812)
					(end 45.797724 -370.91493)
				)
				(arc
					(start 45.797724 -370.22913)
					(mid 45.775406 -370.175248)
					(end 45.721524 -370.15293)
				)
				(arc
					(start 45.52696 -370.15293)
					(mid 45.505216 -370.156098)
					(end 45.485304 -370.165376)
				)
				(arc
					(start 45.18914 -370.358162)
					(mid 45.147456 -370.370384)
					(end 45.105828 -370.357908)
				)
				(arc
					(start 44.812204 -370.165376)
					(mid 44.79228 -370.15614)
					(end 44.770548 -370.15293)
				)
				(arc
					(start 44.575984 -370.15293)
					(mid 44.522102 -370.175248)
					(end 44.499784 -370.22913)
				)
				(arc
					(start 44.499784 -370.91493)
					(mid 44.522102 -370.968812)
					(end 44.575984 -370.99113)
				)
				(arc
					(start 44.771818 -370.99113)
					(mid 44.793562 -370.987962)
					(end 44.813474 -370.978684)
				)
				(arc
					(start 45.107098 -370.786152)
					(mid 45.148754 -370.77375)
					(end 45.19041 -370.786152)
				)
			)
		)
	)
	(zone
		(layers "In1.Cu" "In2.Cu")
		(hatch none 0.5)
		(connect_pads
			(clearance 0)
		)
		(min_thickness 0.25)
		(keepout
			(tracks not_allowed)
			(vias allowed)
			(pads allowed)
			(copperpour not_allowed)
			(footprints allowed)
		)
		(placement
			(enabled no)
			(sheetname "")
		)
		(fill yes
			(thermal_gap 0.5)
			(thermal_bridge_width 0.5)
			(island_removal_mode 0)
		)
		(polygon
			(pts
				(arc
					(start 44.670218 -227.085398)
					(mid 44.009818 -227.085398)
					(end 44.670218 -227.085398)
				)
			)
		)
	)
	(zone
		(layers "In1.Cu" "In2.Cu")
		(hatch none 0.5)
		(connect_pads
			(clearance 0)
		)
		(min_thickness 0.25)
		(keepout
			(tracks not_allowed)
			(vias allowed)
			(pads allowed)
			(copperpour not_allowed)
			(footprints allowed)
		)
		(placement
			(enabled no)
			(sheetname "")
		)
		(fill yes
			(thermal_gap 0.5)
			(thermal_bridge_width 0.5)
			(island_removal_mode 0)
		)
		(polygon
			(pts
				(arc
					(start 37.126164 -266.185396)
					(mid 36.465764 -266.185396)
					(end 37.126164 -266.185396)
				)
			)
		)
	)
	(zone
		(layers "In1.Cu" "In2.Cu")
		(hatch none 0.5)
		(connect_pads
			(clearance 0)
		)
		(min_thickness 0.25)
		(keepout
			(tracks not_allowed)
			(vias allowed)
			(pads allowed)
			(copperpour not_allowed)
			(footprints allowed)
		)
		(placement
			(enabled no)
			(sheetname "")
		)
		(fill yes
			(thermal_gap 0.5)
			(thermal_bridge_width 0.5)
			(island_removal_mode 0)
		)
		(polygon
			(pts
				(arc
					(start 37.126164 -228.78542)
					(mid 36.465764 -228.78542)
					(end 37.126164 -228.78542)
				)
			)
		)
	)
	(zone
		(layers "In1.Cu" "In2.Cu")
		(hatch none 0.5)
		(connect_pads
			(clearance 0)
		)
		(min_thickness 0.25)
		(keepout
			(tracks not_allowed)
			(vias allowed)
			(pads allowed)
			(copperpour not_allowed)
			(footprints allowed)
		)
		(placement
			(enabled no)
			(sheetname "")
		)
		(fill yes
			(thermal_gap 0.5)
			(thermal_bridge_width 0.5)
			(island_removal_mode 0)
		)
		(polygon
			(pts
				(arc
					(start 22.03831 -284.885384)
					(mid 21.37791 -284.885384)
					(end 22.03831 -284.885384)
				)
			)
		)
	)
	(zone
		(layers "In1.Cu" "In2.Cu")
		(hatch none 0.5)
		(connect_pads
			(clearance 0)
		)
		(min_thickness 0.25)
		(keepout
			(tracks not_allowed)
			(vias allowed)
			(pads allowed)
			(copperpour not_allowed)
			(footprints allowed)
		)
		(placement
			(enabled no)
			(sheetname "")
		)
		(fill yes
			(thermal_gap 0.5)
			(thermal_bridge_width 0.5)
			(island_removal_mode 0)
		)
		(polygon
			(pts
				(arc
					(start 296.054272 -274.684998)
					(mid 295.393872 -274.684998)
					(end 296.054272 -274.684998)
				)
			)
		)
	)
	(zone
		(layers "In1.Cu" "In2.Cu")
		(hatch none 0.5)
		(connect_pads
			(clearance 0)
		)
		(min_thickness 0.25)
		(keepout
			(tracks not_allowed)
			(vias allowed)
			(pads allowed)
			(copperpour not_allowed)
			(footprints allowed)
		)
		(placement
			(enabled no)
			(sheetname "")
		)
		(fill yes
			(thermal_gap 0.5)
			(thermal_bridge_width 0.5)
			(island_removal_mode 0)
		)
		(polygon
			(pts
				(arc
					(start 450.4182 -295.935146)
					(mid 449.7578 -295.935146)
					(end 450.4182 -295.935146)
				)
			)
		)
	)
	(zone
		(layers "In1.Cu" "In2.Cu")
		(hatch none 0.5)
		(connect_pads
			(clearance 0)
		)
		(min_thickness 0.25)
		(keepout
			(tracks not_allowed)
			(vias allowed)
			(pads allowed)
			(copperpour not_allowed)
			(footprints allowed)
		)
		(placement
			(enabled no)
			(sheetname "")
		)
		(fill yes
			(thermal_gap 0.5)
			(thermal_bridge_width 0.5)
			(island_removal_mode 0)
		)
		(polygon
			(pts
				(arc
					(start 183.946292 -269.58544)
					(mid 183.285892 -269.58544)
					(end 183.946292 -269.58544)
				)
			)
		)
	)
	(zone
		(layers "In1.Cu" "In2.Cu")
		(hatch none 0.5)
		(connect_pads
			(clearance 0)
		)
		(min_thickness 0.25)
		(keepout
			(tracks not_allowed)
			(vias allowed)
			(pads allowed)
			(copperpour not_allowed)
			(footprints allowed)
		)
		(placement
			(enabled no)
			(sheetname "")
		)
		(fill yes
			(thermal_gap 0.5)
			(thermal_bridge_width 0.5)
			(island_removal_mode 0)
		)
		(polygon
			(pts
				(arc
					(start 424.93819 -379.360684)
					(mid 424.958114 -379.36992)
					(end 424.979846 -379.37313)
				)
				(arc
					(start 425.17441 -379.37313)
					(mid 425.228292 -379.350812)
					(end 425.25061 -379.29693)
				)
				(arc
					(start 425.25061 -378.61113)
					(mid 425.228292 -378.557248)
					(end 425.17441 -378.53493)
				)
				(arc
					(start 424.979846 -378.53493)
					(mid 424.958102 -378.538098)
					(end 424.93819 -378.547376)
				)
				(arc
					(start 424.642026 -378.740162)
					(mid 424.600342 -378.752384)
					(end 424.558714 -378.739908)
				)
				(arc
					(start 424.26509 -378.547376)
					(mid 424.245166 -378.53814)
					(end 424.223434 -378.53493)
				)
				(arc
					(start 424.02887 -378.53493)
					(mid 423.974988 -378.557248)
					(end 423.95267 -378.61113)
				)
				(arc
					(start 423.95267 -379.29693)
					(mid 423.974988 -379.350812)
					(end 424.02887 -379.37313)
				)
				(arc
					(start 424.224704 -379.37313)
					(mid 424.246448 -379.369962)
					(end 424.26636 -379.360684)
				)
				(arc
					(start 424.559984 -379.168152)
					(mid 424.60164 -379.15575)
					(end 424.643296 -379.168152)
				)
			)
		)
	)
	(zone
		(layers "In1.Cu" "In2.Cu")
		(hatch none 0.5)
		(connect_pads
			(clearance 0)
		)
		(min_thickness 0.25)
		(keepout
			(tracks not_allowed)
			(vias allowed)
			(pads allowed)
			(copperpour not_allowed)
			(footprints allowed)
		)
		(placement
			(enabled no)
			(sheetname "")
		)
		(fill yes
			(thermal_gap 0.5)
			(thermal_bridge_width 0.5)
			(island_removal_mode 0)
		)
		(polygon
			(pts
				(arc
					(start 454.518268 -264.48512)
					(mid 453.857868 -264.48512)
					(end 454.518268 -264.48512)
				)
			)
		)
	)
	(zone
		(layers "In1.Cu" "In2.Cu")
		(hatch none 0.5)
		(connect_pads
			(clearance 0)
		)
		(min_thickness 0.25)
		(keepout
			(tracks not_allowed)
			(vias allowed)
			(pads allowed)
			(copperpour not_allowed)
			(footprints allowed)
		)
		(placement
			(enabled no)
			(sheetname "")
		)
		(fill yes
			(thermal_gap 0.5)
			(thermal_bridge_width 0.5)
			(island_removal_mode 0)
		)
		(polygon
			(pts
				(arc
					(start 300.15434 -285.735014)
					(mid 299.49394 -285.735014)
					(end 300.15434 -285.735014)
				)
			)
		)
	)
	(zone
		(layers "In1.Cu" "In2.Cu")
		(hatch none 0.5)
		(connect_pads
			(clearance 0)
		)
		(min_thickness 0.25)
		(keepout
			(tracks not_allowed)
			(vias allowed)
			(pads allowed)
			(copperpour not_allowed)
			(footprints allowed)
		)
		(placement
			(enabled no)
			(sheetname "")
		)
		(fill yes
			(thermal_gap 0.5)
			(thermal_bridge_width 0.5)
			(island_removal_mode 0)
		)
		(polygon
			(pts
				(arc
					(start 273.422364 -233.884978)
					(mid 272.761964 -233.884978)
					(end 273.422364 -233.884978)
				)
			)
		)
	)
	(zone
		(layers "In1.Cu" "In2.Cu")
		(hatch none 0.5)
		(connect_pads
			(clearance 0)
		)
		(min_thickness 0.25)
		(keepout
			(tracks not_allowed)
			(vias allowed)
			(pads allowed)
			(copperpour not_allowed)
			(footprints allowed)
		)
		(placement
			(enabled no)
			(sheetname "")
		)
		(fill yes
			(thermal_gap 0.5)
			(thermal_bridge_width 0.5)
			(island_removal_mode 0)
		)
		(polygon
			(pts
				(arc
					(start 280.966164 -248.335038)
					(mid 280.305764 -248.335038)
					(end 280.966164 -248.335038)
				)
			)
		)
	)
	(zone
		(layers "In1.Cu" "In2.Cu")
		(hatch none 0.5)
		(connect_pads
			(clearance 0)
		)
		(min_thickness 0.25)
		(keepout
			(tracks not_allowed)
			(vias allowed)
			(pads allowed)
			(copperpour not_allowed)
			(footprints allowed)
		)
		(placement
			(enabled no)
			(sheetname "")
		)
		(fill yes
			(thermal_gap 0.5)
			(thermal_bridge_width 0.5)
			(island_removal_mode 0)
		)
		(polygon
			(pts
				(arc
					(start 52.214272 -261.08533)
					(mid 51.553872 -261.08533)
					(end 52.214272 -261.08533)
				)
			)
		)
	)
	(zone
		(layers "In1.Cu" "In2.Cu")
		(hatch none 0.5)
		(connect_pads
			(clearance 0)
		)
		(min_thickness 0.25)
		(keepout
			(tracks not_allowed)
			(vias allowed)
			(pads allowed)
			(copperpour not_allowed)
			(footprints allowed)
		)
		(placement
			(enabled no)
			(sheetname "")
		)
		(fill yes
			(thermal_gap 0.5)
			(thermal_bridge_width 0.5)
			(island_removal_mode 0)
		)
		(polygon
			(pts
				(arc
					(start 292.610286 -245.785132)
					(mid 291.949886 -245.785132)
					(end 292.610286 -245.785132)
				)
			)
		)
	)
	(zone
		(layers "In1.Cu" "In2.Cu")
		(hatch none 0.5)
		(connect_pads
			(clearance 0)
		)
		(min_thickness 0.25)
		(keepout
			(tracks not_allowed)
			(vias allowed)
			(pads allowed)
			(copperpour not_allowed)
			(footprints allowed)
		)
		(placement
			(enabled no)
			(sheetname "")
		)
		(fill yes
			(thermal_gap 0.5)
			(thermal_bridge_width 0.5)
			(island_removal_mode 0)
		)
		(polygon
			(pts
				(arc
					(start 446.974468 -295.085008)
					(mid 446.314068 -295.085008)
					(end 446.974468 -295.085008)
				)
			)
		)
	)
	(zone
		(layers "In1.Cu" "In2.Cu")
		(hatch none 0.5)
		(connect_pads
			(clearance 0)
		)
		(min_thickness 0.25)
		(keepout
			(tracks not_allowed)
			(vias allowed)
			(pads allowed)
			(copperpour not_allowed)
			(footprints allowed)
		)
		(placement
			(enabled no)
			(sheetname "")
		)
		(fill yes
			(thermal_gap 0.5)
			(thermal_bridge_width 0.5)
			(island_removal_mode 0)
		)
		(polygon
			(pts
				(arc
					(start 44.670218 -201.585322)
					(mid 44.009818 -201.585322)
					(end 44.670218 -201.585322)
				)
			)
		)
	)
	(zone
		(layers "In1.Cu" "In2.Cu")
		(hatch none 0.5)
		(connect_pads
			(clearance 0)
		)
		(min_thickness 0.25)
		(keepout
			(tracks not_allowed)
			(vias allowed)
			(pads allowed)
			(copperpour not_allowed)
			(footprints allowed)
		)
		(placement
			(enabled no)
			(sheetname "")
		)
		(fill yes
			(thermal_gap 0.5)
			(thermal_bridge_width 0.5)
			(island_removal_mode 0)
		)
		(polygon
			(pts
				(arc
					(start 40.57015 -243.235226)
					(mid 39.90975 -243.235226)
					(end 40.57015 -243.235226)
				)
			)
		)
	)
	(zone
		(layers "In1.Cu" "In2.Cu")
		(hatch none 0.5)
		(connect_pads
			(clearance 0)
		)
		(min_thickness 0.25)
		(keepout
			(tracks not_allowed)
			(vias allowed)
			(pads allowed)
			(copperpour not_allowed)
			(footprints allowed)
		)
		(placement
			(enabled no)
			(sheetname "")
		)
		(fill yes
			(thermal_gap 0.5)
			(thermal_bridge_width 0.5)
			(island_removal_mode 0)
		)
		(polygon
			(pts
				(arc
					(start 44.670218 -290.835334)
					(mid 44.009818 -290.835334)
					(end 44.670218 -290.835334)
				)
			)
		)
	)
	(zone
		(layers "In1.Cu" "In2.Cu")
		(hatch none 0.5)
		(connect_pads
			(clearance 0)
		)
		(min_thickness 0.25)
		(keepout
			(tracks not_allowed)
			(vias allowed)
			(pads allowed)
			(copperpour not_allowed)
			(footprints allowed)
		)
		(placement
			(enabled no)
			(sheetname "")
		)
		(fill yes
			(thermal_gap 0.5)
			(thermal_bridge_width 0.5)
			(island_removal_mode 0)
		)
		(polygon
			(pts
				(arc
					(start 454.518268 -273.835114)
					(mid 453.857868 -273.835114)
					(end 454.518268 -273.835114)
				)
			)
		)
	)
	(zone
		(layers "In1.Cu" "In2.Cu")
		(hatch none 0.5)
		(connect_pads
			(clearance 0)
		)
		(min_thickness 0.25)
		(keepout
			(tracks not_allowed)
			(vias allowed)
			(pads allowed)
			(copperpour not_allowed)
			(footprints allowed)
		)
		(placement
			(enabled no)
			(sheetname "")
		)
		(fill yes
			(thermal_gap 0.5)
			(thermal_bridge_width 0.5)
			(island_removal_mode 0)
		)
		(polygon
			(pts
				(arc
					(start 172.30217 -224.535238)
					(mid 171.64177 -224.535238)
					(end 172.30217 -224.535238)
				)
			)
		)
	)
	(zone
		(layers "In1.Cu" "In2.Cu")
		(hatch none 0.5)
		(connect_pads
			(clearance 0)
		)
		(min_thickness 0.25)
		(keepout
			(tracks not_allowed)
			(vias allowed)
			(pads allowed)
			(copperpour not_allowed)
			(footprints allowed)
		)
		(placement
			(enabled no)
			(sheetname "")
		)
		(fill yes
			(thermal_gap 0.5)
			(thermal_bridge_width 0.5)
			(island_removal_mode 0)
		)
		(polygon
			(pts
				(arc
					(start 424.342306 -229.63505)
					(mid 423.681906 -229.63505)
					(end 424.342306 -229.63505)
				)
			)
		)
	)
	(zone
		(layers "In1.Cu" "In2.Cu")
		(hatch none 0.5)
		(connect_pads
			(clearance 0)
		)
		(min_thickness 0.25)
		(keepout
			(tracks not_allowed)
			(vias allowed)
			(pads allowed)
			(copperpour not_allowed)
			(footprints allowed)
		)
		(placement
			(enabled no)
			(sheetname "")
		)
		(fill yes
			(thermal_gap 0.5)
			(thermal_bridge_width 0.5)
			(island_removal_mode 0)
		)
		(polygon
			(pts
				(arc
					(start 288.510218 -284.034992)
					(mid 287.849818 -284.034992)
					(end 288.510218 -284.034992)
				)
			)
		)
	)
	(zone
		(layers "In1.Cu" "In2.Cu")
		(hatch none 0.5)
		(connect_pads
			(clearance 0)
		)
		(min_thickness 0.25)
		(keepout
			(tracks not_allowed)
			(vias allowed)
			(pads allowed)
			(copperpour not_allowed)
			(footprints allowed)
		)
		(placement
			(enabled no)
			(sheetname "")
		)
		(fill yes
			(thermal_gap 0.5)
			(thermal_bridge_width 0.5)
			(island_removal_mode 0)
		)
		(polygon
			(pts
				(arc
					(start 427.786292 -267.035026)
					(mid 427.125892 -267.035026)
					(end 427.786292 -267.035026)
				)
			)
		)
	)
	(zone
		(layers "In1.Cu" "In2.Cu")
		(hatch none 0.5)
		(connect_pads
			(clearance 0)
		)
		(min_thickness 0.25)
		(keepout
			(tracks not_allowed)
			(vias allowed)
			(pads allowed)
			(copperpour not_allowed)
			(footprints allowed)
		)
		(placement
			(enabled no)
			(sheetname "")
		)
		(fill yes
			(thermal_gap 0.5)
			(thermal_bridge_width 0.5)
			(island_removal_mode 0)
		)
		(polygon
			(pts
				(arc
					(start 442.8744 -284.034992)
					(mid 442.214 -284.034992)
					(end 442.8744 -284.034992)
				)
			)
		)
	)
	(zone
		(layers "In1.Cu" "In2.Cu")
		(hatch none 0.5)
		(connect_pads
			(clearance 0)
		)
		(min_thickness 0.25)
		(keepout
			(tracks not_allowed)
			(vias allowed)
			(pads allowed)
			(copperpour not_allowed)
			(footprints allowed)
		)
		(placement
			(enabled no)
			(sheetname "")
		)
		(fill yes
			(thermal_gap 0.5)
			(thermal_bridge_width 0.5)
			(island_removal_mode 0)
		)
		(polygon
			(pts
				(arc
					(start 435.330346 -204.134974)
					(mid 434.669946 -204.134974)
					(end 435.330346 -204.134974)
				)
			)
		)
	)
	(zone
		(layers "In1.Cu" "In2.Cu")
		(hatch none 0.5)
		(connect_pads
			(clearance 0)
		)
		(min_thickness 0.25)
		(keepout
			(tracks not_allowed)
			(vias allowed)
			(pads allowed)
			(copperpour not_allowed)
			(footprints allowed)
		)
		(placement
			(enabled no)
			(sheetname "")
		)
		(fill yes
			(thermal_gap 0.5)
			(thermal_bridge_width 0.5)
			(island_removal_mode 0)
		)
		(polygon
			(pts
				(arc
					(start 37.126164 -311.235344)
					(mid 36.465764 -311.235344)
					(end 37.126164 -311.235344)
				)
			)
		)
	)
	(zone
		(layers "In1.Cu" "In2.Cu")
		(hatch none 0.5)
		(connect_pads
			(clearance 0)
		)
		(min_thickness 0.25)
		(keepout
			(tracks not_allowed)
			(vias allowed)
			(pads allowed)
			(copperpour not_allowed)
			(footprints allowed)
		)
		(placement
			(enabled no)
			(sheetname "")
		)
		(fill yes
			(thermal_gap 0.5)
			(thermal_bridge_width 0.5)
			(island_removal_mode 0)
		)
		(polygon
			(pts
				(arc
					(start 442.8744 -216.885012)
					(mid 442.214 -216.885012)
					(end 442.8744 -216.885012)
				)
			)
		)
	)
	(zone
		(layers "In1.Cu" "In2.Cu")
		(hatch none 0.5)
		(connect_pads
			(clearance 0)
		)
		(min_thickness 0.25)
		(keepout
			(tracks not_allowed)
			(vias allowed)
			(pads allowed)
			(copperpour not_allowed)
			(footprints allowed)
		)
		(placement
			(enabled no)
			(sheetname "")
		)
		(fill yes
			(thermal_gap 0.5)
			(thermal_bridge_width 0.5)
			(island_removal_mode 0)
		)
		(polygon
			(pts
				(arc
					(start 439.430414 -295.085008)
					(mid 438.770014 -295.085008)
					(end 439.430414 -295.085008)
				)
			)
		)
	)
	(zone
		(layers "In1.Cu" "In2.Cu")
		(hatch none 0.5)
		(connect_pads
			(clearance 0)
		)
		(min_thickness 0.25)
		(keepout
			(tracks not_allowed)
			(vias allowed)
			(pads allowed)
			(copperpour not_allowed)
			(footprints allowed)
		)
		(placement
			(enabled no)
			(sheetname "")
		)
		(fill yes
			(thermal_gap 0.5)
			(thermal_bridge_width 0.5)
			(island_removal_mode 0)
		)
		(polygon
			(pts
				(arc
					(start 288.510218 -289.985196)
					(mid 287.849818 -289.985196)
					(end 288.510218 -289.985196)
				)
			)
		)
	)
	(zone
		(layers "In1.Cu" "In2.Cu")
		(hatch none 0.5)
		(connect_pads
			(clearance 0)
		)
		(min_thickness 0.25)
		(keepout
			(tracks not_allowed)
			(vias allowed)
			(pads allowed)
			(copperpour not_allowed)
			(footprints allowed)
		)
		(placement
			(enabled no)
			(sheetname "")
		)
		(fill yes
			(thermal_gap 0.5)
			(thermal_bridge_width 0.5)
			(island_removal_mode 0)
		)
		(polygon
			(pts
				(arc
					(start 277.522432 -311.23509)
					(mid 276.862032 -311.23509)
					(end 277.522432 -311.23509)
				)
			)
		)
	)
	(zone
		(layers "In1.Cu" "In2.Cu")
		(hatch none 0.5)
		(connect_pads
			(clearance 0)
		)
		(min_thickness 0.25)
		(keepout
			(tracks not_allowed)
			(vias allowed)
			(pads allowed)
			(copperpour not_allowed)
			(footprints allowed)
		)
		(placement
			(enabled no)
			(sheetname "")
		)
		(fill yes
			(thermal_gap 0.5)
			(thermal_bridge_width 0.5)
			(island_removal_mode 0)
		)
		(polygon
			(pts
				(arc
					(start 194.934332 -312.085228)
					(mid 194.273932 -312.085228)
					(end 194.934332 -312.085228)
				)
			)
		)
	)
	(zone
		(layers "In1.Cu" "In2.Cu")
		(hatch none 0.5)
		(connect_pads
			(clearance 0)
		)
		(min_thickness 0.25)
		(keepout
			(tracks not_allowed)
			(vias allowed)
			(pads allowed)
			(copperpour not_allowed)
			(footprints allowed)
		)
		(placement
			(enabled no)
			(sheetname "")
		)
		(fill yes
			(thermal_gap 0.5)
			(thermal_bridge_width 0.5)
			(island_removal_mode 0)
		)
		(polygon
			(pts
				(arc
					(start 349.525336 -417.242244)
					(mid 349.547654 -417.296126)
					(end 349.601536 -417.318444)
				)
				(arc
					(start 349.797116 -417.318444)
					(mid 349.818992 -417.315312)
					(end 349.839026 -417.305998)
				)
				(arc
					(start 350.13265 -417.113466)
					(mid 350.174306 -417.101064)
					(end 350.215962 -417.113466)
				)
				(arc
					(start 350.510856 -417.305998)
					(mid 350.53078 -417.315234)
					(end 350.552512 -417.318444)
				)
				(arc
					(start 350.747076 -417.318444)
					(mid 350.800958 -417.296126)
					(end 350.823276 -417.242244)
				)
				(arc
					(start 350.823276 -416.556444)
					(mid 350.800958 -416.502562)
					(end 350.747076 -416.480244)
				)
				(arc
					(start 350.552512 -416.480244)
					(mid 350.530768 -416.483412)
					(end 350.510856 -416.49269)
				)
				(arc
					(start 350.214692 -416.685476)
					(mid 350.173008 -416.697698)
					(end 350.13138 -416.685222)
				)
				(arc
					(start 349.837756 -416.49269)
					(mid 349.817832 -416.483454)
					(end 349.7961 -416.480244)
				)
				(arc
					(start 349.601536 -416.480244)
					(mid 349.547654 -416.502562)
					(end 349.525336 -416.556444)
				)
			)
		)
	)
	(zone
		(layers "In1.Cu" "In2.Cu")
		(hatch none 0.5)
		(connect_pads
			(clearance 0)
		)
		(min_thickness 0.25)
		(keepout
			(tracks not_allowed)
			(vias allowed)
			(pads allowed)
			(copperpour not_allowed)
			(footprints allowed)
		)
		(placement
			(enabled no)
			(sheetname "")
		)
		(fill yes
			(thermal_gap 0.5)
			(thermal_bridge_width 0.5)
			(island_removal_mode 0)
		)
		(polygon
			(pts
				(arc
					(start 237.158784 -51.872896)
					(mid 237.212666 -51.895214)
					(end 237.234984 -51.949096)
				)
				(arc
					(start 237.234984 -52.980844)
					(mid 237.212666 -53.034726)
					(end 237.158784 -53.057044)
				)
				(arc
					(start 236.041184 -53.057044)
					(mid 235.987302 -53.034726)
					(end 235.964984 -52.980844)
				)
				(arc
					(start 235.964984 -51.949096)
					(mid 235.987302 -51.895214)
					(end 236.041184 -51.872896)
				)
			)
		)
	)
	(zone
		(layers "In1.Cu" "In2.Cu")
		(hatch none 0.5)
		(connect_pads
			(clearance 0)
		)
		(min_thickness 0.25)
		(keepout
			(tracks not_allowed)
			(vias allowed)
			(pads allowed)
			(copperpour not_allowed)
			(footprints allowed)
		)
		(placement
			(enabled no)
			(sheetname "")
		)
		(fill yes
			(thermal_gap 0.5)
			(thermal_bridge_width 0.5)
			(island_removal_mode 0)
		)
		(polygon
			(pts
				(arc
					(start 288.510218 -318.035178)
					(mid 287.849818 -318.035178)
					(end 288.510218 -318.035178)
				)
			)
		)
	)
	(zone
		(layers "In1.Cu" "In2.Cu")
		(hatch none 0.5)
		(connect_pads
			(clearance 0)
		)
		(min_thickness 0.25)
		(keepout
			(tracks not_allowed)
			(vias allowed)
			(pads allowed)
			(copperpour not_allowed)
			(footprints allowed)
		)
		(placement
			(enabled no)
			(sheetname "")
		)
		(fill yes
			(thermal_gap 0.5)
			(thermal_bridge_width 0.5)
			(island_removal_mode 0)
		)
		(polygon
			(pts
				(arc
					(start 17.938242 -291.685218)
					(mid 17.277842 -291.685218)
					(end 17.938242 -291.685218)
				)
			)
		)
	)
	(zone
		(layers "In1.Cu" "In2.Cu")
		(hatch none 0.5)
		(connect_pads
			(clearance 0)
		)
		(min_thickness 0.25)
		(keepout
			(tracks not_allowed)
			(vias allowed)
			(pads allowed)
			(copperpour not_allowed)
			(footprints allowed)
		)
		(placement
			(enabled no)
			(sheetname "")
		)
		(fill yes
			(thermal_gap 0.5)
			(thermal_bridge_width 0.5)
			(island_removal_mode 0)
		)
		(polygon
			(pts
				(arc
					(start 269.978378 -300.185074)
					(mid 269.317978 -300.185074)
					(end 269.978378 -300.185074)
				)
			)
		)
	)
	(zone
		(layers "In1.Cu" "In2.Cu")
		(hatch none 0.5)
		(connect_pads
			(clearance 0)
		)
		(min_thickness 0.25)
		(keepout
			(tracks not_allowed)
			(vias allowed)
			(pads allowed)
			(copperpour not_allowed)
			(footprints allowed)
		)
		(placement
			(enabled no)
			(sheetname "")
		)
		(fill yes
			(thermal_gap 0.5)
			(thermal_bridge_width 0.5)
			(island_removal_mode 0)
		)
		(polygon
			(pts
				(arc
					(start 273.422364 -274.684998)
					(mid 272.761964 -274.684998)
					(end 273.422364 -274.684998)
				)
			)
		)
	)
	(zone
		(layers "In1.Cu" "In2.Cu")
		(hatch none 0.5)
		(connect_pads
			(clearance 0)
		)
		(min_thickness 0.25)
		(keepout
			(tracks not_allowed)
			(vias allowed)
			(pads allowed)
			(copperpour not_allowed)
			(footprints allowed)
		)
		(placement
			(enabled no)
			(sheetname "")
		)
		(fill yes
			(thermal_gap 0.5)
			(thermal_bridge_width 0.5)
			(island_removal_mode 0)
		)
		(polygon
			(pts
				(arc
					(start 280.966164 -221.13494)
					(mid 280.305764 -221.13494)
					(end 280.966164 -221.13494)
				)
			)
		)
	)
	(zone
		(layers "In1.Cu" "In2.Cu")
		(hatch none 0.5)
		(connect_pads
			(clearance 0)
		)
		(min_thickness 0.25)
		(keepout
			(tracks not_allowed)
			(vias allowed)
			(pads allowed)
			(copperpour not_allowed)
			(footprints allowed)
		)
		(placement
			(enabled no)
			(sheetname "")
		)
		(fill yes
			(thermal_gap 0.5)
			(thermal_bridge_width 0.5)
			(island_removal_mode 0)
		)
		(polygon
			(pts
				(arc
					(start 296.054272 -318.035178)
					(mid 295.393872 -318.035178)
					(end 296.054272 -318.035178)
				)
			)
		)
	)
	(zone
		(layers "In1.Cu" "In2.Cu")
		(hatch none 0.5)
		(connect_pads
			(clearance 0)
		)
		(min_thickness 0.25)
		(keepout
			(tracks not_allowed)
			(vias allowed)
			(pads allowed)
			(copperpour not_allowed)
			(footprints allowed)
		)
		(placement
			(enabled no)
			(sheetname "")
		)
		(fill yes
			(thermal_gap 0.5)
			(thermal_bridge_width 0.5)
			(island_removal_mode 0)
		)
		(polygon
			(pts
				(arc
					(start 300.15434 -220.285056)
					(mid 299.49394 -220.285056)
					(end 300.15434 -220.285056)
				)
			)
		)
	)
	(zone
		(layers "In1.Cu" "In2.Cu")
		(hatch none 0.5)
		(connect_pads
			(clearance 0)
		)
		(min_thickness 0.25)
		(keepout
			(tracks not_allowed)
			(vias allowed)
			(pads allowed)
			(copperpour not_allowed)
			(footprints allowed)
		)
		(placement
			(enabled no)
			(sheetname "")
		)
		(fill yes
			(thermal_gap 0.5)
			(thermal_bridge_width 0.5)
			(island_removal_mode 0)
		)
		(polygon
			(pts
				(arc
					(start 420.242238 -272.984976)
					(mid 419.581838 -272.984976)
					(end 420.242238 -272.984976)
				)
			)
		)
	)
	(zone
		(layers "In1.Cu" "In2.Cu")
		(hatch none 0.5)
		(connect_pads
			(clearance 0)
		)
		(min_thickness 0.25)
		(keepout
			(tracks not_allowed)
			(vias allowed)
			(pads allowed)
			(copperpour not_allowed)
			(footprints allowed)
		)
		(placement
			(enabled no)
			(sheetname "")
		)
		(fill yes
			(thermal_gap 0.5)
			(thermal_bridge_width 0.5)
			(island_removal_mode 0)
		)
		(polygon
			(pts
				(arc
					(start 446.974468 -315.485018)
					(mid 446.314068 -315.485018)
					(end 446.974468 -315.485018)
				)
			)
		)
	)
	(zone
		(layers "In1.Cu" "In2.Cu")
		(hatch none 0.5)
		(connect_pads
			(clearance 0)
		)
		(min_thickness 0.25)
		(keepout
			(tracks not_allowed)
			(vias allowed)
			(pads allowed)
			(copperpour not_allowed)
			(footprints allowed)
		)
		(placement
			(enabled no)
			(sheetname "")
		)
		(fill yes
			(thermal_gap 0.5)
			(thermal_bridge_width 0.5)
			(island_removal_mode 0)
		)
		(polygon
			(pts
				(arc
					(start 280.966164 -222.834962)
					(mid 280.305764 -222.834962)
					(end 280.966164 -222.834962)
				)
			)
		)
	)
	(zone
		(layers "In1.Cu" "In2.Cu")
		(hatch none 0.5)
		(connect_pads
			(clearance 0)
		)
		(min_thickness 0.25)
		(keepout
			(tracks not_allowed)
			(vias allowed)
			(pads allowed)
			(copperpour not_allowed)
			(footprints allowed)
		)
		(placement
			(enabled no)
			(sheetname "")
		)
		(fill yes
			(thermal_gap 0.5)
			(thermal_bridge_width 0.5)
			(island_removal_mode 0)
		)
		(polygon
			(pts
				(arc
					(start 431.88636 -247.485154)
					(mid 431.22596 -247.485154)
					(end 431.88636 -247.485154)
				)
			)
		)
	)
	(zone
		(layers "In1.Cu" "In2.Cu")
		(hatch none 0.5)
		(connect_pads
			(clearance 0)
		)
		(min_thickness 0.25)
		(keepout
			(tracks not_allowed)
			(vias allowed)
			(pads allowed)
			(copperpour not_allowed)
			(footprints allowed)
		)
		(placement
			(enabled no)
			(sheetname "")
		)
		(fill yes
			(thermal_gap 0.5)
			(thermal_bridge_width 0.5)
			(island_removal_mode 0)
		)
		(polygon
			(pts
				(arc
					(start 29.582364 -217.735404)
					(mid 28.921964 -217.735404)
					(end 29.582364 -217.735404)
				)
			)
		)
	)
	(zone
		(layers "In1.Cu" "In2.Cu")
		(hatch none 0.5)
		(connect_pads
			(clearance 0)
		)
		(min_thickness 0.25)
		(keepout
			(tracks not_allowed)
			(vias allowed)
			(pads allowed)
			(copperpour not_allowed)
			(footprints allowed)
		)
		(placement
			(enabled no)
			(sheetname "")
		)
		(fill yes
			(thermal_gap 0.5)
			(thermal_bridge_width 0.5)
			(island_removal_mode 0)
		)
		(polygon
			(pts
				(arc
					(start 237.158784 -57.272936)
					(mid 237.212666 -57.295254)
					(end 237.234984 -57.349136)
				)
				(arc
					(start 237.234984 -58.380884)
					(mid 237.212666 -58.434766)
					(end 237.158784 -58.457084)
				)
				(arc
					(start 236.041184 -58.457084)
					(mid 235.987302 -58.434766)
					(end 235.964984 -58.380884)
				)
				(arc
					(start 235.964984 -57.349136)
					(mid 235.987302 -57.295254)
					(end 236.041184 -57.272936)
				)
			)
		)
	)
	(zone
		(layers "In1.Cu" "In2.Cu")
		(hatch none 0.5)
		(connect_pads
			(clearance 0)
		)
		(min_thickness 0.25)
		(keepout
			(tracks not_allowed)
			(vias allowed)
			(pads allowed)
			(copperpour not_allowed)
			(footprints allowed)
		)
		(placement
			(enabled no)
			(sheetname "")
		)
		(fill yes
			(thermal_gap 0.5)
			(thermal_bridge_width 0.5)
			(island_removal_mode 0)
		)
		(polygon
			(pts
				(arc
					(start 202.478132 -278.935434)
					(mid 201.817732 -278.935434)
					(end 202.478132 -278.935434)
				)
			)
		)
	)
	(zone
		(layers "In1.Cu" "In2.Cu")
		(hatch none 0.5)
		(connect_pads
			(clearance 0)
		)
		(min_thickness 0.25)
		(keepout
			(tracks not_allowed)
			(vias allowed)
			(pads allowed)
			(copperpour not_allowed)
			(footprints allowed)
		)
		(placement
			(enabled no)
			(sheetname "")
		)
		(fill yes
			(thermal_gap 0.5)
			(thermal_bridge_width 0.5)
			(island_removal_mode 0)
		)
		(polygon
			(pts
				(arc
					(start 151.435816 -408.860244)
					(mid 151.458134 -408.914126)
					(end 151.512016 -408.936444)
				)
				(arc
					(start 151.707596 -408.936444)
					(mid 151.729472 -408.933312)
					(end 151.749506 -408.923998)
				)
				(arc
					(start 152.04313 -408.731466)
					(mid 152.084786 -408.719064)
					(end 152.126442 -408.731466)
				)
				(arc
					(start 152.421336 -408.923998)
					(mid 152.44126 -408.933234)
					(end 152.462992 -408.936444)
				)
				(arc
					(start 152.657556 -408.936444)
					(mid 152.711438 -408.914126)
					(end 152.733756 -408.860244)
				)
				(arc
					(start 152.733756 -408.174444)
					(mid 152.711438 -408.120562)
					(end 152.657556 -408.098244)
				)
				(arc
					(start 152.462992 -408.098244)
					(mid 152.441248 -408.101412)
					(end 152.421336 -408.11069)
				)
				(arc
					(start 152.125172 -408.303476)
					(mid 152.083488 -408.315698)
					(end 152.04186 -408.303222)
				)
				(arc
					(start 151.748236 -408.11069)
					(mid 151.728312 -408.101454)
					(end 151.70658 -408.098244)
				)
				(arc
					(start 151.512016 -408.098244)
					(mid 151.458134 -408.120562)
					(end 151.435816 -408.174444)
				)
			)
		)
	)
	(zone
		(layers "In1.Cu" "In2.Cu")
		(hatch none 0.5)
		(connect_pads
			(clearance 0)
		)
		(min_thickness 0.25)
		(keepout
			(tracks not_allowed)
			(vias allowed)
			(pads allowed)
			(copperpour not_allowed)
			(footprints allowed)
		)
		(placement
			(enabled no)
			(sheetname "")
		)
		(fill yes
			(thermal_gap 0.5)
			(thermal_bridge_width 0.5)
			(island_removal_mode 0)
		)
		(polygon
			(pts
				(arc
					(start 273.422364 -201.585068)
					(mid 272.761964 -201.585068)
					(end 273.422364 -201.585068)
				)
			)
		)
	)
	(zone
		(layers "In1.Cu" "In2.Cu")
		(hatch none 0.5)
		(connect_pads
			(clearance 0)
		)
		(min_thickness 0.25)
		(keepout
			(tracks not_allowed)
			(vias allowed)
			(pads allowed)
			(copperpour not_allowed)
			(footprints allowed)
		)
		(placement
			(enabled no)
			(sheetname "")
		)
		(fill yes
			(thermal_gap 0.5)
			(thermal_bridge_width 0.5)
			(island_removal_mode 0)
		)
		(polygon
			(pts
				(arc
					(start 191.490346 -234.73537)
					(mid 190.829946 -234.73537)
					(end 191.490346 -234.73537)
				)
			)
		)
	)
	(zone
		(layers "In1.Cu" "In2.Cu")
		(hatch none 0.5)
		(connect_pads
			(clearance 0)
		)
		(min_thickness 0.25)
		(keepout
			(tracks not_allowed)
			(vias allowed)
			(pads allowed)
			(copperpour not_allowed)
			(footprints allowed)
		)
		(placement
			(enabled no)
			(sheetname "")
		)
		(fill yes
			(thermal_gap 0.5)
			(thermal_bridge_width 0.5)
			(island_removal_mode 0)
		)
		(polygon
			(pts
				(arc
					(start 431.88636 -303.585118)
					(mid 431.22596 -303.585118)
					(end 431.88636 -303.585118)
				)
			)
		)
	)
	(zone
		(layers "In1.Cu" "In2.Cu")
		(hatch none 0.5)
		(connect_pads
			(clearance 0)
		)
		(min_thickness 0.25)
		(keepout
			(tracks not_allowed)
			(vias allowed)
			(pads allowed)
			(copperpour not_allowed)
			(footprints allowed)
		)
		(placement
			(enabled no)
			(sheetname "")
		)
		(fill yes
			(thermal_gap 0.5)
			(thermal_bridge_width 0.5)
			(island_removal_mode 0)
		)
		(polygon
			(pts
				(arc
					(start 296.054272 -232.184956)
					(mid 295.393872 -232.184956)
					(end 296.054272 -232.184956)
				)
			)
		)
	)
	(zone
		(layers "In1.Cu" "In2.Cu")
		(hatch none 0.5)
		(connect_pads
			(clearance 0)
		)
		(min_thickness 0.25)
		(keepout
			(tracks not_allowed)
			(vias allowed)
			(pads allowed)
			(copperpour not_allowed)
			(footprints allowed)
		)
		(placement
			(enabled no)
			(sheetname "")
		)
		(fill yes
			(thermal_gap 0.5)
			(thermal_bridge_width 0.5)
			(island_removal_mode 0)
		)
		(polygon
			(pts
				(arc
					(start 269.978378 -269.585186)
					(mid 269.317978 -269.585186)
					(end 269.978378 -269.585186)
				)
			)
		)
	)
	(zone
		(layers "In1.Cu" "In2.Cu")
		(hatch none 0.5)
		(connect_pads
			(clearance 0)
		)
		(min_thickness 0.25)
		(keepout
			(tracks not_allowed)
			(vias allowed)
			(pads allowed)
			(copperpour not_allowed)
			(footprints allowed)
		)
		(placement
			(enabled no)
			(sheetname "")
		)
		(fill yes
			(thermal_gap 0.5)
			(thermal_bridge_width 0.5)
			(island_removal_mode 0)
		)
		(polygon
			(pts
				(arc
					(start 446.974468 -247.485154)
					(mid 446.314068 -247.485154)
					(end 446.974468 -247.485154)
				)
			)
		)
	)
	(zone
		(layers "In1.Cu" "In2.Cu")
		(hatch none 0.5)
		(connect_pads
			(clearance 0)
		)
		(min_thickness 0.25)
		(keepout
			(tracks not_allowed)
			(vias allowed)
			(pads allowed)
			(copperpour not_allowed)
			(footprints allowed)
		)
		(placement
			(enabled no)
			(sheetname "")
		)
		(fill yes
			(thermal_gap 0.5)
			(thermal_bridge_width 0.5)
			(island_removal_mode 0)
		)
		(polygon
			(pts
				(arc
					(start 25.482296 -277.235412)
					(mid 24.821896 -277.235412)
					(end 25.482296 -277.235412)
				)
			)
		)
	)
	(zone
		(layers "In1.Cu" "In2.Cu")
		(hatch none 0.5)
		(connect_pads
			(clearance 0)
		)
		(min_thickness 0.25)
		(keepout
			(tracks not_allowed)
			(vias allowed)
			(pads allowed)
			(copperpour not_allowed)
			(footprints allowed)
		)
		(placement
			(enabled no)
			(sheetname "")
		)
		(fill yes
			(thermal_gap 0.5)
			(thermal_bridge_width 0.5)
			(island_removal_mode 0)
		)
		(polygon
			(pts
				(arc
					(start 37.126164 -294.235378)
					(mid 36.465764 -294.235378)
					(end 37.126164 -294.235378)
				)
			)
		)
	)
	(zone
		(layers "In1.Cu" "In2.Cu")
		(hatch none 0.5)
		(connect_pads
			(clearance 0)
		)
		(min_thickness 0.25)
		(keepout
			(tracks not_allowed)
			(vias allowed)
			(pads allowed)
			(copperpour not_allowed)
			(footprints allowed)
		)
		(placement
			(enabled no)
			(sheetname "")
		)
		(fill yes
			(thermal_gap 0.5)
			(thermal_bridge_width 0.5)
			(island_removal_mode 0)
		)
		(polygon
			(pts
				(arc
					(start 194.934332 -237.285276)
					(mid 194.273932 -237.285276)
					(end 194.934332 -237.285276)
				)
			)
		)
	)
	(zone
		(layers "In1.Cu" "In2.Cu")
		(hatch none 0.5)
		(connect_pads
			(clearance 0)
		)
		(min_thickness 0.25)
		(keepout
			(tracks not_allowed)
			(vias allowed)
			(pads allowed)
			(copperpour not_allowed)
			(footprints allowed)
		)
		(placement
			(enabled no)
			(sheetname "")
		)
		(fill yes
			(thermal_gap 0.5)
			(thermal_bridge_width 0.5)
			(island_removal_mode 0)
		)
		(polygon
			(pts
				(arc
					(start 442.8744 -314.635134)
					(mid 442.214 -314.635134)
					(end 442.8744 -314.635134)
				)
			)
		)
	)
	(zone
		(layers "In1.Cu" "In2.Cu")
		(hatch none 0.5)
		(connect_pads
			(clearance 0)
		)
		(min_thickness 0.25)
		(keepout
			(tracks not_allowed)
			(vias allowed)
			(pads allowed)
			(copperpour not_allowed)
			(footprints allowed)
		)
		(placement
			(enabled no)
			(sheetname "")
		)
		(fill yes
			(thermal_gap 0.5)
			(thermal_bridge_width 0.5)
			(island_removal_mode 0)
		)
		(polygon
			(pts
				(arc
					(start 427.786292 -250.03506)
					(mid 427.125892 -250.03506)
					(end 427.786292 -250.03506)
				)
			)
		)
	)
	(zone
		(layers "In1.Cu" "In2.Cu")
		(hatch none 0.5)
		(connect_pads
			(clearance 0)
		)
		(min_thickness 0.25)
		(keepout
			(tracks not_allowed)
			(vias allowed)
			(pads allowed)
			(copperpour not_allowed)
			(footprints allowed)
		)
		(placement
			(enabled no)
			(sheetname "")
		)
		(fill yes
			(thermal_gap 0.5)
			(thermal_bridge_width 0.5)
			(island_removal_mode 0)
		)
		(polygon
			(pts
				(arc
					(start 454.518268 -266.185142)
					(mid 453.857868 -266.185142)
					(end 454.518268 -266.185142)
				)
			)
		)
	)
	(zone
		(layers "In1.Cu" "In2.Cu")
		(hatch none 0.5)
		(connect_pads
			(clearance 0)
		)
		(min_thickness 0.25)
		(keepout
			(tracks not_allowed)
			(vias allowed)
			(pads allowed)
			(copperpour not_allowed)
			(footprints allowed)
		)
		(placement
			(enabled no)
			(sheetname "")
		)
		(fill yes
			(thermal_gap 0.5)
			(thermal_bridge_width 0.5)
			(island_removal_mode 0)
		)
		(polygon
			(pts
				(arc
					(start 396.952216 -7.672324)
					(mid 396.974534 -7.618442)
					(end 397.028416 -7.596124)
				)
				(arc
					(start 398.06499 -7.596124)
					(mid 398.118872 -7.618442)
					(end 398.14119 -7.672324)
				)
				(arc
					(start 398.14119 -9.071864)
					(mid 398.118872 -9.125746)
					(end 398.06499 -9.148064)
				)
				(arc
					(start 397.028416 -9.148064)
					(mid 396.974534 -9.125746)
					(end 396.952216 -9.071864)
				)
			)
		)
	)
	(zone
		(layers "In1.Cu" "In2.Cu")
		(hatch none 0.5)
		(connect_pads
			(clearance 0)
		)
		(min_thickness 0.25)
		(keepout
			(tracks not_allowed)
			(vias allowed)
			(pads allowed)
			(copperpour not_allowed)
			(footprints allowed)
		)
		(placement
			(enabled no)
			(sheetname "")
		)
		(fill yes
			(thermal_gap 0.5)
			(thermal_bridge_width 0.5)
			(island_removal_mode 0)
		)
		(polygon
			(pts
				(arc
					(start 292.610286 -221.985078)
					(mid 291.949886 -221.985078)
					(end 292.610286 -221.985078)
				)
			)
		)
	)
	(zone
		(layers "In1.Cu" "In2.Cu")
		(hatch none 0.5)
		(connect_pads
			(clearance 0)
		)
		(min_thickness 0.25)
		(keepout
			(tracks not_allowed)
			(vias allowed)
			(pads allowed)
			(copperpour not_allowed)
			(footprints allowed)
		)
		(placement
			(enabled no)
			(sheetname "")
		)
		(fill yes
			(thermal_gap 0.5)
			(thermal_bridge_width 0.5)
			(island_removal_mode 0)
		)
		(polygon
			(pts
				(arc
					(start 199.0344 -210.085432)
					(mid 198.374 -210.085432)
					(end 199.0344 -210.085432)
				)
			)
		)
	)
	(zone
		(layers "In1.Cu" "In2.Cu")
		(hatch none 0.5)
		(connect_pads
			(clearance 0)
		)
		(min_thickness 0.25)
		(keepout
			(tracks not_allowed)
			(vias allowed)
			(pads allowed)
			(copperpour not_allowed)
			(footprints allowed)
		)
		(placement
			(enabled no)
			(sheetname "")
		)
		(fill yes
			(thermal_gap 0.5)
			(thermal_bridge_width 0.5)
			(island_removal_mode 0)
		)
		(polygon
			(pts
				(arc
					(start 194.934332 -293.38524)
					(mid 194.273932 -293.38524)
					(end 194.934332 -293.38524)
				)
			)
		)
	)
	(zone
		(layers "In1.Cu" "In2.Cu")
		(hatch none 0.5)
		(connect_pads
			(clearance 0)
		)
		(min_thickness 0.25)
		(keepout
			(tracks not_allowed)
			(vias allowed)
			(pads allowed)
			(copperpour not_allowed)
			(footprints allowed)
		)
		(placement
			(enabled no)
			(sheetname "")
		)
		(fill yes
			(thermal_gap 0.5)
			(thermal_bridge_width 0.5)
			(island_removal_mode 0)
		)
		(polygon
			(pts
				(arc
					(start 25.482296 -222.835216)
					(mid 24.821896 -222.835216)
					(end 25.482296 -222.835216)
				)
			)
		)
	)
	(zone
		(layers "In1.Cu" "In2.Cu")
		(hatch none 0.5)
		(connect_pads
			(clearance 0)
		)
		(min_thickness 0.25)
		(keepout
			(tracks not_allowed)
			(vias allowed)
			(pads allowed)
			(copperpour not_allowed)
			(footprints allowed)
		)
		(placement
			(enabled no)
			(sheetname "")
		)
		(fill yes
			(thermal_gap 0.5)
			(thermal_bridge_width 0.5)
			(island_removal_mode 0)
		)
		(polygon
			(pts
				(arc
					(start 17.938242 -246.63527)
					(mid 17.277842 -246.63527)
					(end 17.938242 -246.63527)
				)
			)
		)
	)
	(zone
		(layers "In1.Cu" "In2.Cu")
		(hatch none 0.5)
		(connect_pads
			(clearance 0)
		)
		(min_thickness 0.25)
		(keepout
			(tracks not_allowed)
			(vias allowed)
			(pads allowed)
			(copperpour not_allowed)
			(footprints allowed)
		)
		(placement
			(enabled no)
			(sheetname "")
		)
		(fill yes
			(thermal_gap 0.5)
			(thermal_bridge_width 0.5)
			(island_removal_mode 0)
		)
		(polygon
			(pts
				(arc
					(start 427.786292 -215.18499)
					(mid 427.125892 -215.18499)
					(end 427.786292 -215.18499)
				)
			)
		)
	)
	(zone
		(layers "In1.Cu" "In2.Cu")
		(hatch none 0.5)
		(connect_pads
			(clearance 0)
		)
		(min_thickness 0.25)
		(keepout
			(tracks not_allowed)
			(vias allowed)
			(pads allowed)
			(copperpour not_allowed)
			(footprints allowed)
		)
		(placement
			(enabled no)
			(sheetname "")
		)
		(fill yes
			(thermal_gap 0.5)
			(thermal_bridge_width 0.5)
			(island_removal_mode 0)
		)
		(polygon
			(pts
				(arc
					(start 280.966164 -305.28514)
					(mid 280.305764 -305.28514)
					(end 280.966164 -305.28514)
				)
			)
		)
	)
	(zone
		(layers "In1.Cu" "In2.Cu")
		(hatch none 0.5)
		(connect_pads
			(clearance 0)
		)
		(min_thickness 0.25)
		(keepout
			(tracks not_allowed)
			(vias allowed)
			(pads allowed)
			(copperpour not_allowed)
			(footprints allowed)
		)
		(placement
			(enabled no)
			(sheetname "")
		)
		(fill yes
			(thermal_gap 0.5)
			(thermal_bridge_width 0.5)
			(island_removal_mode 0)
		)
		(polygon
			(pts
				(arc
					(start 446.974468 -197.33514)
					(mid 446.314068 -197.33514)
					(end 446.974468 -197.33514)
				)
			)
		)
	)
	(zone
		(layers "In1.Cu" "In2.Cu")
		(hatch none 0.5)
		(connect_pads
			(clearance 0)
		)
		(min_thickness 0.25)
		(keepout
			(tracks not_allowed)
			(vias allowed)
			(pads allowed)
			(copperpour not_allowed)
			(footprints allowed)
		)
		(placement
			(enabled no)
			(sheetname "")
		)
		(fill yes
			(thermal_gap 0.5)
			(thermal_bridge_width 0.5)
			(island_removal_mode 0)
		)
		(polygon
			(pts
				(arc
					(start 22.03831 -249.18543)
					(mid 21.37791 -249.18543)
					(end 22.03831 -249.18543)
				)
			)
		)
	)
	(zone
		(layers "In1.Cu" "In2.Cu")
		(hatch none 0.5)
		(connect_pads
			(clearance 0)
		)
		(min_thickness 0.25)
		(keepout
			(tracks not_allowed)
			(vias allowed)
			(pads allowed)
			(copperpour not_allowed)
			(footprints allowed)
		)
		(placement
			(enabled no)
			(sheetname "")
		)
		(fill yes
			(thermal_gap 0.5)
			(thermal_bridge_width 0.5)
			(island_removal_mode 0)
		)
		(polygon
			(pts
				(arc
					(start 44.670218 -311.235344)
					(mid 44.009818 -311.235344)
					(end 44.670218 -311.235344)
				)
			)
		)
	)
	(zone
		(layers "In1.Cu" "In2.Cu")
		(hatch none 0.5)
		(connect_pads
			(clearance 0)
		)
		(min_thickness 0.25)
		(keepout
			(tracks not_allowed)
			(vias allowed)
			(pads allowed)
			(copperpour not_allowed)
			(footprints allowed)
		)
		(placement
			(enabled no)
			(sheetname "")
		)
		(fill yes
			(thermal_gap 0.5)
			(thermal_bridge_width 0.5)
			(island_removal_mode 0)
		)
		(polygon
			(pts
				(arc
					(start 187.390278 -220.28531)
					(mid 186.729878 -220.28531)
					(end 187.390278 -220.28531)
				)
			)
		)
	)
	(zone
		(layers "In1.Cu" "In2.Cu")
		(hatch none 0.5)
		(connect_pads
			(clearance 0)
		)
		(min_thickness 0.25)
		(keepout
			(tracks not_allowed)
			(vias allowed)
			(pads allowed)
			(copperpour not_allowed)
			(footprints allowed)
		)
		(placement
			(enabled no)
			(sheetname "")
		)
		(fill yes
			(thermal_gap 0.5)
			(thermal_bridge_width 0.5)
			(island_removal_mode 0)
		)
		(polygon
			(pts
				(arc
					(start 450.4182 -239.835182)
					(mid 449.7578 -239.835182)
					(end 450.4182 -239.835182)
				)
			)
		)
	)
	(zone
		(layers "In1.Cu" "In2.Cu")
		(hatch none 0.5)
		(connect_pads
			(clearance 0)
		)
		(min_thickness 0.25)
		(keepout
			(tracks not_allowed)
			(vias allowed)
			(pads allowed)
			(copperpour not_allowed)
			(footprints allowed)
		)
		(placement
			(enabled no)
			(sheetname "")
		)
		(fill yes
			(thermal_gap 0.5)
			(thermal_bridge_width 0.5)
			(island_removal_mode 0)
		)
		(polygon
			(pts
				(arc
					(start 176.402238 -315.485272)
					(mid 175.741838 -315.485272)
					(end 176.402238 -315.485272)
				)
			)
		)
	)
	(zone
		(layers "In1.Cu" "In2.Cu")
		(hatch none 0.5)
		(connect_pads
			(clearance 0)
		)
		(min_thickness 0.25)
		(keepout
			(tracks not_allowed)
			(vias allowed)
			(pads allowed)
			(copperpour not_allowed)
			(footprints allowed)
		)
		(placement
			(enabled no)
			(sheetname "")
		)
		(fill yes
			(thermal_gap 0.5)
			(thermal_bridge_width 0.5)
			(island_removal_mode 0)
		)
		(polygon
			(pts
				(arc
					(start 285.066232 -284.88513)
					(mid 284.405832 -284.88513)
					(end 285.066232 -284.88513)
				)
			)
		)
	)
	(zone
		(layers "In1.Cu" "In2.Cu")
		(hatch none 0.5)
		(connect_pads
			(clearance 0)
		)
		(min_thickness 0.25)
		(keepout
			(tracks not_allowed)
			(vias allowed)
			(pads allowed)
			(copperpour not_allowed)
			(footprints allowed)
		)
		(placement
			(enabled no)
			(sheetname "")
		)
		(fill yes
			(thermal_gap 0.5)
			(thermal_bridge_width 0.5)
			(island_removal_mode 0)
		)
		(polygon
			(pts
				(arc
					(start 450.4182 -286.585152)
					(mid 449.7578 -286.585152)
					(end 450.4182 -286.585152)
				)
			)
		)
	)
	(zone
		(layers "In1.Cu" "In2.Cu")
		(hatch none 0.5)
		(connect_pads
			(clearance 0)
		)
		(min_thickness 0.25)
		(keepout
			(tracks not_allowed)
			(vias allowed)
			(pads allowed)
			(copperpour not_allowed)
			(footprints allowed)
		)
		(placement
			(enabled no)
			(sheetname "")
		)
		(fill yes
			(thermal_gap 0.5)
			(thermal_bridge_width 0.5)
			(island_removal_mode 0)
		)
		(polygon
			(pts
				(arc
					(start 52.214272 -285.735268)
					(mid 51.553872 -285.735268)
					(end 52.214272 -285.735268)
				)
			)
		)
	)
	(zone
		(layers "In1.Cu" "In2.Cu")
		(hatch none 0.5)
		(connect_pads
			(clearance 0)
		)
		(min_thickness 0.25)
		(keepout
			(tracks not_allowed)
			(vias allowed)
			(pads allowed)
			(copperpour not_allowed)
			(footprints allowed)
		)
		(placement
			(enabled no)
			(sheetname "")
		)
		(fill yes
			(thermal_gap 0.5)
			(thermal_bridge_width 0.5)
			(island_removal_mode 0)
		)
		(polygon
			(pts
				(arc
					(start 292.610286 -284.88513)
					(mid 291.949886 -284.88513)
					(end 292.610286 -284.88513)
				)
			)
		)
	)
	(zone
		(layers "In1.Cu" "In2.Cu")
		(hatch none 0.5)
		(connect_pads
			(clearance 0)
		)
		(min_thickness 0.25)
		(keepout
			(tracks not_allowed)
			(vias allowed)
			(pads allowed)
			(copperpour not_allowed)
			(footprints allowed)
		)
		(placement
			(enabled no)
			(sheetname "")
		)
		(fill yes
			(thermal_gap 0.5)
			(thermal_bridge_width 0.5)
			(island_removal_mode 0)
		)
		(polygon
			(pts
				(arc
					(start 40.57015 -261.935214)
					(mid 39.90975 -261.935214)
					(end 40.57015 -261.935214)
				)
			)
		)
	)
	(zone
		(layers "In1.Cu" "In2.Cu")
		(hatch none 0.5)
		(connect_pads
			(clearance 0)
		)
		(min_thickness 0.25)
		(keepout
			(tracks not_allowed)
			(vias allowed)
			(pads allowed)
			(copperpour not_allowed)
			(footprints allowed)
		)
		(placement
			(enabled no)
			(sheetname "")
		)
		(fill yes
			(thermal_gap 0.5)
			(thermal_bridge_width 0.5)
			(island_removal_mode 0)
		)
		(polygon
			(pts
				(arc
					(start 429.261524 -11.91768)
					(mid 429.239206 -11.971562)
					(end 429.185324 -11.99388)
				)
				(arc
					(start 428.14875 -11.99388)
					(mid 428.094868 -11.971562)
					(end 428.07255 -11.91768)
				)
				(arc
					(start 428.07255 -10.51814)
					(mid 428.094868 -10.464258)
					(end 428.14875 -10.44194)
				)
				(arc
					(start 429.185324 -10.44194)
					(mid 429.239206 -10.464258)
					(end 429.261524 -10.51814)
				)
			)
		)
	)
	(zone
		(layers "In1.Cu" "In2.Cu")
		(hatch none 0.5)
		(connect_pads
			(clearance 0)
		)
		(min_thickness 0.25)
		(keepout
			(tracks not_allowed)
			(vias allowed)
			(pads allowed)
			(copperpour not_allowed)
			(footprints allowed)
		)
		(placement
			(enabled no)
			(sheetname "")
		)
		(fill yes
			(thermal_gap 0.5)
			(thermal_bridge_width 0.5)
			(island_removal_mode 0)
		)
		(polygon
			(pts
				(arc
					(start 424.342306 -216.035128)
					(mid 423.681906 -216.035128)
					(end 424.342306 -216.035128)
				)
			)
		)
	)
	(zone
		(layers "In1.Cu" "In2.Cu")
		(hatch none 0.5)
		(connect_pads
			(clearance 0)
		)
		(min_thickness 0.25)
		(keepout
			(tracks not_allowed)
			(vias allowed)
			(pads allowed)
			(copperpour not_allowed)
			(footprints allowed)
		)
		(placement
			(enabled no)
			(sheetname "")
		)
		(fill yes
			(thermal_gap 0.5)
			(thermal_bridge_width 0.5)
			(island_removal_mode 0)
		)
		(polygon
			(pts
				(arc
					(start 442.8744 -205.834996)
					(mid 442.214 -205.834996)
					(end 442.8744 -205.834996)
				)
			)
		)
	)
	(zone
		(layers "In1.Cu" "In2.Cu")
		(hatch none 0.5)
		(connect_pads
			(clearance 0)
		)
		(min_thickness 0.25)
		(keepout
			(tracks not_allowed)
			(vias allowed)
			(pads allowed)
			(copperpour not_allowed)
			(footprints allowed)
		)
		(placement
			(enabled no)
			(sheetname "")
		)
		(fill yes
			(thermal_gap 0.5)
			(thermal_bridge_width 0.5)
			(island_removal_mode 0)
		)
		(polygon
			(pts
				(arc
					(start 450.4182 -229.63505)
					(mid 449.7578 -229.63505)
					(end 450.4182 -229.63505)
				)
			)
		)
	)
	(zone
		(layers "In1.Cu" "In2.Cu")
		(hatch none 0.5)
		(connect_pads
			(clearance 0)
		)
		(min_thickness 0.25)
		(keepout
			(tracks not_allowed)
			(vias allowed)
			(pads allowed)
			(copperpour not_allowed)
			(footprints allowed)
		)
		(placement
			(enabled no)
			(sheetname "")
		)
		(fill yes
			(thermal_gap 0.5)
			(thermal_bridge_width 0.5)
			(island_removal_mode 0)
		)
		(polygon
			(pts
				(arc
					(start 424.342306 -317.18504)
					(mid 423.681906 -317.18504)
					(end 424.342306 -317.18504)
				)
			)
		)
	)
	(zone
		(layers "In1.Cu" "In2.Cu")
		(hatch none 0.5)
		(connect_pads
			(clearance 0)
		)
		(min_thickness 0.25)
		(keepout
			(tracks not_allowed)
			(vias allowed)
			(pads allowed)
			(copperpour not_allowed)
			(footprints allowed)
		)
		(placement
			(enabled no)
			(sheetname "")
		)
		(fill yes
			(thermal_gap 0.5)
			(thermal_bridge_width 0.5)
			(island_removal_mode 0)
		)
		(polygon
			(pts
				(arc
					(start 48.114204 -285.735268)
					(mid 47.453804 -285.735268)
					(end 48.114204 -285.735268)
				)
			)
		)
	)
	(zone
		(layers "In1.Cu" "In2.Cu")
		(hatch none 0.5)
		(connect_pads
			(clearance 0)
		)
		(min_thickness 0.25)
		(keepout
			(tracks not_allowed)
			(vias allowed)
			(pads allowed)
			(copperpour not_allowed)
			(footprints allowed)
		)
		(placement
			(enabled no)
			(sheetname "")
		)
		(fill yes
			(thermal_gap 0.5)
			(thermal_bridge_width 0.5)
			(island_removal_mode 0)
		)
		(polygon
			(pts
				(arc
					(start 33.026096 -313.78525)
					(mid 32.365696 -313.78525)
					(end 33.026096 -313.78525)
				)
			)
		)
	)
	(zone
		(layers "In1.Cu" "In2.Cu")
		(hatch none 0.5)
		(connect_pads
			(clearance 0)
		)
		(min_thickness 0.25)
		(keepout
			(tracks not_allowed)
			(vias allowed)
			(pads allowed)
			(copperpour not_allowed)
			(footprints allowed)
		)
		(placement
			(enabled no)
			(sheetname "")
		)
		(fill yes
			(thermal_gap 0.5)
			(thermal_bridge_width 0.5)
			(island_removal_mode 0)
		)
		(polygon
			(pts
				(arc
					(start 415.267394 -17.967198)
					(mid 415.289712 -18.02108)
					(end 415.343594 -18.043398)
				)
				(arc
					(start 415.539174 -18.043398)
					(mid 415.56105 -18.040266)
					(end 415.581084 -18.030952)
				)
				(arc
					(start 415.874708 -17.83842)
					(mid 415.916364 -17.826018)
					(end 415.95802 -17.83842)
				)
				(arc
					(start 416.252914 -18.030952)
					(mid 416.272838 -18.040188)
					(end 416.29457 -18.043398)
				)
				(arc
					(start 416.489134 -18.043398)
					(mid 416.543016 -18.02108)
					(end 416.565334 -17.967198)
				)
				(arc
					(start 416.565334 -17.281398)
					(mid 416.543016 -17.227516)
					(end 416.489134 -17.205198)
				)
				(arc
					(start 416.29457 -17.205198)
					(mid 416.272826 -17.208366)
					(end 416.252914 -17.217644)
				)
				(arc
					(start 415.95675 -17.41043)
					(mid 415.915066 -17.422652)
					(end 415.873438 -17.410176)
				)
				(arc
					(start 415.579814 -17.217644)
					(mid 415.55989 -17.208408)
					(end 415.538158 -17.205198)
				)
				(arc
					(start 415.343594 -17.205198)
					(mid 415.289712 -17.227516)
					(end 415.267394 -17.281398)
				)
			)
		)
	)
	(zone
		(layers "In1.Cu" "In2.Cu")
		(hatch none 0.5)
		(connect_pads
			(clearance 0)
		)
		(min_thickness 0.25)
		(keepout
			(tracks not_allowed)
			(vias allowed)
			(pads allowed)
			(copperpour not_allowed)
			(footprints allowed)
		)
		(placement
			(enabled no)
			(sheetname "")
		)
		(fill yes
			(thermal_gap 0.5)
			(thermal_bridge_width 0.5)
			(island_removal_mode 0)
		)
		(polygon
			(pts
				(arc
					(start 172.30217 -306.985416)
					(mid 171.64177 -306.985416)
					(end 172.30217 -306.985416)
				)
			)
		)
	)
	(zone
		(layers "In1.Cu" "In2.Cu")
		(hatch none 0.5)
		(connect_pads
			(clearance 0)
		)
		(min_thickness 0.25)
		(keepout
			(tracks not_allowed)
			(vias allowed)
			(pads allowed)
			(copperpour not_allowed)
			(footprints allowed)
		)
		(placement
			(enabled no)
			(sheetname "")
		)
		(fill yes
			(thermal_gap 0.5)
			(thermal_bridge_width 0.5)
			(island_removal_mode 0)
		)
		(polygon
			(pts
				(arc
					(start 300.15434 -250.884944)
					(mid 299.49394 -250.884944)
					(end 300.15434 -250.884944)
				)
			)
		)
	)
	(zone
		(layers "In1.Cu" "In2.Cu")
		(hatch none 0.5)
		(connect_pads
			(clearance 0)
		)
		(min_thickness 0.25)
		(keepout
			(tracks not_allowed)
			(vias allowed)
			(pads allowed)
			(copperpour not_allowed)
			(footprints allowed)
		)
		(placement
			(enabled no)
			(sheetname "")
		)
		(fill yes
			(thermal_gap 0.5)
			(thermal_bridge_width 0.5)
			(island_removal_mode 0)
		)
		(polygon
			(pts
				(arc
					(start 194.934332 -280.635202)
					(mid 194.273932 -280.635202)
					(end 194.934332 -280.635202)
				)
			)
		)
	)
	(zone
		(layers "In1.Cu" "In2.Cu")
		(hatch none 0.5)
		(connect_pads
			(clearance 0)
		)
		(min_thickness 0.25)
		(keepout
			(tracks not_allowed)
			(vias allowed)
			(pads allowed)
			(copperpour not_allowed)
			(footprints allowed)
		)
		(placement
			(enabled no)
			(sheetname "")
		)
		(fill yes
			(thermal_gap 0.5)
			(thermal_bridge_width 0.5)
			(island_removal_mode 0)
		)
		(polygon
			(pts
				(arc
					(start 277.522432 -214.335106)
					(mid 276.862032 -214.335106)
					(end 277.522432 -214.335106)
				)
			)
		)
	)
	(zone
		(layers "In1.Cu" "In2.Cu")
		(hatch none 0.5)
		(connect_pads
			(clearance 0)
		)
		(min_thickness 0.25)
		(keepout
			(tracks not_allowed)
			(vias allowed)
			(pads allowed)
			(copperpour not_allowed)
			(footprints allowed)
		)
		(placement
			(enabled no)
			(sheetname "")
		)
		(fill yes
			(thermal_gap 0.5)
			(thermal_bridge_width 0.5)
			(island_removal_mode 0)
		)
		(polygon
			(pts
				(arc
					(start 300.15434 -242.385088)
					(mid 299.49394 -242.385088)
					(end 300.15434 -242.385088)
				)
			)
		)
	)
	(zone
		(layers "In1.Cu" "In2.Cu")
		(hatch none 0.5)
		(connect_pads
			(clearance 0)
		)
		(min_thickness 0.25)
		(keepout
			(tracks not_allowed)
			(vias allowed)
			(pads allowed)
			(copperpour not_allowed)
			(footprints allowed)
		)
		(placement
			(enabled no)
			(sheetname "")
		)
		(fill yes
			(thermal_gap 0.5)
			(thermal_bridge_width 0.5)
			(island_removal_mode 0)
		)
		(polygon
			(pts
				(arc
					(start 296.054272 -278.93518)
					(mid 295.393872 -278.93518)
					(end 296.054272 -278.93518)
				)
			)
		)
	)
	(zone
		(layers "In1.Cu" "In2.Cu")
		(hatch none 0.5)
		(connect_pads
			(clearance 0)
		)
		(min_thickness 0.25)
		(keepout
			(tracks not_allowed)
			(vias allowed)
			(pads allowed)
			(copperpour not_allowed)
			(footprints allowed)
		)
		(placement
			(enabled no)
			(sheetname "")
		)
		(fill yes
			(thermal_gap 0.5)
			(thermal_bridge_width 0.5)
			(island_removal_mode 0)
		)
		(polygon
			(pts
				(arc
					(start 33.026096 -246.63527)
					(mid 32.365696 -246.63527)
					(end 33.026096 -246.63527)
				)
			)
		)
	)
	(zone
		(layers "In1.Cu" "In2.Cu")
		(hatch none 0.5)
		(connect_pads
			(clearance 0)
		)
		(min_thickness 0.25)
		(keepout
			(tracks not_allowed)
			(vias allowed)
			(pads allowed)
			(copperpour not_allowed)
			(footprints allowed)
		)
		(placement
			(enabled no)
			(sheetname "")
		)
		(fill yes
			(thermal_gap 0.5)
			(thermal_bridge_width 0.5)
			(island_removal_mode 0)
		)
		(polygon
			(pts
				(arc
					(start 446.974468 -234.735116)
					(mid 446.314068 -234.735116)
					(end 446.974468 -234.735116)
				)
			)
		)
	)
	(zone
		(layers "In1.Cu" "In2.Cu")
		(hatch none 0.5)
		(connect_pads
			(clearance 0)
		)
		(min_thickness 0.25)
		(keepout
			(tracks not_allowed)
			(vias allowed)
			(pads allowed)
			(copperpour not_allowed)
			(footprints allowed)
		)
		(placement
			(enabled no)
			(sheetname "")
		)
		(fill yes
			(thermal_gap 0.5)
			(thermal_bridge_width 0.5)
			(island_removal_mode 0)
		)
		(polygon
			(pts
				(arc
					(start 17.938242 -243.235226)
					(mid 17.277842 -243.235226)
					(end 17.938242 -243.235226)
				)
			)
		)
	)
	(zone
		(layers "In1.Cu" "In2.Cu")
		(hatch none 0.5)
		(connect_pads
			(clearance 0)
		)
		(min_thickness 0.25)
		(keepout
			(tracks not_allowed)
			(vias allowed)
			(pads allowed)
			(copperpour not_allowed)
			(footprints allowed)
		)
		(placement
			(enabled no)
			(sheetname "")
		)
		(fill yes
			(thermal_gap 0.5)
			(thermal_bridge_width 0.5)
			(island_removal_mode 0)
		)
		(polygon
			(pts
				(arc
					(start 136.36498 -28.06192)
					(mid 136.329059 -28.076799)
					(end 136.31418 -28.11272)
				)
				(arc
					(start 136.31418 -29.38272)
					(mid 136.329059 -29.418641)
					(end 136.36498 -29.43352)
				)
				(arc
					(start 136.64438 -29.43352)
					(mid 136.680301 -29.418641)
					(end 136.69518 -29.38272)
				)
				(arc
					(start 136.69518 -28.11272)
					(mid 136.680301 -28.076799)
					(end 136.64438 -28.06192)
				)
			)
		)
	)
	(zone
		(layers "In1.Cu" "In2.Cu")
		(hatch none 0.5)
		(connect_pads
			(clearance 0)
		)
		(min_thickness 0.25)
		(keepout
			(tracks not_allowed)
			(vias allowed)
			(pads allowed)
			(copperpour not_allowed)
			(footprints allowed)
		)
		(placement
			(enabled no)
			(sheetname "")
		)
		(fill yes
			(thermal_gap 0.5)
			(thermal_bridge_width 0.5)
			(island_removal_mode 0)
		)
		(polygon
			(pts
				(arc
					(start 199.0344 -221.985332)
					(mid 198.374 -221.985332)
					(end 199.0344 -221.985332)
				)
			)
		)
	)
	(zone
		(layers "In1.Cu" "In2.Cu")
		(hatch none 0.5)
		(connect_pads
			(clearance 0)
		)
		(min_thickness 0.25)
		(keepout
			(tracks not_allowed)
			(vias allowed)
			(pads allowed)
			(copperpour not_allowed)
			(footprints allowed)
		)
		(placement
			(enabled no)
			(sheetname "")
		)
		(fill yes
			(thermal_gap 0.5)
			(thermal_bridge_width 0.5)
			(island_removal_mode 0)
		)
		(polygon
			(pts
				(arc
					(start 44.670218 -212.635338)
					(mid 44.009818 -212.635338)
					(end 44.670218 -212.635338)
				)
			)
		)
	)
	(zone
		(layers "In1.Cu" "In2.Cu")
		(hatch none 0.5)
		(connect_pads
			(clearance 0)
		)
		(min_thickness 0.25)
		(keepout
			(tracks not_allowed)
			(vias allowed)
			(pads allowed)
			(copperpour not_allowed)
			(footprints allowed)
		)
		(placement
			(enabled no)
			(sheetname "")
		)
		(fill yes
			(thermal_gap 0.5)
			(thermal_bridge_width 0.5)
			(island_removal_mode 0)
		)
		(polygon
			(pts
				(arc
					(start 183.946292 -279.785318)
					(mid 183.285892 -279.785318)
					(end 183.946292 -279.785318)
				)
			)
		)
	)
	(zone
		(layers "In1.Cu" "In2.Cu")
		(hatch none 0.5)
		(connect_pads
			(clearance 0)
		)
		(min_thickness 0.25)
		(keepout
			(tracks not_allowed)
			(vias allowed)
			(pads allowed)
			(copperpour not_allowed)
			(footprints allowed)
		)
		(placement
			(enabled no)
			(sheetname "")
		)
		(fill yes
			(thermal_gap 0.5)
			(thermal_bridge_width 0.5)
			(island_removal_mode 0)
		)
		(polygon
			(pts
				(arc
					(start 424.342306 -315.485018)
					(mid 423.681906 -315.485018)
					(end 424.342306 -315.485018)
				)
			)
		)
	)
	(zone
		(layers "In1.Cu" "In2.Cu")
		(hatch none 0.5)
		(connect_pads
			(clearance 0)
		)
		(min_thickness 0.25)
		(keepout
			(tracks not_allowed)
			(vias allowed)
			(pads allowed)
			(copperpour not_allowed)
			(footprints allowed)
		)
		(placement
			(enabled no)
			(sheetname "")
		)
		(fill yes
			(thermal_gap 0.5)
			(thermal_bridge_width 0.5)
			(island_removal_mode 0)
		)
		(polygon
			(pts
				(arc
					(start 413.02559 -381.824484)
					(mid 413.045514 -381.83372)
					(end 413.067246 -381.83693)
				)
				(arc
					(start 413.26181 -381.83693)
					(mid 413.315692 -381.814612)
					(end 413.33801 -381.76073)
				)
				(arc
					(start 413.33801 -381.07493)
					(mid 413.315692 -381.021048)
					(end 413.26181 -380.99873)
				)
				(arc
					(start 413.067246 -380.99873)
					(mid 413.045502 -381.001898)
					(end 413.02559 -381.011176)
				)
				(arc
					(start 412.729426 -381.203962)
					(mid 412.687742 -381.216184)
					(end 412.646114 -381.203708)
				)
				(arc
					(start 412.35249 -381.011176)
					(mid 412.332566 -381.00194)
					(end 412.310834 -380.99873)
				)
				(arc
					(start 412.11627 -380.99873)
					(mid 412.062388 -381.021048)
					(end 412.04007 -381.07493)
				)
				(arc
					(start 412.04007 -381.76073)
					(mid 412.062388 -381.814612)
					(end 412.11627 -381.83693)
				)
				(arc
					(start 412.312104 -381.83693)
					(mid 412.333848 -381.833762)
					(end 412.35376 -381.824484)
				)
				(arc
					(start 412.647384 -381.631952)
					(mid 412.68904 -381.61955)
					(end 412.730696 -381.631952)
				)
			)
		)
	)
	(zone
		(layers "In1.Cu" "In2.Cu")
		(hatch none 0.5)
		(connect_pads
			(clearance 0)
		)
		(min_thickness 0.25)
		(keepout
			(tracks not_allowed)
			(vias allowed)
			(pads allowed)
			(copperpour not_allowed)
			(footprints allowed)
		)
		(placement
			(enabled no)
			(sheetname "")
		)
		(fill yes
			(thermal_gap 0.5)
			(thermal_bridge_width 0.5)
			(island_removal_mode 0)
		)
		(polygon
			(pts
				(arc
					(start 280.966164 -238.985044)
					(mid 280.305764 -238.985044)
					(end 280.966164 -238.985044)
				)
			)
		)
	)
	(zone
		(layers "In1.Cu" "In2.Cu")
		(hatch none 0.5)
		(connect_pads
			(clearance 0)
		)
		(min_thickness 0.25)
		(keepout
			(tracks not_allowed)
			(vias allowed)
			(pads allowed)
			(copperpour not_allowed)
			(footprints allowed)
		)
		(placement
			(enabled no)
			(sheetname "")
		)
		(fill yes
			(thermal_gap 0.5)
			(thermal_bridge_width 0.5)
			(island_removal_mode 0)
		)
		(polygon
			(pts
				(arc
					(start 25.482296 -241.535204)
					(mid 24.821896 -241.535204)
					(end 25.482296 -241.535204)
				)
			)
		)
	)
	(zone
		(layers "In1.Cu" "In2.Cu")
		(hatch none 0.5)
		(connect_pads
			(clearance 0)
		)
		(min_thickness 0.25)
		(keepout
			(tracks not_allowed)
			(vias allowed)
			(pads allowed)
			(copperpour not_allowed)
			(footprints allowed)
		)
		(placement
			(enabled no)
			(sheetname "")
		)
		(fill yes
			(thermal_gap 0.5)
			(thermal_bridge_width 0.5)
			(island_removal_mode 0)
		)
		(polygon
			(pts
				(arc
					(start 292.610286 -240.685066)
					(mid 291.949886 -240.685066)
					(end 292.610286 -240.685066)
				)
			)
		)
	)
	(zone
		(layers "In1.Cu" "In2.Cu")
		(hatch none 0.5)
		(connect_pads
			(clearance 0)
		)
		(min_thickness 0.25)
		(keepout
			(tracks not_allowed)
			(vias allowed)
			(pads allowed)
			(copperpour not_allowed)
			(footprints allowed)
		)
		(placement
			(enabled no)
			(sheetname "")
		)
		(fill yes
			(thermal_gap 0.5)
			(thermal_bridge_width 0.5)
			(island_removal_mode 0)
		)
		(polygon
			(pts
				(arc
					(start 176.402238 -300.185328)
					(mid 175.741838 -300.185328)
					(end 176.402238 -300.185328)
				)
			)
		)
	)
	(zone
		(layers "In1.Cu" "In2.Cu")
		(hatch none 0.5)
		(connect_pads
			(clearance 0)
		)
		(min_thickness 0.25)
		(keepout
			(tracks not_allowed)
			(vias allowed)
			(pads allowed)
			(copperpour not_allowed)
			(footprints allowed)
		)
		(placement
			(enabled no)
			(sheetname "")
		)
		(fill yes
			(thermal_gap 0.5)
			(thermal_bridge_width 0.5)
			(island_removal_mode 0)
		)
		(polygon
			(pts
				(arc
					(start 439.430414 -301.885096)
					(mid 438.770014 -301.885096)
					(end 439.430414 -301.885096)
				)
			)
		)
	)
	(zone
		(layers "In1.Cu" "In2.Cu")
		(hatch none 0.5)
		(connect_pads
			(clearance 0)
		)
		(min_thickness 0.25)
		(keepout
			(tracks not_allowed)
			(vias allowed)
			(pads allowed)
			(copperpour not_allowed)
			(footprints allowed)
		)
		(placement
			(enabled no)
			(sheetname "")
		)
		(fill yes
			(thermal_gap 0.5)
			(thermal_bridge_width 0.5)
			(island_removal_mode 0)
		)
		(polygon
			(pts
				(arc
					(start 431.88636 -254.284988)
					(mid 431.22596 -254.284988)
					(end 431.88636 -254.284988)
				)
			)
		)
	)
	(zone
		(layers "In1.Cu" "In2.Cu")
		(hatch none 0.5)
		(connect_pads
			(clearance 0)
		)
		(min_thickness 0.25)
		(keepout
			(tracks not_allowed)
			(vias allowed)
			(pads allowed)
			(copperpour not_allowed)
			(footprints allowed)
		)
		(placement
			(enabled no)
			(sheetname "")
		)
		(fill yes
			(thermal_gap 0.5)
			(thermal_bridge_width 0.5)
			(island_removal_mode 0)
		)
		(polygon
			(pts
				(arc
					(start 442.8744 -250.03506)
					(mid 442.214 -250.03506)
					(end 442.8744 -250.03506)
				)
			)
		)
	)
	(zone
		(layers "In1.Cu" "In2.Cu")
		(hatch none 0.5)
		(connect_pads
			(clearance 0)
		)
		(min_thickness 0.25)
		(keepout
			(tracks not_allowed)
			(vias allowed)
			(pads allowed)
			(copperpour not_allowed)
			(footprints allowed)
		)
		(placement
			(enabled no)
			(sheetname "")
		)
		(fill yes
			(thermal_gap 0.5)
			(thermal_bridge_width 0.5)
			(island_removal_mode 0)
		)
		(polygon
			(pts
				(arc
					(start 29.582364 -303.585372)
					(mid 28.921964 -303.585372)
					(end 29.582364 -303.585372)
				)
			)
		)
	)
	(zone
		(layers "In1.Cu" "In2.Cu")
		(hatch none 0.5)
		(connect_pads
			(clearance 0)
		)
		(min_thickness 0.25)
		(keepout
			(tracks not_allowed)
			(vias allowed)
			(pads allowed)
			(copperpour not_allowed)
			(footprints allowed)
		)
		(placement
			(enabled no)
			(sheetname "")
		)
		(fill yes
			(thermal_gap 0.5)
			(thermal_bridge_width 0.5)
			(island_removal_mode 0)
		)
		(polygon
			(pts
				(arc
					(start 29.582364 -295.085262)
					(mid 28.921964 -295.085262)
					(end 29.582364 -295.085262)
				)
			)
		)
	)
	(zone
		(layers "In1.Cu" "In2.Cu")
		(hatch none 0.5)
		(connect_pads
			(clearance 0)
		)
		(min_thickness 0.25)
		(keepout
			(tracks not_allowed)
			(vias allowed)
			(pads allowed)
			(copperpour not_allowed)
			(footprints allowed)
		)
		(placement
			(enabled no)
			(sheetname "")
		)
		(fill yes
			(thermal_gap 0.5)
			(thermal_bridge_width 0.5)
			(island_removal_mode 0)
		)
		(polygon
			(pts
				(arc
					(start 172.30217 -237.285276)
					(mid 171.64177 -237.285276)
					(end 172.30217 -237.285276)
				)
			)
		)
	)
	(zone
		(layers "In1.Cu" "In2.Cu")
		(hatch none 0.5)
		(connect_pads
			(clearance 0)
		)
		(min_thickness 0.25)
		(keepout
			(tracks not_allowed)
			(vias allowed)
			(pads allowed)
			(copperpour not_allowed)
			(footprints allowed)
		)
		(placement
			(enabled no)
			(sheetname "")
		)
		(fill yes
			(thermal_gap 0.5)
			(thermal_bridge_width 0.5)
			(island_removal_mode 0)
		)
		(polygon
			(pts
				(arc
					(start 420.242238 -310.384952)
					(mid 419.581838 -310.384952)
					(end 420.242238 -310.384952)
				)
			)
		)
	)
	(zone
		(layers "In1.Cu" "In2.Cu")
		(hatch none 0.5)
		(connect_pads
			(clearance 0)
		)
		(min_thickness 0.25)
		(keepout
			(tracks not_allowed)
			(vias allowed)
			(pads allowed)
			(copperpour not_allowed)
			(footprints allowed)
		)
		(placement
			(enabled no)
			(sheetname "")
		)
		(fill yes
			(thermal_gap 0.5)
			(thermal_bridge_width 0.5)
			(island_removal_mode 0)
		)
		(polygon
			(pts
				(arc
					(start 277.522432 -296.78503)
					(mid 276.862032 -296.78503)
					(end 277.522432 -296.78503)
				)
			)
		)
	)
	(zone
		(layers "In1.Cu" "In2.Cu")
		(hatch none 0.5)
		(connect_pads
			(clearance 0)
		)
		(min_thickness 0.25)
		(keepout
			(tracks not_allowed)
			(vias allowed)
			(pads allowed)
			(copperpour not_allowed)
			(footprints allowed)
		)
		(placement
			(enabled no)
			(sheetname "")
		)
		(fill yes
			(thermal_gap 0.5)
			(thermal_bridge_width 0.5)
			(island_removal_mode 0)
		)
		(polygon
			(pts
				(arc
					(start 292.610286 -266.185142)
					(mid 291.949886 -266.185142)
					(end 292.610286 -266.185142)
				)
			)
		)
	)
	(zone
		(layers "In1.Cu" "In2.Cu")
		(hatch none 0.5)
		(connect_pads
			(clearance 0)
		)
		(min_thickness 0.25)
		(keepout
			(tracks not_allowed)
			(vias allowed)
			(pads allowed)
			(copperpour not_allowed)
			(footprints allowed)
		)
		(placement
			(enabled no)
			(sheetname "")
		)
		(fill yes
			(thermal_gap 0.5)
			(thermal_bridge_width 0.5)
			(island_removal_mode 0)
		)
		(polygon
			(pts
				(arc
					(start 25.482296 -312.085228)
					(mid 24.821896 -312.085228)
					(end 25.482296 -312.085228)
				)
			)
		)
	)
	(zone
		(layers "In1.Cu" "In2.Cu")
		(hatch none 0.5)
		(connect_pads
			(clearance 0)
		)
		(min_thickness 0.25)
		(keepout
			(tracks not_allowed)
			(vias allowed)
			(pads allowed)
			(copperpour not_allowed)
			(footprints allowed)
		)
		(placement
			(enabled no)
			(sheetname "")
		)
		(fill yes
			(thermal_gap 0.5)
			(thermal_bridge_width 0.5)
			(island_removal_mode 0)
		)
		(polygon
			(pts
				(arc
					(start 442.8744 -243.234972)
					(mid 442.214 -243.234972)
					(end 442.8744 -243.234972)
				)
			)
		)
	)
	(zone
		(layers "In1.Cu" "In2.Cu")
		(hatch none 0.5)
		(connect_pads
			(clearance 0)
		)
		(min_thickness 0.25)
		(keepout
			(tracks not_allowed)
			(vias allowed)
			(pads allowed)
			(copperpour not_allowed)
			(footprints allowed)
		)
		(placement
			(enabled no)
			(sheetname "")
		)
		(fill yes
			(thermal_gap 0.5)
			(thermal_bridge_width 0.5)
			(island_removal_mode 0)
		)
		(polygon
			(pts
				(arc
					(start 176.402238 -296.785284)
					(mid 175.741838 -296.785284)
					(end 176.402238 -296.785284)
				)
			)
		)
	)
	(zone
		(layers "In1.Cu" "In2.Cu")
		(hatch none 0.5)
		(connect_pads
			(clearance 0)
		)
		(min_thickness 0.25)
		(keepout
			(tracks not_allowed)
			(vias allowed)
			(pads allowed)
			(copperpour not_allowed)
			(footprints allowed)
		)
		(placement
			(enabled no)
			(sheetname "")
		)
		(fill yes
			(thermal_gap 0.5)
			(thermal_bridge_width 0.5)
			(island_removal_mode 0)
		)
		(polygon
			(pts
				(arc
					(start 52.214272 -312.935366)
					(mid 51.553872 -312.935366)
					(end 52.214272 -312.935366)
				)
			)
		)
	)
	(zone
		(layers "In1.Cu" "In2.Cu")
		(hatch none 0.5)
		(connect_pads
			(clearance 0)
		)
		(min_thickness 0.25)
		(keepout
			(tracks not_allowed)
			(vias allowed)
			(pads allowed)
			(copperpour not_allowed)
			(footprints allowed)
		)
		(placement
			(enabled no)
			(sheetname "")
		)
		(fill yes
			(thermal_gap 0.5)
			(thermal_bridge_width 0.5)
			(island_removal_mode 0)
		)
		(polygon
			(pts
				(arc
					(start 29.582364 -244.085364)
					(mid 28.921964 -244.085364)
					(end 29.582364 -244.085364)
				)
			)
		)
	)
	(zone
		(layers "In1.Cu" "In2.Cu")
		(hatch none 0.5)
		(connect_pads
			(clearance 0)
		)
		(min_thickness 0.25)
		(keepout
			(tracks not_allowed)
			(vias allowed)
			(pads allowed)
			(copperpour not_allowed)
			(footprints allowed)
		)
		(placement
			(enabled no)
			(sheetname "")
		)
		(fill yes
			(thermal_gap 0.5)
			(thermal_bridge_width 0.5)
			(island_removal_mode 0)
		)
		(polygon
			(pts
				(arc
					(start 450.4182 -244.934994)
					(mid 449.7578 -244.934994)
					(end 450.4182 -244.934994)
				)
			)
		)
	)
	(zone
		(layers "In1.Cu" "In2.Cu")
		(hatch none 0.5)
		(connect_pads
			(clearance 0)
		)
		(min_thickness 0.25)
		(keepout
			(tracks not_allowed)
			(vias allowed)
			(pads allowed)
			(copperpour not_allowed)
			(footprints allowed)
		)
		(placement
			(enabled no)
			(sheetname "")
		)
		(fill yes
			(thermal_gap 0.5)
			(thermal_bridge_width 0.5)
			(island_removal_mode 0)
		)
		(polygon
			(pts
				(arc
					(start 37.126164 -216.035382)
					(mid 36.465764 -216.035382)
					(end 37.126164 -216.035382)
				)
			)
		)
	)
	(zone
		(layers "In1.Cu" "In2.Cu")
		(hatch none 0.5)
		(connect_pads
			(clearance 0)
		)
		(min_thickness 0.25)
		(keepout
			(tracks not_allowed)
			(vias allowed)
			(pads allowed)
			(copperpour not_allowed)
			(footprints allowed)
		)
		(placement
			(enabled no)
			(sheetname "")
		)
		(fill yes
			(thermal_gap 0.5)
			(thermal_bridge_width 0.5)
			(island_removal_mode 0)
		)
		(polygon
			(pts
				(arc
					(start 424.342306 -300.185074)
					(mid 423.681906 -300.185074)
					(end 424.342306 -300.185074)
				)
			)
		)
	)
	(zone
		(layers "In1.Cu" "In2.Cu")
		(hatch none 0.5)
		(connect_pads
			(clearance 0)
		)
		(min_thickness 0.25)
		(keepout
			(tracks not_allowed)
			(vias allowed)
			(pads allowed)
			(copperpour not_allowed)
			(footprints allowed)
		)
		(placement
			(enabled no)
			(sheetname "")
		)
		(fill yes
			(thermal_gap 0.5)
			(thermal_bridge_width 0.5)
			(island_removal_mode 0)
		)
		(polygon
			(pts
				(arc
					(start 420.242238 -232.184956)
					(mid 419.581838 -232.184956)
					(end 420.242238 -232.184956)
				)
			)
		)
	)
	(zone
		(layers "In1.Cu" "In2.Cu")
		(hatch none 0.5)
		(connect_pads
			(clearance 0)
		)
		(min_thickness 0.25)
		(keepout
			(tracks not_allowed)
			(vias allowed)
			(pads allowed)
			(copperpour not_allowed)
			(footprints allowed)
		)
		(placement
			(enabled no)
			(sheetname "")
		)
		(fill yes
			(thermal_gap 0.5)
			(thermal_bridge_width 0.5)
			(island_removal_mode 0)
		)
		(polygon
			(pts
				(arc
					(start 40.57015 -284.035246)
					(mid 39.90975 -284.035246)
					(end 40.57015 -284.035246)
				)
			)
		)
	)
	(zone
		(layers "In1.Cu" "In2.Cu")
		(hatch none 0.5)
		(connect_pads
			(clearance 0)
		)
		(min_thickness 0.25)
		(keepout
			(tracks not_allowed)
			(vias allowed)
			(pads allowed)
			(copperpour not_allowed)
			(footprints allowed)
		)
		(placement
			(enabled no)
			(sheetname "")
		)
		(fill yes
			(thermal_gap 0.5)
			(thermal_bridge_width 0.5)
			(island_removal_mode 0)
		)
		(polygon
			(pts
				(arc
					(start 33.026096 -276.385274)
					(mid 32.365696 -276.385274)
					(end 33.026096 -276.385274)
				)
			)
		)
	)
	(zone
		(layers "In1.Cu" "In2.Cu")
		(hatch none 0.5)
		(connect_pads
			(clearance 0)
		)
		(min_thickness 0.25)
		(keepout
			(tracks not_allowed)
			(vias allowed)
			(pads allowed)
			(copperpour not_allowed)
			(footprints allowed)
		)
		(placement
			(enabled no)
			(sheetname "")
		)
		(fill yes
			(thermal_gap 0.5)
			(thermal_bridge_width 0.5)
			(island_removal_mode 0)
		)
		(polygon
			(pts
				(arc
					(start 44.670218 -278.085296)
					(mid 44.009818 -278.085296)
					(end 44.670218 -278.085296)
				)
			)
		)
	)
	(zone
		(layers "In1.Cu" "In2.Cu")
		(hatch none 0.5)
		(connect_pads
			(clearance 0)
		)
		(min_thickness 0.25)
		(keepout
			(tracks not_allowed)
			(vias allowed)
			(pads allowed)
			(copperpour not_allowed)
			(footprints allowed)
		)
		(placement
			(enabled no)
			(sheetname "")
		)
		(fill yes
			(thermal_gap 0.5)
			(thermal_bridge_width 0.5)
			(island_removal_mode 0)
		)
		(polygon
			(pts
				(arc
					(start 40.57015 -251.735336)
					(mid 39.90975 -251.735336)
					(end 40.57015 -251.735336)
				)
			)
		)
	)
	(zone
		(layers "In1.Cu" "In2.Cu")
		(hatch none 0.5)
		(connect_pads
			(clearance 0)
		)
		(min_thickness 0.25)
		(keepout
			(tracks not_allowed)
			(vias allowed)
			(pads allowed)
			(copperpour not_allowed)
			(footprints allowed)
		)
		(placement
			(enabled no)
			(sheetname "")
		)
		(fill yes
			(thermal_gap 0.5)
			(thermal_bridge_width 0.5)
			(island_removal_mode 0)
		)
		(polygon
			(pts
				(arc
					(start 442.8744 -295.085008)
					(mid 442.214 -295.085008)
					(end 442.8744 -295.085008)
				)
			)
		)
	)
	(zone
		(layers "In1.Cu" "In2.Cu")
		(hatch none 0.5)
		(connect_pads
			(clearance 0)
		)
		(min_thickness 0.25)
		(keepout
			(tracks not_allowed)
			(vias allowed)
			(pads allowed)
			(copperpour not_allowed)
			(footprints allowed)
		)
		(placement
			(enabled no)
			(sheetname "")
		)
		(fill yes
			(thermal_gap 0.5)
			(thermal_bridge_width 0.5)
			(island_removal_mode 0)
		)
		(polygon
			(pts
				(arc
					(start 177.832258 -47.058834)
					(mid 177.88614 -47.081152)
					(end 177.908458 -47.135034)
				)
				(arc
					(start 177.908458 -47.965106)
					(mid 177.88614 -48.018988)
					(end 177.832258 -48.041306)
				)
				(arc
					(start 176.384458 -48.041306)
					(mid 176.330576 -48.018988)
					(end 176.308258 -47.965106)
				)
				(arc
					(start 176.308258 -47.135034)
					(mid 176.330576 -47.081152)
					(end 176.384458 -47.058834)
				)
			)
		)
	)
	(zone
		(layers "In1.Cu" "In2.Cu")
		(hatch none 0.5)
		(connect_pads
			(clearance 0)
		)
		(min_thickness 0.25)
		(keepout
			(tracks not_allowed)
			(vias allowed)
			(pads allowed)
			(copperpour not_allowed)
			(footprints allowed)
		)
		(placement
			(enabled no)
			(sheetname "")
		)
		(fill yes
			(thermal_gap 0.5)
			(thermal_bridge_width 0.5)
			(island_removal_mode 0)
		)
		(polygon
			(pts
				(arc
					(start 179.846224 -220.28531)
					(mid 179.185824 -220.28531)
					(end 179.846224 -220.28531)
				)
			)
		)
	)
	(zone
		(layers "In1.Cu" "In2.Cu")
		(hatch none 0.5)
		(connect_pads
			(clearance 0)
		)
		(min_thickness 0.25)
		(keepout
			(tracks not_allowed)
			(vias allowed)
			(pads allowed)
			(copperpour not_allowed)
			(footprints allowed)
		)
		(placement
			(enabled no)
			(sheetname "")
		)
		(fill yes
			(thermal_gap 0.5)
			(thermal_bridge_width 0.5)
			(island_removal_mode 0)
		)
		(polygon
			(pts
				(arc
					(start 454.518268 -229.63505)
					(mid 453.857868 -229.63505)
					(end 454.518268 -229.63505)
				)
			)
		)
	)
	(zone
		(layers "In1.Cu" "In2.Cu")
		(hatch none 0.5)
		(connect_pads
			(clearance 0)
		)
		(min_thickness 0.25)
		(keepout
			(tracks not_allowed)
			(vias allowed)
			(pads allowed)
			(copperpour not_allowed)
			(footprints allowed)
		)
		(placement
			(enabled no)
			(sheetname "")
		)
		(fill yes
			(thermal_gap 0.5)
			(thermal_bridge_width 0.5)
			(island_removal_mode 0)
		)
		(polygon
			(pts
				(arc
					(start 199.0344 -307.8353)
					(mid 198.374 -307.8353)
					(end 199.0344 -307.8353)
				)
			)
		)
	)
	(zone
		(layers "In1.Cu" "In2.Cu")
		(hatch none 0.5)
		(connect_pads
			(clearance 0)
		)
		(min_thickness 0.25)
		(keepout
			(tracks not_allowed)
			(vias allowed)
			(pads allowed)
			(copperpour not_allowed)
			(footprints allowed)
		)
		(placement
			(enabled no)
			(sheetname "")
		)
		(fill yes
			(thermal_gap 0.5)
			(thermal_bridge_width 0.5)
			(island_removal_mode 0)
		)
		(polygon
			(pts
				(arc
					(start 427.786292 -241.53495)
					(mid 427.125892 -241.53495)
					(end 427.786292 -241.53495)
				)
			)
		)
	)
	(zone
		(layers "In1.Cu" "In2.Cu")
		(hatch none 0.5)
		(connect_pads
			(clearance 0)
		)
		(min_thickness 0.25)
		(keepout
			(tracks not_allowed)
			(vias allowed)
			(pads allowed)
			(copperpour not_allowed)
			(footprints allowed)
		)
		(placement
			(enabled no)
			(sheetname "")
		)
		(fill yes
			(thermal_gap 0.5)
			(thermal_bridge_width 0.5)
			(island_removal_mode 0)
		)
		(polygon
			(pts
				(arc
					(start 202.478132 -291.685218)
					(mid 201.817732 -291.685218)
					(end 202.478132 -291.685218)
				)
			)
		)
	)
	(zone
		(layers "In1.Cu" "In2.Cu")
		(hatch none 0.5)
		(connect_pads
			(clearance 0)
		)
		(min_thickness 0.25)
		(keepout
			(tracks not_allowed)
			(vias allowed)
			(pads allowed)
			(copperpour not_allowed)
			(footprints allowed)
		)
		(placement
			(enabled no)
			(sheetname "")
		)
		(fill yes
			(thermal_gap 0.5)
			(thermal_bridge_width 0.5)
			(island_removal_mode 0)
		)
		(polygon
			(pts
				(arc
					(start 48.114204 -299.335444)
					(mid 47.453804 -299.335444)
					(end 48.114204 -299.335444)
				)
			)
		)
	)
	(zone
		(layers "In1.Cu" "In2.Cu")
		(hatch none 0.5)
		(connect_pads
			(clearance 0)
		)
		(min_thickness 0.25)
		(keepout
			(tracks not_allowed)
			(vias allowed)
			(pads allowed)
			(copperpour not_allowed)
			(footprints allowed)
		)
		(placement
			(enabled no)
			(sheetname "")
		)
		(fill yes
			(thermal_gap 0.5)
			(thermal_bridge_width 0.5)
			(island_removal_mode 0)
		)
		(polygon
			(pts
				(arc
					(start 300.15434 -284.88513)
					(mid 299.49394 -284.88513)
					(end 300.15434 -284.88513)
				)
			)
		)
	)
	(zone
		(layers "In1.Cu" "In2.Cu")
		(hatch none 0.5)
		(connect_pads
			(clearance 0)
		)
		(min_thickness 0.25)
		(keepout
			(tracks not_allowed)
			(vias allowed)
			(pads allowed)
			(copperpour not_allowed)
			(footprints allowed)
		)
		(placement
			(enabled no)
			(sheetname "")
		)
		(fill yes
			(thermal_gap 0.5)
			(thermal_bridge_width 0.5)
			(island_removal_mode 0)
		)
		(polygon
			(pts
				(arc
					(start 33.026096 -215.185244)
					(mid 32.365696 -215.185244)
					(end 33.026096 -215.185244)
				)
			)
		)
	)
	(zone
		(layers "In1.Cu" "In2.Cu")
		(hatch none 0.5)
		(connect_pads
			(clearance 0)
		)
		(min_thickness 0.25)
		(keepout
			(tracks not_allowed)
			(vias allowed)
			(pads allowed)
			(copperpour not_allowed)
			(footprints allowed)
		)
		(placement
			(enabled no)
			(sheetname "")
		)
		(fill yes
			(thermal_gap 0.5)
			(thermal_bridge_width 0.5)
			(island_removal_mode 0)
		)
		(polygon
			(pts
				(arc
					(start 442.8744 -233.884978)
					(mid 442.214 -233.884978)
					(end 442.8744 -233.884978)
				)
			)
		)
	)
	(zone
		(layers "In1.Cu" "In2.Cu")
		(hatch none 0.5)
		(connect_pads
			(clearance 0)
		)
		(min_thickness 0.25)
		(keepout
			(tracks not_allowed)
			(vias allowed)
			(pads allowed)
			(copperpour not_allowed)
			(footprints allowed)
		)
		(placement
			(enabled no)
			(sheetname "")
		)
		(fill yes
			(thermal_gap 0.5)
			(thermal_bridge_width 0.5)
			(island_removal_mode 0)
		)
		(polygon
			(pts
				(arc
					(start 288.510218 -238.985044)
					(mid 287.849818 -238.985044)
					(end 288.510218 -238.985044)
				)
			)
		)
	)
	(zone
		(layers "In1.Cu" "In2.Cu")
		(hatch none 0.5)
		(connect_pads
			(clearance 0)
		)
		(min_thickness 0.25)
		(keepout
			(tracks not_allowed)
			(vias allowed)
			(pads allowed)
			(copperpour not_allowed)
			(footprints allowed)
		)
		(placement
			(enabled no)
			(sheetname "")
		)
		(fill yes
			(thermal_gap 0.5)
			(thermal_bridge_width 0.5)
			(island_removal_mode 0)
		)
		(polygon
			(pts
				(arc
					(start 285.066232 -231.335072)
					(mid 284.405832 -231.335072)
					(end 285.066232 -231.335072)
				)
			)
		)
	)
	(zone
		(layers "In1.Cu" "In2.Cu")
		(hatch none 0.5)
		(connect_pads
			(clearance 0)
		)
		(min_thickness 0.25)
		(keepout
			(tracks not_allowed)
			(vias allowed)
			(pads allowed)
			(copperpour not_allowed)
			(footprints allowed)
		)
		(placement
			(enabled no)
			(sheetname "")
		)
		(fill yes
			(thermal_gap 0.5)
			(thermal_bridge_width 0.5)
			(island_removal_mode 0)
		)
		(polygon
			(pts
				(arc
					(start 37.126164 -272.135346)
					(mid 36.465764 -272.135346)
					(end 37.126164 -272.135346)
				)
			)
		)
	)
	(zone
		(layers "In1.Cu" "In2.Cu")
		(hatch none 0.5)
		(connect_pads
			(clearance 0)
		)
		(min_thickness 0.25)
		(keepout
			(tracks not_allowed)
			(vias allowed)
			(pads allowed)
			(copperpour not_allowed)
			(footprints allowed)
		)
		(placement
			(enabled no)
			(sheetname "")
		)
		(fill yes
			(thermal_gap 0.5)
			(thermal_bridge_width 0.5)
			(island_removal_mode 0)
		)
		(polygon
			(pts
				(arc
					(start 442.8744 -201.585068)
					(mid 442.214 -201.585068)
					(end 442.8744 -201.585068)
				)
			)
		)
	)
	(zone
		(layers "In1.Cu" "In2.Cu")
		(hatch none 0.5)
		(connect_pads
			(clearance 0)
		)
		(min_thickness 0.25)
		(keepout
			(tracks not_allowed)
			(vias allowed)
			(pads allowed)
			(copperpour not_allowed)
			(footprints allowed)
		)
		(placement
			(enabled no)
			(sheetname "")
		)
		(fill yes
			(thermal_gap 0.5)
			(thermal_bridge_width 0.5)
			(island_removal_mode 0)
		)
		(polygon
			(pts
				(arc
					(start 431.88636 -273.835114)
					(mid 431.22596 -273.835114)
					(end 431.88636 -273.835114)
				)
			)
		)
	)
	(zone
		(layers "In1.Cu" "In2.Cu")
		(hatch none 0.5)
		(connect_pads
			(clearance 0)
		)
		(min_thickness 0.25)
		(keepout
			(tracks not_allowed)
			(vias allowed)
			(pads allowed)
			(copperpour not_allowed)
			(footprints allowed)
		)
		(placement
			(enabled no)
			(sheetname "")
		)
		(fill yes
			(thermal_gap 0.5)
			(thermal_bridge_width 0.5)
			(island_removal_mode 0)
		)
		(polygon
			(pts
				(arc
					(start 409.373578 -17.967198)
					(mid 409.395896 -18.02108)
					(end 409.449778 -18.043398)
				)
				(arc
					(start 409.645358 -18.043398)
					(mid 409.667234 -18.040266)
					(end 409.687268 -18.030952)
				)
				(arc
					(start 409.980892 -17.83842)
					(mid 410.022548 -17.826018)
					(end 410.064204 -17.83842)
				)
				(arc
					(start 410.359098 -18.030952)
					(mid 410.379022 -18.040188)
					(end 410.400754 -18.043398)
				)
				(arc
					(start 410.595318 -18.043398)
					(mid 410.6492 -18.02108)
					(end 410.671518 -17.967198)
				)
				(arc
					(start 410.671518 -17.281398)
					(mid 410.6492 -17.227516)
					(end 410.595318 -17.205198)
				)
				(arc
					(start 410.400754 -17.205198)
					(mid 410.37901 -17.208366)
					(end 410.359098 -17.217644)
				)
				(arc
					(start 410.062934 -17.41043)
					(mid 410.02125 -17.422652)
					(end 409.979622 -17.410176)
				)
				(arc
					(start 409.685998 -17.217644)
					(mid 409.666074 -17.208408)
					(end 409.644342 -17.205198)
				)
				(arc
					(start 409.449778 -17.205198)
					(mid 409.395896 -17.227516)
					(end 409.373578 -17.281398)
				)
			)
		)
	)
	(zone
		(layers "In1.Cu" "In2.Cu")
		(hatch none 0.5)
		(connect_pads
			(clearance 0)
		)
		(min_thickness 0.25)
		(keepout
			(tracks not_allowed)
			(vias allowed)
			(pads allowed)
			(copperpour not_allowed)
			(footprints allowed)
		)
		(placement
			(enabled no)
			(sheetname "")
		)
		(fill yes
			(thermal_gap 0.5)
			(thermal_bridge_width 0.5)
			(island_removal_mode 0)
		)
		(polygon
			(pts
				(arc
					(start 37.126164 -238.135414)
					(mid 36.465764 -238.135414)
					(end 37.126164 -238.135414)
				)
			)
		)
	)
	(zone
		(layers "In1.Cu" "In2.Cu")
		(hatch none 0.5)
		(connect_pads
			(clearance 0)
		)
		(min_thickness 0.25)
		(keepout
			(tracks not_allowed)
			(vias allowed)
			(pads allowed)
			(copperpour not_allowed)
			(footprints allowed)
		)
		(placement
			(enabled no)
			(sheetname "")
		)
		(fill yes
			(thermal_gap 0.5)
			(thermal_bridge_width 0.5)
			(island_removal_mode 0)
		)
		(polygon
			(pts
				(arc
					(start 194.934332 -277.235412)
					(mid 194.273932 -277.235412)
					(end 194.934332 -277.235412)
				)
			)
		)
	)
	(zone
		(layers "In1.Cu" "In2.Cu")
		(hatch none 0.5)
		(connect_pads
			(clearance 0)
		)
		(min_thickness 0.25)
		(keepout
			(tracks not_allowed)
			(vias allowed)
			(pads allowed)
			(copperpour not_allowed)
			(footprints allowed)
		)
		(placement
			(enabled no)
			(sheetname "")
		)
		(fill yes
			(thermal_gap 0.5)
			(thermal_bridge_width 0.5)
			(island_removal_mode 0)
		)
		(polygon
			(pts
				(arc
					(start 52.214272 -292.535356)
					(mid 51.553872 -292.535356)
					(end 52.214272 -292.535356)
				)
			)
		)
	)
	(zone
		(layers "In1.Cu" "In2.Cu")
		(hatch none 0.5)
		(connect_pads
			(clearance 0)
		)
		(min_thickness 0.25)
		(keepout
			(tracks not_allowed)
			(vias allowed)
			(pads allowed)
			(copperpour not_allowed)
			(footprints allowed)
		)
		(placement
			(enabled no)
			(sheetname "")
		)
		(fill yes
			(thermal_gap 0.5)
			(thermal_bridge_width 0.5)
			(island_removal_mode 0)
		)
		(polygon
			(pts
				(arc
					(start 292.610286 -283.185108)
					(mid 291.949886 -283.185108)
					(end 292.610286 -283.185108)
				)
			)
		)
	)
	(zone
		(layers "In1.Cu" "In2.Cu")
		(hatch none 0.5)
		(connect_pads
			(clearance 0)
		)
		(min_thickness 0.25)
		(keepout
			(tracks not_allowed)
			(vias allowed)
			(pads allowed)
			(copperpour not_allowed)
			(footprints allowed)
		)
		(placement
			(enabled no)
			(sheetname "")
		)
		(fill yes
			(thermal_gap 0.5)
			(thermal_bridge_width 0.5)
			(island_removal_mode 0)
		)
		(polygon
			(pts
				(arc
					(start 172.30217 -289.98545)
					(mid 171.64177 -289.98545)
					(end 172.30217 -289.98545)
				)
			)
		)
	)
	(zone
		(layers "In1.Cu" "In2.Cu")
		(hatch none 0.5)
		(connect_pads
			(clearance 0)
		)
		(min_thickness 0.25)
		(keepout
			(tracks not_allowed)
			(vias allowed)
			(pads allowed)
			(copperpour not_allowed)
			(footprints allowed)
		)
		(placement
			(enabled no)
			(sheetname "")
		)
		(fill yes
			(thermal_gap 0.5)
			(thermal_bridge_width 0.5)
			(island_removal_mode 0)
		)
		(polygon
			(pts
				(arc
					(start 288.510218 -295.085008)
					(mid 287.849818 -295.085008)
					(end 288.510218 -295.085008)
				)
			)
		)
	)
	(zone
		(layers "In1.Cu" "In2.Cu")
		(hatch none 0.5)
		(connect_pads
			(clearance 0)
		)
		(min_thickness 0.25)
		(keepout
			(tracks not_allowed)
			(vias allowed)
			(pads allowed)
			(copperpour not_allowed)
			(footprints allowed)
		)
		(placement
			(enabled no)
			(sheetname "")
		)
		(fill yes
			(thermal_gap 0.5)
			(thermal_bridge_width 0.5)
			(island_removal_mode 0)
		)
		(polygon
			(pts
				(arc
					(start 194.934332 -235.585254)
					(mid 194.273932 -235.585254)
					(end 194.934332 -235.585254)
				)
			)
		)
	)
	(zone
		(layers "In1.Cu" "In2.Cu")
		(hatch none 0.5)
		(connect_pads
			(clearance 0)
		)
		(min_thickness 0.25)
		(keepout
			(tracks not_allowed)
			(vias allowed)
			(pads allowed)
			(copperpour not_allowed)
			(footprints allowed)
		)
		(placement
			(enabled no)
			(sheetname "")
		)
		(fill yes
			(thermal_gap 0.5)
			(thermal_bridge_width 0.5)
			(island_removal_mode 0)
		)
		(polygon
			(pts
				(arc
					(start 273.422364 -308.685184)
					(mid 272.761964 -308.685184)
					(end 273.422364 -308.685184)
				)
			)
		)
	)
	(zone
		(layers "In1.Cu" "In2.Cu")
		(hatch none 0.5)
		(connect_pads
			(clearance 0)
		)
		(min_thickness 0.25)
		(keepout
			(tracks not_allowed)
			(vias allowed)
			(pads allowed)
			(copperpour not_allowed)
			(footprints allowed)
		)
		(placement
			(enabled no)
			(sheetname "")
		)
		(fill yes
			(thermal_gap 0.5)
			(thermal_bridge_width 0.5)
			(island_removal_mode 0)
		)
		(polygon
			(pts
				(arc
					(start 439.430414 -229.63505)
					(mid 438.770014 -229.63505)
					(end 439.430414 -229.63505)
				)
			)
		)
	)
	(zone
		(layers "In1.Cu" "In2.Cu")
		(hatch none 0.5)
		(connect_pads
			(clearance 0)
		)
		(min_thickness 0.25)
		(keepout
			(tracks not_allowed)
			(vias allowed)
			(pads allowed)
			(copperpour not_allowed)
			(footprints allowed)
		)
		(placement
			(enabled no)
			(sheetname "")
		)
		(fill yes
			(thermal_gap 0.5)
			(thermal_bridge_width 0.5)
			(island_removal_mode 0)
		)
		(polygon
			(pts
				(arc
					(start 194.934332 -202.435206)
					(mid 194.273932 -202.435206)
					(end 194.934332 -202.435206)
				)
			)
		)
	)
	(zone
		(layers "In1.Cu" "In2.Cu")
		(hatch none 0.5)
		(connect_pads
			(clearance 0)
		)
		(min_thickness 0.25)
		(keepout
			(tracks not_allowed)
			(vias allowed)
			(pads allowed)
			(copperpour not_allowed)
			(footprints allowed)
		)
		(placement
			(enabled no)
			(sheetname "")
		)
		(fill yes
			(thermal_gap 0.5)
			(thermal_bridge_width 0.5)
			(island_removal_mode 0)
		)
		(polygon
			(pts
				(arc
					(start 427.786292 -285.735014)
					(mid 427.125892 -285.735014)
					(end 427.786292 -285.735014)
				)
			)
		)
	)
	(zone
		(layers "In1.Cu" "In2.Cu")
		(hatch none 0.5)
		(connect_pads
			(clearance 0)
		)
		(min_thickness 0.25)
		(keepout
			(tracks not_allowed)
			(vias allowed)
			(pads allowed)
			(copperpour not_allowed)
			(footprints allowed)
		)
		(placement
			(enabled no)
			(sheetname "")
		)
		(fill yes
			(thermal_gap 0.5)
			(thermal_bridge_width 0.5)
			(island_removal_mode 0)
		)
		(polygon
			(pts
				(arc
					(start 191.490346 -247.485408)
					(mid 190.829946 -247.485408)
					(end 191.490346 -247.485408)
				)
			)
		)
	)
	(zone
		(layers "In1.Cu" "In2.Cu")
		(hatch none 0.5)
		(connect_pads
			(clearance 0)
		)
		(min_thickness 0.25)
		(keepout
			(tracks not_allowed)
			(vias allowed)
			(pads allowed)
			(copperpour not_allowed)
			(footprints allowed)
		)
		(placement
			(enabled no)
			(sheetname "")
		)
		(fill yes
			(thermal_gap 0.5)
			(thermal_bridge_width 0.5)
			(island_removal_mode 0)
		)
		(polygon
			(pts
				(arc
					(start 454.518268 -238.985044)
					(mid 453.857868 -238.985044)
					(end 454.518268 -238.985044)
				)
			)
		)
	)
	(zone
		(layers "In1.Cu" "In2.Cu")
		(hatch none 0.5)
		(connect_pads
			(clearance 0)
		)
		(min_thickness 0.25)
		(keepout
			(tracks not_allowed)
			(vias allowed)
			(pads allowed)
			(copperpour not_allowed)
			(footprints allowed)
		)
		(placement
			(enabled no)
			(sheetname "")
		)
		(fill yes
			(thermal_gap 0.5)
			(thermal_bridge_width 0.5)
			(island_removal_mode 0)
		)
		(polygon
			(pts
				(arc
					(start 454.518268 -283.185108)
					(mid 453.857868 -283.185108)
					(end 454.518268 -283.185108)
				)
			)
		)
	)
	(zone
		(layers "In1.Cu" "In2.Cu")
		(hatch none 0.5)
		(connect_pads
			(clearance 0)
		)
		(min_thickness 0.25)
		(keepout
			(tracks not_allowed)
			(vias allowed)
			(pads allowed)
			(copperpour not_allowed)
			(footprints allowed)
		)
		(placement
			(enabled no)
			(sheetname "")
		)
		(fill yes
			(thermal_gap 0.5)
			(thermal_bridge_width 0.5)
			(island_removal_mode 0)
		)
		(polygon
			(pts
				(arc
					(start 427.786292 -276.38502)
					(mid 427.125892 -276.38502)
					(end 427.786292 -276.38502)
				)
			)
		)
	)
	(zone
		(layers "In1.Cu" "In2.Cu")
		(hatch none 0.5)
		(connect_pads
			(clearance 0)
		)
		(min_thickness 0.25)
		(keepout
			(tracks not_allowed)
			(vias allowed)
			(pads allowed)
			(copperpour not_allowed)
			(footprints allowed)
		)
		(placement
			(enabled no)
			(sheetname "")
		)
		(fill yes
			(thermal_gap 0.5)
			(thermal_bridge_width 0.5)
			(island_removal_mode 0)
		)
		(polygon
			(pts
				(arc
					(start 285.066232 -290.83508)
					(mid 284.405832 -290.83508)
					(end 285.066232 -290.83508)
				)
			)
		)
	)
	(zone
		(layers "In1.Cu" "In2.Cu")
		(hatch none 0.5)
		(connect_pads
			(clearance 0)
		)
		(min_thickness 0.25)
		(keepout
			(tracks not_allowed)
			(vias allowed)
			(pads allowed)
			(copperpour not_allowed)
			(footprints allowed)
		)
		(placement
			(enabled no)
			(sheetname "")
		)
		(fill yes
			(thermal_gap 0.5)
			(thermal_bridge_width 0.5)
			(island_removal_mode 0)
		)
		(polygon
			(pts
				(arc
					(start 292.610286 -298.485052)
					(mid 291.949886 -298.485052)
					(end 292.610286 -298.485052)
				)
			)
		)
	)
	(zone
		(layers "In1.Cu" "In2.Cu")
		(hatch none 0.5)
		(connect_pads
			(clearance 0)
		)
		(min_thickness 0.25)
		(keepout
			(tracks not_allowed)
			(vias allowed)
			(pads allowed)
			(copperpour not_allowed)
			(footprints allowed)
		)
		(placement
			(enabled no)
			(sheetname "")
		)
		(fill yes
			(thermal_gap 0.5)
			(thermal_bridge_width 0.5)
			(island_removal_mode 0)
		)
		(polygon
			(pts
				(arc
					(start 187.390278 -276.385274)
					(mid 186.729878 -276.385274)
					(end 187.390278 -276.385274)
				)
			)
		)
	)
	(zone
		(layers "In1.Cu" "In2.Cu")
		(hatch none 0.5)
		(connect_pads
			(clearance 0)
		)
		(min_thickness 0.25)
		(keepout
			(tracks not_allowed)
			(vias allowed)
			(pads allowed)
			(copperpour not_allowed)
			(footprints allowed)
		)
		(placement
			(enabled no)
			(sheetname "")
		)
		(fill yes
			(thermal_gap 0.5)
			(thermal_bridge_width 0.5)
			(island_removal_mode 0)
		)
		(polygon
			(pts
				(arc
					(start 172.30217 -272.98523)
					(mid 171.64177 -272.98523)
					(end 172.30217 -272.98523)
				)
			)
		)
	)
	(zone
		(layers "In1.Cu" "In2.Cu")
		(hatch none 0.5)
		(connect_pads
			(clearance 0)
		)
		(min_thickness 0.25)
		(keepout
			(tracks not_allowed)
			(vias allowed)
			(pads allowed)
			(copperpour not_allowed)
			(footprints allowed)
		)
		(placement
			(enabled no)
			(sheetname "")
		)
		(fill yes
			(thermal_gap 0.5)
			(thermal_bridge_width 0.5)
			(island_removal_mode 0)
		)
		(polygon
			(pts
				(arc
					(start 442.8744 -254.284988)
					(mid 442.214 -254.284988)
					(end 442.8744 -254.284988)
				)
			)
		)
	)
	(zone
		(layers "In1.Cu" "In2.Cu")
		(hatch none 0.5)
		(connect_pads
			(clearance 0)
		)
		(min_thickness 0.25)
		(keepout
			(tracks not_allowed)
			(vias allowed)
			(pads allowed)
			(copperpour not_allowed)
			(footprints allowed)
		)
		(placement
			(enabled no)
			(sheetname "")
		)
		(fill yes
			(thermal_gap 0.5)
			(thermal_bridge_width 0.5)
			(island_removal_mode 0)
		)
		(polygon
			(pts
				(arc
					(start 183.946292 -278.085296)
					(mid 183.285892 -278.085296)
					(end 183.946292 -278.085296)
				)
			)
		)
	)
	(zone
		(layers "In1.Cu" "In2.Cu")
		(hatch none 0.5)
		(connect_pads
			(clearance 0)
		)
		(min_thickness 0.25)
		(keepout
			(tracks not_allowed)
			(vias allowed)
			(pads allowed)
			(copperpour not_allowed)
			(footprints allowed)
		)
		(placement
			(enabled no)
			(sheetname "")
		)
		(fill yes
			(thermal_gap 0.5)
			(thermal_bridge_width 0.5)
			(island_removal_mode 0)
		)
		(polygon
			(pts
				(arc
					(start 446.974468 -231.335072)
					(mid 446.314068 -231.335072)
					(end 446.974468 -231.335072)
				)
			)
		)
	)
	(zone
		(layers "In1.Cu" "In2.Cu")
		(hatch none 0.5)
		(connect_pads
			(clearance 0)
		)
		(min_thickness 0.25)
		(keepout
			(tracks not_allowed)
			(vias allowed)
			(pads allowed)
			(copperpour not_allowed)
			(footprints allowed)
		)
		(placement
			(enabled no)
			(sheetname "")
		)
		(fill yes
			(thermal_gap 0.5)
			(thermal_bridge_width 0.5)
			(island_removal_mode 0)
		)
		(polygon
			(pts
				(arc
					(start 44.670218 -244.08511)
					(mid 44.009818 -244.08511)
					(end 44.670218 -244.08511)
				)
			)
		)
	)
	(zone
		(layers "In1.Cu" "In2.Cu")
		(hatch none 0.5)
		(connect_pads
			(clearance 0)
		)
		(min_thickness 0.25)
		(keepout
			(tracks not_allowed)
			(vias allowed)
			(pads allowed)
			(copperpour not_allowed)
			(footprints allowed)
		)
		(placement
			(enabled no)
			(sheetname "")
		)
		(fill yes
			(thermal_gap 0.5)
			(thermal_bridge_width 0.5)
			(island_removal_mode 0)
		)
		(polygon
			(pts
				(arc
					(start 176.402238 -287.43529)
					(mid 175.741838 -287.43529)
					(end 176.402238 -287.43529)
				)
			)
		)
	)
	(zone
		(layers "In1.Cu" "In2.Cu")
		(hatch none 0.5)
		(connect_pads
			(clearance 0)
		)
		(min_thickness 0.25)
		(keepout
			(tracks not_allowed)
			(vias allowed)
			(pads allowed)
			(copperpour not_allowed)
			(footprints allowed)
		)
		(placement
			(enabled no)
			(sheetname "")
		)
		(fill yes
			(thermal_gap 0.5)
			(thermal_bridge_width 0.5)
			(island_removal_mode 0)
		)
		(polygon
			(pts
				(arc
					(start 191.490346 -238.985298)
					(mid 190.829946 -238.985298)
					(end 191.490346 -238.985298)
				)
			)
		)
	)
	(zone
		(layers "In1.Cu" "In2.Cu")
		(hatch none 0.5)
		(connect_pads
			(clearance 0)
		)
		(min_thickness 0.25)
		(keepout
			(tracks not_allowed)
			(vias allowed)
			(pads allowed)
			(copperpour not_allowed)
			(footprints allowed)
		)
		(placement
			(enabled no)
			(sheetname "")
		)
		(fill yes
			(thermal_gap 0.5)
			(thermal_bridge_width 0.5)
			(island_removal_mode 0)
		)
		(polygon
			(pts
				(arc
					(start 199.0344 -242.385342)
					(mid 198.374 -242.385342)
					(end 199.0344 -242.385342)
				)
			)
		)
	)
	(zone
		(layers "In1.Cu" "In2.Cu")
		(hatch none 0.5)
		(connect_pads
			(clearance 0)
		)
		(min_thickness 0.25)
		(keepout
			(tracks not_allowed)
			(vias allowed)
			(pads allowed)
			(copperpour not_allowed)
			(footprints allowed)
		)
		(placement
			(enabled no)
			(sheetname "")
		)
		(fill yes
			(thermal_gap 0.5)
			(thermal_bridge_width 0.5)
			(island_removal_mode 0)
		)
		(polygon
			(pts
				(arc
					(start 40.57015 -274.685252)
					(mid 39.90975 -274.685252)
					(end 40.57015 -274.685252)
				)
			)
		)
	)
	(zone
		(layers "In1.Cu" "In2.Cu")
		(hatch none 0.5)
		(connect_pads
			(clearance 0)
		)
		(min_thickness 0.25)
		(keepout
			(tracks not_allowed)
			(vias allowed)
			(pads allowed)
			(copperpour not_allowed)
			(footprints allowed)
		)
		(placement
			(enabled no)
			(sheetname "")
		)
		(fill yes
			(thermal_gap 0.5)
			(thermal_bridge_width 0.5)
			(island_removal_mode 0)
		)
		(polygon
			(pts
				(arc
					(start 273.422364 -221.13494)
					(mid 272.761964 -221.13494)
					(end 273.422364 -221.13494)
				)
			)
		)
	)
	(zone
		(layers "In1.Cu" "In2.Cu")
		(hatch none 0.5)
		(connect_pads
			(clearance 0)
		)
		(min_thickness 0.25)
		(keepout
			(tracks not_allowed)
			(vias allowed)
			(pads allowed)
			(copperpour not_allowed)
			(footprints allowed)
		)
		(placement
			(enabled no)
			(sheetname "")
		)
		(fill yes
			(thermal_gap 0.5)
			(thermal_bridge_width 0.5)
			(island_removal_mode 0)
		)
		(polygon
			(pts
				(arc
					(start 292.610286 -238.13516)
					(mid 291.949886 -238.13516)
					(end 292.610286 -238.13516)
				)
			)
		)
	)
	(zone
		(layers "In1.Cu" "In2.Cu")
		(hatch none 0.5)
		(connect_pads
			(clearance 0)
		)
		(min_thickness 0.25)
		(keepout
			(tracks not_allowed)
			(vias allowed)
			(pads allowed)
			(copperpour not_allowed)
			(footprints allowed)
		)
		(placement
			(enabled no)
			(sheetname "")
		)
		(fill yes
			(thermal_gap 0.5)
			(thermal_bridge_width 0.5)
			(island_removal_mode 0)
		)
		(polygon
			(pts
				(arc
					(start 183.946292 -210.085432)
					(mid 183.285892 -210.085432)
					(end 183.946292 -210.085432)
				)
			)
		)
	)
	(zone
		(layers "In1.Cu" "In2.Cu")
		(hatch none 0.5)
		(connect_pads
			(clearance 0)
		)
		(min_thickness 0.25)
		(keepout
			(tracks not_allowed)
			(vias allowed)
			(pads allowed)
			(copperpour not_allowed)
			(footprints allowed)
		)
		(placement
			(enabled no)
			(sheetname "")
		)
		(fill yes
			(thermal_gap 0.5)
			(thermal_bridge_width 0.5)
			(island_removal_mode 0)
		)
		(polygon
			(pts
				(arc
					(start 285.066232 -229.63505)
					(mid 284.405832 -229.63505)
					(end 285.066232 -229.63505)
				)
			)
		)
	)
	(zone
		(layers "In1.Cu" "In2.Cu")
		(hatch none 0.5)
		(connect_pads
			(clearance 0)
		)
		(min_thickness 0.25)
		(keepout
			(tracks not_allowed)
			(vias allowed)
			(pads allowed)
			(copperpour not_allowed)
			(footprints allowed)
		)
		(placement
			(enabled no)
			(sheetname "")
		)
		(fill yes
			(thermal_gap 0.5)
			(thermal_bridge_width 0.5)
			(island_removal_mode 0)
		)
		(polygon
			(pts
				(arc
					(start 183.946292 -311.235344)
					(mid 183.285892 -311.235344)
					(end 183.946292 -311.235344)
				)
			)
		)
	)
	(zone
		(layers "In1.Cu" "In2.Cu")
		(hatch none 0.5)
		(connect_pads
			(clearance 0)
		)
		(min_thickness 0.25)
		(keepout
			(tracks not_allowed)
			(vias allowed)
			(pads allowed)
			(copperpour not_allowed)
			(footprints allowed)
		)
		(placement
			(enabled no)
			(sheetname "")
		)
		(fill yes
			(thermal_gap 0.5)
			(thermal_bridge_width 0.5)
			(island_removal_mode 0)
		)
		(polygon
			(pts
				(arc
					(start 22.03831 -312.935366)
					(mid 21.37791 -312.935366)
					(end 22.03831 -312.935366)
				)
			)
		)
	)
	(zone
		(layers "In1.Cu" "In2.Cu")
		(hatch none 0.5)
		(connect_pads
			(clearance 0)
		)
		(min_thickness 0.25)
		(keepout
			(tracks not_allowed)
			(vias allowed)
			(pads allowed)
			(copperpour not_allowed)
			(footprints allowed)
		)
		(placement
			(enabled no)
			(sheetname "")
		)
		(fill yes
			(thermal_gap 0.5)
			(thermal_bridge_width 0.5)
			(island_removal_mode 0)
		)
		(polygon
			(pts
				(arc
					(start 48.114204 -268.735302)
					(mid 47.453804 -268.735302)
					(end 48.114204 -268.735302)
				)
			)
		)
	)
	(zone
		(layers "In1.Cu" "In2.Cu")
		(hatch none 0.5)
		(connect_pads
			(clearance 0)
		)
		(min_thickness 0.25)
		(keepout
			(tracks not_allowed)
			(vias allowed)
			(pads allowed)
			(copperpour not_allowed)
			(footprints allowed)
		)
		(placement
			(enabled no)
			(sheetname "")
		)
		(fill yes
			(thermal_gap 0.5)
			(thermal_bridge_width 0.5)
			(island_removal_mode 0)
		)
		(polygon
			(pts
				(arc
					(start 285.066232 -307.835046)
					(mid 284.405832 -307.835046)
					(end 285.066232 -307.835046)
				)
			)
		)
	)
	(zone
		(layers "In1.Cu" "In2.Cu")
		(hatch none 0.5)
		(connect_pads
			(clearance 0)
		)
		(min_thickness 0.25)
		(keepout
			(tracks not_allowed)
			(vias allowed)
			(pads allowed)
			(copperpour not_allowed)
			(footprints allowed)
		)
		(placement
			(enabled no)
			(sheetname "")
		)
		(fill yes
			(thermal_gap 0.5)
			(thermal_bridge_width 0.5)
			(island_removal_mode 0)
		)
		(polygon
			(pts
				(arc
					(start 424.342306 -238.985044)
					(mid 423.681906 -238.985044)
					(end 424.342306 -238.985044)
				)
			)
		)
	)
	(zone
		(layers "In1.Cu" "In2.Cu")
		(hatch none 0.5)
		(connect_pads
			(clearance 0)
		)
		(min_thickness 0.25)
		(keepout
			(tracks not_allowed)
			(vias allowed)
			(pads allowed)
			(copperpour not_allowed)
			(footprints allowed)
		)
		(placement
			(enabled no)
			(sheetname "")
		)
		(fill yes
			(thermal_gap 0.5)
			(thermal_bridge_width 0.5)
			(island_removal_mode 0)
		)
		(polygon
			(pts
				(arc
					(start 56.766714 -408.860244)
					(mid 56.789032 -408.914126)
					(end 56.842914 -408.936444)
				)
				(arc
					(start 57.038494 -408.936444)
					(mid 57.06037 -408.933312)
					(end 57.080404 -408.923998)
				)
				(arc
					(start 57.374028 -408.731466)
					(mid 57.415684 -408.719064)
					(end 57.45734 -408.731466)
				)
				(arc
					(start 57.752234 -408.923998)
					(mid 57.772158 -408.933234)
					(end 57.79389 -408.936444)
				)
				(arc
					(start 57.988454 -408.936444)
					(mid 58.042336 -408.914126)
					(end 58.064654 -408.860244)
				)
				(arc
					(start 58.064654 -408.174444)
					(mid 58.042336 -408.120562)
					(end 57.988454 -408.098244)
				)
				(arc
					(start 57.79389 -408.098244)
					(mid 57.772146 -408.101412)
					(end 57.752234 -408.11069)
				)
				(arc
					(start 57.45607 -408.303476)
					(mid 57.414386 -408.315698)
					(end 57.372758 -408.303222)
				)
				(arc
					(start 57.079134 -408.11069)
					(mid 57.05921 -408.101454)
					(end 57.037478 -408.098244)
				)
				(arc
					(start 56.842914 -408.098244)
					(mid 56.789032 -408.120562)
					(end 56.766714 -408.174444)
				)
			)
		)
	)
	(zone
		(layers "In1.Cu" "In2.Cu")
		(hatch none 0.5)
		(connect_pads
			(clearance 0)
		)
		(min_thickness 0.25)
		(keepout
			(tracks not_allowed)
			(vias allowed)
			(pads allowed)
			(copperpour not_allowed)
			(footprints allowed)
		)
		(placement
			(enabled no)
			(sheetname "")
		)
		(fill yes
			(thermal_gap 0.5)
			(thermal_bridge_width 0.5)
			(island_removal_mode 0)
		)
		(polygon
			(pts
				(arc
					(start 22.03831 -313.78525)
					(mid 21.37791 -313.78525)
					(end 22.03831 -313.78525)
				)
			)
		)
	)
	(zone
		(layers "In1.Cu" "In2.Cu")
		(hatch none 0.5)
		(connect_pads
			(clearance 0)
		)
		(min_thickness 0.25)
		(keepout
			(tracks not_allowed)
			(vias allowed)
			(pads allowed)
			(copperpour not_allowed)
			(footprints allowed)
		)
		(placement
			(enabled no)
			(sheetname "")
		)
		(fill yes
			(thermal_gap 0.5)
			(thermal_bridge_width 0.5)
			(island_removal_mode 0)
		)
		(polygon
			(pts
				(arc
					(start 48.114204 -218.585288)
					(mid 47.453804 -218.585288)
					(end 48.114204 -218.585288)
				)
			)
		)
	)
	(zone
		(layers "In1.Cu" "In2.Cu")
		(hatch none 0.5)
		(connect_pads
			(clearance 0)
		)
		(min_thickness 0.25)
		(keepout
			(tracks not_allowed)
			(vias allowed)
			(pads allowed)
			(copperpour not_allowed)
			(footprints allowed)
		)
		(placement
			(enabled no)
			(sheetname "")
		)
		(fill yes
			(thermal_gap 0.5)
			(thermal_bridge_width 0.5)
			(island_removal_mode 0)
		)
		(polygon
			(pts
				(arc
					(start 176.402238 -240.68532)
					(mid 175.741838 -240.68532)
					(end 176.402238 -240.68532)
				)
			)
		)
	)
	(zone
		(layers "In1.Cu" "In2.Cu")
		(hatch none 0.5)
		(connect_pads
			(clearance 0)
		)
		(min_thickness 0.25)
		(keepout
			(tracks not_allowed)
			(vias allowed)
			(pads allowed)
			(copperpour not_allowed)
			(footprints allowed)
		)
		(placement
			(enabled no)
			(sheetname "")
		)
		(fill yes
			(thermal_gap 0.5)
			(thermal_bridge_width 0.5)
			(island_removal_mode 0)
		)
		(polygon
			(pts
				(arc
					(start 446.974468 -223.6851)
					(mid 446.314068 -223.6851)
					(end 446.974468 -223.6851)
				)
			)
		)
	)
	(zone
		(layers "In1.Cu" "In2.Cu")
		(hatch none 0.5)
		(connect_pads
			(clearance 0)
		)
		(min_thickness 0.25)
		(keepout
			(tracks not_allowed)
			(vias allowed)
			(pads allowed)
			(copperpour not_allowed)
			(footprints allowed)
		)
		(placement
			(enabled no)
			(sheetname "")
		)
		(fill yes
			(thermal_gap 0.5)
			(thermal_bridge_width 0.5)
			(island_removal_mode 0)
		)
		(polygon
			(pts
				(arc
					(start 273.422364 -218.585034)
					(mid 272.761964 -218.585034)
					(end 273.422364 -218.585034)
				)
			)
		)
	)
	(zone
		(layers "In1.Cu" "In2.Cu")
		(hatch none 0.5)
		(connect_pads
			(clearance 0)
		)
		(min_thickness 0.25)
		(keepout
			(tracks not_allowed)
			(vias allowed)
			(pads allowed)
			(copperpour not_allowed)
			(footprints allowed)
		)
		(placement
			(enabled no)
			(sheetname "")
		)
		(fill yes
			(thermal_gap 0.5)
			(thermal_bridge_width 0.5)
			(island_removal_mode 0)
		)
		(polygon
			(pts
				(arc
					(start 48.114204 -239.835436)
					(mid 47.453804 -239.835436)
					(end 48.114204 -239.835436)
				)
			)
		)
	)
	(zone
		(layers "In1.Cu" "In2.Cu")
		(hatch none 0.5)
		(connect_pads
			(clearance 0)
		)
		(min_thickness 0.25)
		(keepout
			(tracks not_allowed)
			(vias allowed)
			(pads allowed)
			(copperpour not_allowed)
			(footprints allowed)
		)
		(placement
			(enabled no)
			(sheetname "")
		)
		(fill yes
			(thermal_gap 0.5)
			(thermal_bridge_width 0.5)
			(island_removal_mode 0)
		)
		(polygon
			(pts
				(arc
					(start 191.490346 -279.785318)
					(mid 190.829946 -279.785318)
					(end 191.490346 -279.785318)
				)
			)
		)
	)
	(zone
		(layers "In1.Cu" "In2.Cu")
		(hatch none 0.5)
		(connect_pads
			(clearance 0)
		)
		(min_thickness 0.25)
		(keepout
			(tracks not_allowed)
			(vias allowed)
			(pads allowed)
			(copperpour not_allowed)
			(footprints allowed)
		)
		(placement
			(enabled no)
			(sheetname "")
		)
		(fill yes
			(thermal_gap 0.5)
			(thermal_bridge_width 0.5)
			(island_removal_mode 0)
		)
		(polygon
			(pts
				(arc
					(start 25.482296 -293.38524)
					(mid 24.821896 -293.38524)
					(end 25.482296 -293.38524)
				)
			)
		)
	)
	(zone
		(layers "In1.Cu" "In2.Cu")
		(hatch none 0.5)
		(connect_pads
			(clearance 0)
		)
		(min_thickness 0.25)
		(keepout
			(tracks not_allowed)
			(vias allowed)
			(pads allowed)
			(copperpour not_allowed)
			(footprints allowed)
		)
		(placement
			(enabled no)
			(sheetname "")
		)
		(fill yes
			(thermal_gap 0.5)
			(thermal_bridge_width 0.5)
			(island_removal_mode 0)
		)
		(polygon
			(pts
				(arc
					(start 420.242238 -220.285056)
					(mid 419.581838 -220.285056)
					(end 420.242238 -220.285056)
				)
			)
		)
	)
	(zone
		(layers "In1.Cu" "In2.Cu")
		(hatch none 0.5)
		(connect_pads
			(clearance 0)
		)
		(min_thickness 0.25)
		(keepout
			(tracks not_allowed)
			(vias allowed)
			(pads allowed)
			(copperpour not_allowed)
			(footprints allowed)
		)
		(placement
			(enabled no)
			(sheetname "")
		)
		(fill yes
			(thermal_gap 0.5)
			(thermal_bridge_width 0.5)
			(island_removal_mode 0)
		)
		(polygon
			(pts
				(arc
					(start 25.482296 -268.735302)
					(mid 24.821896 -268.735302)
					(end 25.482296 -268.735302)
				)
			)
		)
	)
	(zone
		(layers "In1.Cu" "In2.Cu")
		(hatch none 0.5)
		(connect_pads
			(clearance 0)
		)
		(min_thickness 0.25)
		(keepout
			(tracks not_allowed)
			(vias allowed)
			(pads allowed)
			(copperpour not_allowed)
			(footprints allowed)
		)
		(placement
			(enabled no)
			(sheetname "")
		)
		(fill yes
			(thermal_gap 0.5)
			(thermal_bridge_width 0.5)
			(island_removal_mode 0)
		)
		(polygon
			(pts
				(arc
					(start 427.786292 -314.635134)
					(mid 427.125892 -314.635134)
					(end 427.786292 -314.635134)
				)
			)
		)
	)
	(zone
		(layers "In1.Cu" "In2.Cu")
		(hatch none 0.5)
		(connect_pads
			(clearance 0)
		)
		(min_thickness 0.25)
		(keepout
			(tracks not_allowed)
			(vias allowed)
			(pads allowed)
			(copperpour not_allowed)
			(footprints allowed)
		)
		(placement
			(enabled no)
			(sheetname "")
		)
		(fill yes
			(thermal_gap 0.5)
			(thermal_bridge_width 0.5)
			(island_removal_mode 0)
		)
		(polygon
			(pts
				(arc
					(start 370.575332 -414.979358)
					(mid 370.59765 -415.03324)
					(end 370.651532 -415.055558)
				)
				(arc
					(start 370.847112 -415.055558)
					(mid 370.868988 -415.052426)
					(end 370.889022 -415.043112)
				)
				(arc
					(start 371.182646 -414.85058)
					(mid 371.224302 -414.838178)
					(end 371.265958 -414.85058)
				)
				(arc
					(start 371.560852 -415.043112)
					(mid 371.580776 -415.052348)
					(end 371.602508 -415.055558)
				)
				(arc
					(start 371.797072 -415.055558)
					(mid 371.850954 -415.03324)
					(end 371.873272 -414.979358)
				)
				(arc
					(start 371.873272 -414.293558)
					(mid 371.850954 -414.239676)
					(end 371.797072 -414.217358)
				)
				(arc
					(start 371.602508 -414.217358)
					(mid 371.580764 -414.220526)
					(end 371.560852 -414.229804)
				)
				(arc
					(start 371.264688 -414.42259)
					(mid 371.223004 -414.434812)
					(end 371.181376 -414.422336)
				)
				(arc
					(start 370.887752 -414.229804)
					(mid 370.867828 -414.220568)
					(end 370.846096 -414.217358)
				)
				(arc
					(start 370.651532 -414.217358)
					(mid 370.59765 -414.239676)
					(end 370.575332 -414.293558)
				)
			)
		)
	)
	(zone
		(layers "In1.Cu" "In2.Cu")
		(hatch none 0.5)
		(connect_pads
			(clearance 0)
		)
		(min_thickness 0.25)
		(keepout
			(tracks not_allowed)
			(vias allowed)
			(pads allowed)
			(copperpour not_allowed)
			(footprints allowed)
		)
		(placement
			(enabled no)
			(sheetname "")
		)
		(fill yes
			(thermal_gap 0.5)
			(thermal_bridge_width 0.5)
			(island_removal_mode 0)
		)
		(polygon
			(pts
				(arc
					(start 176.402238 -312.935366)
					(mid 175.741838 -312.935366)
					(end 176.402238 -312.935366)
				)
			)
		)
	)
	(zone
		(layers "In1.Cu" "In2.Cu")
		(hatch none 0.5)
		(connect_pads
			(clearance 0)
		)
		(min_thickness 0.25)
		(keepout
			(tracks not_allowed)
			(vias allowed)
			(pads allowed)
			(copperpour not_allowed)
			(footprints allowed)
		)
		(placement
			(enabled no)
			(sheetname "")
		)
		(fill yes
			(thermal_gap 0.5)
			(thermal_bridge_width 0.5)
			(island_removal_mode 0)
		)
		(polygon
			(pts
				(arc
					(start 123.866656 -408.860244)
					(mid 123.888974 -408.914126)
					(end 123.942856 -408.936444)
				)
				(arc
					(start 124.138436 -408.936444)
					(mid 124.160312 -408.933312)
					(end 124.180346 -408.923998)
				)
				(arc
					(start 124.47397 -408.731466)
					(mid 124.515626 -408.719064)
					(end 124.557282 -408.731466)
				)
				(arc
					(start 124.852176 -408.923998)
					(mid 124.8721 -408.933234)
					(end 124.893832 -408.936444)
				)
				(arc
					(start 125.088396 -408.936444)
					(mid 125.142278 -408.914126)
					(end 125.164596 -408.860244)
				)
				(arc
					(start 125.164596 -408.174444)
					(mid 125.142278 -408.120562)
					(end 125.088396 -408.098244)
				)
				(arc
					(start 124.893832 -408.098244)
					(mid 124.872088 -408.101412)
					(end 124.852176 -408.11069)
				)
				(arc
					(start 124.556012 -408.303476)
					(mid 124.514328 -408.315698)
					(end 124.4727 -408.303222)
				)
				(arc
					(start 124.179076 -408.11069)
					(mid 124.159152 -408.101454)
					(end 124.13742 -408.098244)
				)
				(arc
					(start 123.942856 -408.098244)
					(mid 123.888974 -408.120562)
					(end 123.866656 -408.174444)
				)
			)
		)
	)
	(zone
		(layers "In1.Cu" "In2.Cu")
		(hatch none 0.5)
		(connect_pads
			(clearance 0)
		)
		(min_thickness 0.25)
		(keepout
			(tracks not_allowed)
			(vias allowed)
			(pads allowed)
			(copperpour not_allowed)
			(footprints allowed)
		)
		(placement
			(enabled no)
			(sheetname "")
		)
		(fill yes
			(thermal_gap 0.5)
			(thermal_bridge_width 0.5)
			(island_removal_mode 0)
		)
		(polygon
			(pts
				(arc
					(start 427.786292 -291.684964)
					(mid 427.125892 -291.684964)
					(end 427.786292 -291.684964)
				)
			)
		)
	)
	(zone
		(layers "In1.Cu" "In2.Cu")
		(hatch none 0.5)
		(connect_pads
			(clearance 0)
		)
		(min_thickness 0.25)
		(keepout
			(tracks not_allowed)
			(vias allowed)
			(pads allowed)
			(copperpour not_allowed)
			(footprints allowed)
		)
		(placement
			(enabled no)
			(sheetname "")
		)
		(fill yes
			(thermal_gap 0.5)
			(thermal_bridge_width 0.5)
			(island_removal_mode 0)
		)
		(polygon
			(pts
				(arc
					(start 273.422364 -272.984976)
					(mid 272.761964 -272.984976)
					(end 273.422364 -272.984976)
				)
			)
		)
	)
	(zone
		(layers "In1.Cu" "In2.Cu")
		(hatch none 0.5)
		(connect_pads
			(clearance 0)
		)
		(min_thickness 0.25)
		(keepout
			(tracks not_allowed)
			(vias allowed)
			(pads allowed)
			(copperpour not_allowed)
			(footprints allowed)
		)
		(placement
			(enabled no)
			(sheetname "")
		)
		(fill yes
			(thermal_gap 0.5)
			(thermal_bridge_width 0.5)
			(island_removal_mode 0)
		)
		(polygon
			(pts
				(arc
					(start 183.946292 -306.135278)
					(mid 183.285892 -306.135278)
					(end 183.946292 -306.135278)
				)
			)
		)
	)
	(zone
		(layers "In1.Cu" "In2.Cu")
		(hatch none 0.5)
		(connect_pads
			(clearance 0)
		)
		(min_thickness 0.25)
		(keepout
			(tracks not_allowed)
			(vias allowed)
			(pads allowed)
			(copperpour not_allowed)
			(footprints allowed)
		)
		(placement
			(enabled no)
			(sheetname "")
		)
		(fill yes
			(thermal_gap 0.5)
			(thermal_bridge_width 0.5)
			(island_removal_mode 0)
		)
		(polygon
			(pts
				(arc
					(start 435.330346 -282.33497)
					(mid 434.669946 -282.33497)
					(end 435.330346 -282.33497)
				)
			)
		)
	)
	(zone
		(layers "In1.Cu" "In2.Cu")
		(hatch none 0.5)
		(connect_pads
			(clearance 0)
		)
		(min_thickness 0.25)
		(keepout
			(tracks not_allowed)
			(vias allowed)
			(pads allowed)
			(copperpour not_allowed)
			(footprints allowed)
		)
		(placement
			(enabled no)
			(sheetname "")
		)
		(fill yes
			(thermal_gap 0.5)
			(thermal_bridge_width 0.5)
			(island_removal_mode 0)
		)
		(polygon
			(pts
				(arc
					(start 176.402238 -281.48534)
					(mid 175.741838 -281.48534)
					(end 176.402238 -281.48534)
				)
			)
		)
	)
	(zone
		(layers "In1.Cu" "In2.Cu")
		(hatch none 0.5)
		(connect_pads
			(clearance 0)
		)
		(min_thickness 0.25)
		(keepout
			(tracks not_allowed)
			(vias allowed)
			(pads allowed)
			(copperpour not_allowed)
			(footprints allowed)
		)
		(placement
			(enabled no)
			(sheetname "")
		)
		(fill yes
			(thermal_gap 0.5)
			(thermal_bridge_width 0.5)
			(island_removal_mode 0)
		)
		(polygon
			(pts
				(arc
					(start 33.026096 -306.985416)
					(mid 32.365696 -306.985416)
					(end 33.026096 -306.985416)
				)
			)
		)
	)
	(zone
		(layers "In1.Cu" "In2.Cu")
		(hatch none 0.5)
		(connect_pads
			(clearance 0)
		)
		(min_thickness 0.25)
		(keepout
			(tracks not_allowed)
			(vias allowed)
			(pads allowed)
			(copperpour not_allowed)
			(footprints allowed)
		)
		(placement
			(enabled no)
			(sheetname "")
		)
		(fill yes
			(thermal_gap 0.5)
			(thermal_bridge_width 0.5)
			(island_removal_mode 0)
		)
		(polygon
			(pts
				(arc
					(start 33.026096 -224.535238)
					(mid 32.365696 -224.535238)
					(end 33.026096 -224.535238)
				)
			)
		)
	)
	(zone
		(layers "In1.Cu" "In2.Cu")
		(hatch none 0.5)
		(connect_pads
			(clearance 0)
		)
		(min_thickness 0.25)
		(keepout
			(tracks not_allowed)
			(vias allowed)
			(pads allowed)
			(copperpour not_allowed)
			(footprints allowed)
		)
		(placement
			(enabled no)
			(sheetname "")
		)
		(fill yes
			(thermal_gap 0.5)
			(thermal_bridge_width 0.5)
			(island_removal_mode 0)
		)
		(polygon
			(pts
				(arc
					(start 420.242238 -263.634982)
					(mid 419.581838 -263.634982)
					(end 420.242238 -263.634982)
				)
			)
		)
	)
	(zone
		(layers "In1.Cu" "In2.Cu")
		(hatch none 0.5)
		(connect_pads
			(clearance 0)
		)
		(min_thickness 0.25)
		(keepout
			(tracks not_allowed)
			(vias allowed)
			(pads allowed)
			(copperpour not_allowed)
			(footprints allowed)
		)
		(placement
			(enabled no)
			(sheetname "")
		)
		(fill yes
			(thermal_gap 0.5)
			(thermal_bridge_width 0.5)
			(island_removal_mode 0)
		)
		(polygon
			(pts
				(arc
					(start 199.0344 -201.585322)
					(mid 198.374 -201.585322)
					(end 199.0344 -201.585322)
				)
			)
		)
	)
	(zone
		(layers "In1.Cu" "In2.Cu")
		(hatch none 0.5)
		(connect_pads
			(clearance 0)
		)
		(min_thickness 0.25)
		(keepout
			(tracks not_allowed)
			(vias allowed)
			(pads allowed)
			(copperpour not_allowed)
			(footprints allowed)
		)
		(placement
			(enabled no)
			(sheetname "")
		)
		(fill yes
			(thermal_gap 0.5)
			(thermal_bridge_width 0.5)
			(island_removal_mode 0)
		)
		(polygon
			(pts
				(arc
					(start 25.482296 -316.33541)
					(mid 24.821896 -316.33541)
					(end 25.482296 -316.33541)
				)
			)
		)
	)
	(zone
		(layers "In1.Cu" "In2.Cu")
		(hatch none 0.5)
		(connect_pads
			(clearance 0)
		)
		(min_thickness 0.25)
		(keepout
			(tracks not_allowed)
			(vias allowed)
			(pads allowed)
			(copperpour not_allowed)
			(footprints allowed)
		)
		(placement
			(enabled no)
			(sheetname "")
		)
		(fill yes
			(thermal_gap 0.5)
			(thermal_bridge_width 0.5)
			(island_removal_mode 0)
		)
		(polygon
			(pts
				(arc
					(start 109.66069 -376.73661)
					(mid 109.651454 -376.756534)
					(end 109.648244 -376.778266)
				)
				(arc
					(start 109.648244 -376.97283)
					(mid 109.670562 -377.026712)
					(end 109.724444 -377.04903)
				)
				(arc
					(start 110.410244 -377.04903)
					(mid 110.464126 -377.026712)
					(end 110.486444 -376.97283)
				)
				(arc
					(start 110.486444 -376.778266)
					(mid 110.483276 -376.756522)
					(end 110.473998 -376.73661)
				)
				(arc
					(start 110.281212 -376.440446)
					(mid 110.26899 -376.398762)
					(end 110.281466 -376.357134)
				)
				(arc
					(start 110.473998 -376.06351)
					(mid 110.483234 -376.043586)
					(end 110.486444 -376.021854)
				)
				(arc
					(start 110.486444 -375.82729)
					(mid 110.464126 -375.773408)
					(end 110.410244 -375.75109)
				)
				(arc
					(start 109.724444 -375.75109)
					(mid 109.670562 -375.773408)
					(end 109.648244 -375.82729)
				)
				(arc
					(start 109.648244 -376.023124)
					(mid 109.651412 -376.044868)
					(end 109.66069 -376.06478)
				)
				(arc
					(start 109.853222 -376.358404)
					(mid 109.865624 -376.40006)
					(end 109.853222 -376.441716)
				)
			)
		)
	)
	(zone
		(layers "In1.Cu" "In2.Cu")
		(hatch none 0.5)
		(connect_pads
			(clearance 0)
		)
		(min_thickness 0.25)
		(keepout
			(tracks not_allowed)
			(vias allowed)
			(pads allowed)
			(copperpour not_allowed)
			(footprints allowed)
		)
		(placement
			(enabled no)
			(sheetname "")
		)
		(fill yes
			(thermal_gap 0.5)
			(thermal_bridge_width 0.5)
			(island_removal_mode 0)
		)
		(polygon
			(pts
				(arc
					(start 450.4182 -314.635134)
					(mid 449.7578 -314.635134)
					(end 450.4182 -314.635134)
				)
			)
		)
	)
	(zone
		(layers "In1.Cu" "In2.Cu")
		(hatch none 0.5)
		(connect_pads
			(clearance 0)
		)
		(min_thickness 0.25)
		(keepout
			(tracks not_allowed)
			(vias allowed)
			(pads allowed)
			(copperpour not_allowed)
			(footprints allowed)
		)
		(placement
			(enabled no)
			(sheetname "")
		)
		(fill yes
			(thermal_gap 0.5)
			(thermal_bridge_width 0.5)
			(island_removal_mode 0)
		)
		(polygon
			(pts
				(arc
					(start 37.126164 -278.085296)
					(mid 36.465764 -278.085296)
					(end 37.126164 -278.085296)
				)
			)
		)
	)
	(zone
		(layers "In1.Cu" "In2.Cu")
		(hatch none 0.5)
		(connect_pads
			(clearance 0)
		)
		(min_thickness 0.25)
		(keepout
			(tracks not_allowed)
			(vias allowed)
			(pads allowed)
			(copperpour not_allowed)
			(footprints allowed)
		)
		(placement
			(enabled no)
			(sheetname "")
		)
		(fill yes
			(thermal_gap 0.5)
			(thermal_bridge_width 0.5)
			(island_removal_mode 0)
		)
		(polygon
			(pts
				(arc
					(start 277.522432 -247.485154)
					(mid 276.862032 -247.485154)
					(end 277.522432 -247.485154)
				)
			)
		)
	)
	(zone
		(layers "In1.Cu" "In2.Cu")
		(hatch none 0.5)
		(connect_pads
			(clearance 0)
		)
		(min_thickness 0.25)
		(keepout
			(tracks not_allowed)
			(vias allowed)
			(pads allowed)
			(copperpour not_allowed)
			(footprints allowed)
		)
		(placement
			(enabled no)
			(sheetname "")
		)
		(fill yes
			(thermal_gap 0.5)
			(thermal_bridge_width 0.5)
			(island_removal_mode 0)
		)
		(polygon
			(pts
				(arc
					(start 202.478132 -199.8853)
					(mid 201.817732 -199.8853)
					(end 202.478132 -199.8853)
				)
			)
		)
	)
	(zone
		(layers "In1.Cu" "In2.Cu")
		(hatch none 0.5)
		(connect_pads
			(clearance 0)
		)
		(min_thickness 0.25)
		(keepout
			(tracks not_allowed)
			(vias allowed)
			(pads allowed)
			(copperpour not_allowed)
			(footprints allowed)
		)
		(placement
			(enabled no)
			(sheetname "")
		)
		(fill yes
			(thermal_gap 0.5)
			(thermal_bridge_width 0.5)
			(island_removal_mode 0)
		)
		(polygon
			(pts
				(arc
					(start 172.30217 -278.935434)
					(mid 171.64177 -278.935434)
					(end 172.30217 -278.935434)
				)
			)
		)
	)
	(zone
		(layers "In1.Cu" "In2.Cu")
		(hatch none 0.5)
		(connect_pads
			(clearance 0)
		)
		(min_thickness 0.25)
		(keepout
			(tracks not_allowed)
			(vias allowed)
			(pads allowed)
			(copperpour not_allowed)
			(footprints allowed)
		)
		(placement
			(enabled no)
			(sheetname "")
		)
		(fill yes
			(thermal_gap 0.5)
			(thermal_bridge_width 0.5)
			(island_removal_mode 0)
		)
		(polygon
			(pts
				(arc
					(start 427.786292 -237.285022)
					(mid 427.125892 -237.285022)
					(end 427.786292 -237.285022)
				)
			)
		)
	)
	(zone
		(layers "In1.Cu" "In2.Cu")
		(hatch none 0.5)
		(connect_pads
			(clearance 0)
		)
		(min_thickness 0.25)
		(keepout
			(tracks not_allowed)
			(vias allowed)
			(pads allowed)
			(copperpour not_allowed)
			(footprints allowed)
		)
		(placement
			(enabled no)
			(sheetname "")
		)
		(fill yes
			(thermal_gap 0.5)
			(thermal_bridge_width 0.5)
			(island_removal_mode 0)
		)
		(polygon
			(pts
				(arc
					(start 450.4182 -205.834996)
					(mid 449.7578 -205.834996)
					(end 450.4182 -205.834996)
				)
			)
		)
	)
	(zone
		(layers "In1.Cu" "In2.Cu")
		(hatch none 0.5)
		(connect_pads
			(clearance 0)
		)
		(min_thickness 0.25)
		(keepout
			(tracks not_allowed)
			(vias allowed)
			(pads allowed)
			(copperpour not_allowed)
			(footprints allowed)
		)
		(placement
			(enabled no)
			(sheetname "")
		)
		(fill yes
			(thermal_gap 0.5)
			(thermal_bridge_width 0.5)
			(island_removal_mode 0)
		)
		(polygon
			(pts
				(arc
					(start 273.422364 -284.034992)
					(mid 272.761964 -284.034992)
					(end 273.422364 -284.034992)
				)
			)
		)
	)
	(zone
		(layers "In1.Cu" "In2.Cu")
		(hatch none 0.5)
		(connect_pads
			(clearance 0)
		)
		(min_thickness 0.25)
		(keepout
			(tracks not_allowed)
			(vias allowed)
			(pads allowed)
			(copperpour not_allowed)
			(footprints allowed)
		)
		(placement
			(enabled no)
			(sheetname "")
		)
		(fill yes
			(thermal_gap 0.5)
			(thermal_bridge_width 0.5)
			(island_removal_mode 0)
		)
		(polygon
			(pts
				(arc
					(start 40.57015 -230.485442)
					(mid 39.90975 -230.485442)
					(end 40.57015 -230.485442)
				)
			)
		)
	)
	(zone
		(layers "In1.Cu" "In2.Cu")
		(hatch none 0.5)
		(connect_pads
			(clearance 0)
		)
		(min_thickness 0.25)
		(keepout
			(tracks not_allowed)
			(vias allowed)
			(pads allowed)
			(copperpour not_allowed)
			(footprints allowed)
		)
		(placement
			(enabled no)
			(sheetname "")
		)
		(fill yes
			(thermal_gap 0.5)
			(thermal_bridge_width 0.5)
			(island_removal_mode 0)
		)
		(polygon
			(pts
				(arc
					(start 442.8744 -210.935062)
					(mid 442.214 -210.935062)
					(end 442.8744 -210.935062)
				)
			)
		)
	)
	(zone
		(layers "In1.Cu" "In2.Cu")
		(hatch none 0.5)
		(connect_pads
			(clearance 0)
		)
		(min_thickness 0.25)
		(keepout
			(tracks not_allowed)
			(vias allowed)
			(pads allowed)
			(copperpour not_allowed)
			(footprints allowed)
		)
		(placement
			(enabled no)
			(sheetname "")
		)
		(fill yes
			(thermal_gap 0.5)
			(thermal_bridge_width 0.5)
			(island_removal_mode 0)
		)
		(polygon
			(pts
				(arc
					(start 187.390278 -215.185244)
					(mid 186.729878 -215.185244)
					(end 187.390278 -215.185244)
				)
			)
		)
	)
	(zone
		(layers "In1.Cu" "In2.Cu")
		(hatch none 0.5)
		(connect_pads
			(clearance 0)
		)
		(min_thickness 0.25)
		(keepout
			(tracks not_allowed)
			(vias allowed)
			(pads allowed)
			(copperpour not_allowed)
			(footprints allowed)
		)
		(placement
			(enabled no)
			(sheetname "")
		)
		(fill yes
			(thermal_gap 0.5)
			(thermal_bridge_width 0.5)
			(island_removal_mode 0)
		)
		(polygon
			(pts
				(arc
					(start 202.478132 -220.28531)
					(mid 201.817732 -220.28531)
					(end 202.478132 -220.28531)
				)
			)
		)
	)
	(zone
		(layers "In1.Cu" "In2.Cu")
		(hatch none 0.5)
		(connect_pads
			(clearance 0)
		)
		(min_thickness 0.25)
		(keepout
			(tracks not_allowed)
			(vias allowed)
			(pads allowed)
			(copperpour not_allowed)
			(footprints allowed)
		)
		(placement
			(enabled no)
			(sheetname "")
		)
		(fill yes
			(thermal_gap 0.5)
			(thermal_bridge_width 0.5)
			(island_removal_mode 0)
		)
		(polygon
			(pts
				(arc
					(start 37.126164 -276.385274)
					(mid 36.465764 -276.385274)
					(end 37.126164 -276.385274)
				)
			)
		)
	)
	(zone
		(layers "In1.Cu" "In2.Cu")
		(hatch none 0.5)
		(connect_pads
			(clearance 0)
		)
		(min_thickness 0.25)
		(keepout
			(tracks not_allowed)
			(vias allowed)
			(pads allowed)
			(copperpour not_allowed)
			(footprints allowed)
		)
		(placement
			(enabled no)
			(sheetname "")
		)
		(fill yes
			(thermal_gap 0.5)
			(thermal_bridge_width 0.5)
			(island_removal_mode 0)
		)
		(polygon
			(pts
				(arc
					(start 446.974468 -312.935112)
					(mid 446.314068 -312.935112)
					(end 446.974468 -312.935112)
				)
			)
		)
	)
	(zone
		(layers "In1.Cu" "In2.Cu")
		(hatch none 0.5)
		(connect_pads
			(clearance 0)
		)
		(min_thickness 0.25)
		(keepout
			(tracks not_allowed)
			(vias allowed)
			(pads allowed)
			(copperpour not_allowed)
			(footprints allowed)
		)
		(placement
			(enabled no)
			(sheetname "")
		)
		(fill yes
			(thermal_gap 0.5)
			(thermal_bridge_width 0.5)
			(island_removal_mode 0)
		)
		(polygon
			(pts
				(arc
					(start 442.8744 -302.73498)
					(mid 442.214 -302.73498)
					(end 442.8744 -302.73498)
				)
			)
		)
	)
	(zone
		(layers "In1.Cu" "In2.Cu")
		(hatch none 0.5)
		(connect_pads
			(clearance 0)
		)
		(min_thickness 0.25)
		(keepout
			(tracks not_allowed)
			(vias allowed)
			(pads allowed)
			(copperpour not_allowed)
			(footprints allowed)
		)
		(placement
			(enabled no)
			(sheetname "")
		)
		(fill yes
			(thermal_gap 0.5)
			(thermal_bridge_width 0.5)
			(island_removal_mode 0)
		)
		(polygon
			(pts
				(arc
					(start 37.126164 -229.635304)
					(mid 36.465764 -229.635304)
					(end 37.126164 -229.635304)
				)
			)
		)
	)
	(zone
		(layers "In1.Cu" "In2.Cu")
		(hatch none 0.5)
		(connect_pads
			(clearance 0)
		)
		(min_thickness 0.25)
		(keepout
			(tracks not_allowed)
			(vias allowed)
			(pads allowed)
			(copperpour not_allowed)
			(footprints allowed)
		)
		(placement
			(enabled no)
			(sheetname "")
		)
		(fill yes
			(thermal_gap 0.5)
			(thermal_bridge_width 0.5)
			(island_removal_mode 0)
		)
		(polygon
			(pts
				(arc
					(start 445.667384 -7.672324)
					(mid 445.689702 -7.618442)
					(end 445.743584 -7.596124)
				)
				(arc
					(start 446.780158 -7.596124)
					(mid 446.83404 -7.618442)
					(end 446.856358 -7.672324)
				)
				(arc
					(start 446.856358 -9.071864)
					(mid 446.83404 -9.125746)
					(end 446.780158 -9.148064)
				)
				(arc
					(start 445.743584 -9.148064)
					(mid 445.689702 -9.125746)
					(end 445.667384 -9.071864)
				)
			)
		)
	)
	(zone
		(layers "In1.Cu" "In2.Cu")
		(hatch none 0.5)
		(connect_pads
			(clearance 0)
		)
		(min_thickness 0.25)
		(keepout
			(tracks not_allowed)
			(vias allowed)
			(pads allowed)
			(copperpour not_allowed)
			(footprints allowed)
		)
		(placement
			(enabled no)
			(sheetname "")
		)
		(fill yes
			(thermal_gap 0.5)
			(thermal_bridge_width 0.5)
			(island_removal_mode 0)
		)
		(polygon
			(pts
				(arc
					(start 439.430414 -238.13516)
					(mid 438.770014 -238.13516)
					(end 439.430414 -238.13516)
				)
			)
		)
	)
	(zone
		(layers "In1.Cu" "In2.Cu")
		(hatch none 0.5)
		(connect_pads
			(clearance 0)
		)
		(min_thickness 0.25)
		(keepout
			(tracks not_allowed)
			(vias allowed)
			(pads allowed)
			(copperpour not_allowed)
			(footprints allowed)
		)
		(placement
			(enabled no)
			(sheetname "")
		)
		(fill yes
			(thermal_gap 0.5)
			(thermal_bridge_width 0.5)
			(island_removal_mode 0)
		)
		(polygon
			(pts
				(arc
					(start 400.991578 -16.443198)
					(mid 401.013896 -16.49708)
					(end 401.067778 -16.519398)
				)
				(arc
					(start 401.263358 -16.519398)
					(mid 401.285234 -16.516266)
					(end 401.305268 -16.506952)
				)
				(arc
					(start 401.598892 -16.31442)
					(mid 401.640548 -16.302018)
					(end 401.682204 -16.31442)
				)
				(arc
					(start 401.977098 -16.506952)
					(mid 401.997022 -16.516188)
					(end 402.018754 -16.519398)
				)
				(arc
					(start 402.213318 -16.519398)
					(mid 402.2672 -16.49708)
					(end 402.289518 -16.443198)
				)
				(arc
					(start 402.289518 -15.757398)
					(mid 402.2672 -15.703516)
					(end 402.213318 -15.681198)
				)
				(arc
					(start 402.018754 -15.681198)
					(mid 401.99701 -15.684366)
					(end 401.977098 -15.693644)
				)
				(arc
					(start 401.680934 -15.88643)
					(mid 401.63925 -15.898652)
					(end 401.597622 -15.886176)
				)
				(arc
					(start 401.303998 -15.693644)
					(mid 401.284074 -15.684408)
					(end 401.262342 -15.681198)
				)
				(arc
					(start 401.067778 -15.681198)
					(mid 401.013896 -15.703516)
					(end 400.991578 -15.757398)
				)
			)
		)
	)
	(zone
		(layers "In1.Cu" "In2.Cu")
		(hatch none 0.5)
		(connect_pads
			(clearance 0)
		)
		(min_thickness 0.25)
		(keepout
			(tracks not_allowed)
			(vias allowed)
			(pads allowed)
			(copperpour not_allowed)
			(footprints allowed)
		)
		(placement
			(enabled no)
			(sheetname "")
		)
		(fill yes
			(thermal_gap 0.5)
			(thermal_bridge_width 0.5)
			(island_removal_mode 0)
		)
		(polygon
			(pts
				(arc
					(start 52.214272 -307.8353)
					(mid 51.553872 -307.8353)
					(end 52.214272 -307.8353)
				)
			)
		)
	)
	(zone
		(layers "In1.Cu" "In2.Cu")
		(hatch none 0.5)
		(connect_pads
			(clearance 0)
		)
		(min_thickness 0.25)
		(keepout
			(tracks not_allowed)
			(vias allowed)
			(pads allowed)
			(copperpour not_allowed)
			(footprints allowed)
		)
		(placement
			(enabled no)
			(sheetname "")
		)
		(fill yes
			(thermal_gap 0.5)
			(thermal_bridge_width 0.5)
			(island_removal_mode 0)
		)
		(polygon
			(pts
				(arc
					(start 269.978378 -219.435172)
					(mid 269.317978 -219.435172)
					(end 269.978378 -219.435172)
				)
			)
		)
	)
	(zone
		(layers "In1.Cu" "In2.Cu")
		(hatch none 0.5)
		(connect_pads
			(clearance 0)
		)
		(min_thickness 0.25)
		(keepout
			(tracks not_allowed)
			(vias allowed)
			(pads allowed)
			(copperpour not_allowed)
			(footprints allowed)
		)
		(placement
			(enabled no)
			(sheetname "")
		)
		(fill yes
			(thermal_gap 0.5)
			(thermal_bridge_width 0.5)
			(island_removal_mode 0)
		)
		(polygon
			(pts
				(arc
					(start 435.330346 -280.634948)
					(mid 434.669946 -280.634948)
					(end 435.330346 -280.634948)
				)
			)
		)
	)
	(zone
		(layers "In1.Cu" "In2.Cu")
		(hatch none 0.5)
		(connect_pads
			(clearance 0)
		)
		(min_thickness 0.25)
		(keepout
			(tracks not_allowed)
			(vias allowed)
			(pads allowed)
			(copperpour not_allowed)
			(footprints allowed)
		)
		(placement
			(enabled no)
			(sheetname "")
		)
		(fill yes
			(thermal_gap 0.5)
			(thermal_bridge_width 0.5)
			(island_removal_mode 0)
		)
		(polygon
			(pts
				(arc
					(start 432.06543 -17.967198)
					(mid 432.087748 -18.02108)
					(end 432.14163 -18.043398)
				)
				(arc
					(start 432.33721 -18.043398)
					(mid 432.359086 -18.040266)
					(end 432.37912 -18.030952)
				)
				(arc
					(start 432.672744 -17.83842)
					(mid 432.7144 -17.826018)
					(end 432.756056 -17.83842)
				)
				(arc
					(start 433.05095 -18.030952)
					(mid 433.070874 -18.040188)
					(end 433.092606 -18.043398)
				)
				(arc
					(start 433.28717 -18.043398)
					(mid 433.341052 -18.02108)
					(end 433.36337 -17.967198)
				)
				(arc
					(start 433.36337 -17.281398)
					(mid 433.341052 -17.227516)
					(end 433.28717 -17.205198)
				)
				(arc
					(start 433.092606 -17.205198)
					(mid 433.070862 -17.208366)
					(end 433.05095 -17.217644)
				)
				(arc
					(start 432.754786 -17.41043)
					(mid 432.713102 -17.422652)
					(end 432.671474 -17.410176)
				)
				(arc
					(start 432.37785 -17.217644)
					(mid 432.357926 -17.208408)
					(end 432.336194 -17.205198)
				)
				(arc
					(start 432.14163 -17.205198)
					(mid 432.087748 -17.227516)
					(end 432.06543 -17.281398)
				)
			)
		)
	)
	(zone
		(layers "In1.Cu" "In2.Cu")
		(hatch none 0.5)
		(connect_pads
			(clearance 0)
		)
		(min_thickness 0.25)
		(keepout
			(tracks not_allowed)
			(vias allowed)
			(pads allowed)
			(copperpour not_allowed)
			(footprints allowed)
		)
		(placement
			(enabled no)
			(sheetname "")
		)
		(fill yes
			(thermal_gap 0.5)
			(thermal_bridge_width 0.5)
			(island_removal_mode 0)
		)
		(polygon
			(pts
				(arc
					(start 179.846224 -224.535238)
					(mid 179.185824 -224.535238)
					(end 179.846224 -224.535238)
				)
			)
		)
	)
	(zone
		(layers "In1.Cu" "In2.Cu")
		(hatch none 0.5)
		(connect_pads
			(clearance 0)
		)
		(min_thickness 0.25)
		(keepout
			(tracks not_allowed)
			(vias allowed)
			(pads allowed)
			(copperpour not_allowed)
			(footprints allowed)
		)
		(placement
			(enabled no)
			(sheetname "")
		)
		(fill yes
			(thermal_gap 0.5)
			(thermal_bridge_width 0.5)
			(island_removal_mode 0)
		)
		(polygon
			(pts
				(arc
					(start 172.30217 -268.735302)
					(mid 171.64177 -268.735302)
					(end 172.30217 -268.735302)
				)
			)
		)
	)
	(zone
		(layers "In1.Cu" "In2.Cu")
		(hatch none 0.5)
		(connect_pads
			(clearance 0)
		)
		(min_thickness 0.25)
		(keepout
			(tracks not_allowed)
			(vias allowed)
			(pads allowed)
			(copperpour not_allowed)
			(footprints allowed)
		)
		(placement
			(enabled no)
			(sheetname "")
		)
		(fill yes
			(thermal_gap 0.5)
			(thermal_bridge_width 0.5)
			(island_removal_mode 0)
		)
		(polygon
			(pts
				(arc
					(start 288.510218 -288.285174)
					(mid 287.849818 -288.285174)
					(end 288.510218 -288.285174)
				)
			)
		)
	)
	(zone
		(layers "In1.Cu" "In2.Cu")
		(hatch none 0.5)
		(connect_pads
			(clearance 0)
		)
		(min_thickness 0.25)
		(keepout
			(tracks not_allowed)
			(vias allowed)
			(pads allowed)
			(copperpour not_allowed)
			(footprints allowed)
		)
		(placement
			(enabled no)
			(sheetname "")
		)
		(fill yes
			(thermal_gap 0.5)
			(thermal_bridge_width 0.5)
			(island_removal_mode 0)
		)
		(polygon
			(pts
				(arc
					(start 160.119314 -19.66214)
					(mid 160.09939 -19.652904)
					(end 160.077658 -19.649694)
				)
				(arc
					(start 159.883094 -19.649694)
					(mid 159.829212 -19.672012)
					(end 159.806894 -19.725894)
				)
				(arc
					(start 159.806894 -20.411694)
					(mid 159.829212 -20.465576)
					(end 159.883094 -20.487894)
				)
				(arc
					(start 160.077658 -20.487894)
					(mid 160.099402 -20.484726)
					(end 160.119314 -20.475448)
				)
				(arc
					(start 160.415478 -20.282662)
					(mid 160.457162 -20.27044)
					(end 160.49879 -20.282916)
				)
				(arc
					(start 160.792414 -20.475448)
					(mid 160.812338 -20.484684)
					(end 160.83407 -20.487894)
				)
				(arc
					(start 161.028634 -20.487894)
					(mid 161.082516 -20.465576)
					(end 161.104834 -20.411694)
				)
				(arc
					(start 161.104834 -19.725894)
					(mid 161.082516 -19.672012)
					(end 161.028634 -19.649694)
				)
				(arc
					(start 160.8328 -19.649694)
					(mid 160.811056 -19.652862)
					(end 160.791144 -19.66214)
				)
				(arc
					(start 160.49752 -19.854672)
					(mid 160.455864 -19.867074)
					(end 160.414208 -19.854672)
				)
			)
		)
	)
	(zone
		(layers "In1.Cu" "In2.Cu")
		(hatch none 0.5)
		(connect_pads
			(clearance 0)
		)
		(min_thickness 0.25)
		(keepout
			(tracks not_allowed)
			(vias allowed)
			(pads allowed)
			(copperpour not_allowed)
			(footprints allowed)
		)
		(placement
			(enabled no)
			(sheetname "")
		)
		(fill yes
			(thermal_gap 0.5)
			(thermal_bridge_width 0.5)
			(island_removal_mode 0)
		)
		(polygon
			(pts
				(arc
					(start 191.490346 -214.33536)
					(mid 190.829946 -214.33536)
					(end 191.490346 -214.33536)
				)
			)
		)
	)
	(zone
		(layers "In1.Cu" "In2.Cu")
		(hatch none 0.5)
		(connect_pads
			(clearance 0)
		)
		(min_thickness 0.25)
		(keepout
			(tracks not_allowed)
			(vias allowed)
			(pads allowed)
			(copperpour not_allowed)
			(footprints allowed)
		)
		(placement
			(enabled no)
			(sheetname "")
		)
		(fill yes
			(thermal_gap 0.5)
			(thermal_bridge_width 0.5)
			(island_removal_mode 0)
		)
		(polygon
			(pts
				(arc
					(start 292.610286 -244.08511)
					(mid 291.949886 -244.08511)
					(end 292.610286 -244.08511)
				)
			)
		)
	)
	(zone
		(layers "In1.Cu" "In2.Cu")
		(hatch none 0.5)
		(connect_pads
			(clearance 0)
		)
		(min_thickness 0.25)
		(keepout
			(tracks not_allowed)
			(vias allowed)
			(pads allowed)
			(copperpour not_allowed)
			(footprints allowed)
		)
		(placement
			(enabled no)
			(sheetname "")
		)
		(fill yes
			(thermal_gap 0.5)
			(thermal_bridge_width 0.5)
			(island_removal_mode 0)
		)
		(polygon
			(pts
				(arc
					(start 424.342306 -221.985078)
					(mid 423.681906 -221.985078)
					(end 424.342306 -221.985078)
				)
			)
		)
	)
	(zone
		(layers "In1.Cu" "In2.Cu")
		(hatch none 0.5)
		(connect_pads
			(clearance 0)
		)
		(min_thickness 0.25)
		(keepout
			(tracks not_allowed)
			(vias allowed)
			(pads allowed)
			(copperpour not_allowed)
			(footprints allowed)
		)
		(placement
			(enabled no)
			(sheetname "")
		)
		(fill yes
			(thermal_gap 0.5)
			(thermal_bridge_width 0.5)
			(island_removal_mode 0)
		)
		(polygon
			(pts
				(arc
					(start 29.582364 -315.485272)
					(mid 28.921964 -315.485272)
					(end 29.582364 -315.485272)
				)
			)
		)
	)
	(zone
		(layers "In1.Cu" "In2.Cu")
		(hatch none 0.5)
		(connect_pads
			(clearance 0)
		)
		(min_thickness 0.25)
		(keepout
			(tracks not_allowed)
			(vias allowed)
			(pads allowed)
			(copperpour not_allowed)
			(footprints allowed)
		)
		(placement
			(enabled no)
			(sheetname "")
		)
		(fill yes
			(thermal_gap 0.5)
			(thermal_bridge_width 0.5)
			(island_removal_mode 0)
		)
		(polygon
			(pts
				(arc
					(start 285.066232 -276.38502)
					(mid 284.405832 -276.38502)
					(end 285.066232 -276.38502)
				)
			)
		)
	)
	(zone
		(layers "In1.Cu" "In2.Cu")
		(hatch none 0.5)
		(connect_pads
			(clearance 0)
		)
		(min_thickness 0.25)
		(keepout
			(tracks not_allowed)
			(vias allowed)
			(pads allowed)
			(copperpour not_allowed)
			(footprints allowed)
		)
		(placement
			(enabled no)
			(sheetname "")
		)
		(fill yes
			(thermal_gap 0.5)
			(thermal_bridge_width 0.5)
			(island_removal_mode 0)
		)
		(polygon
			(pts
				(arc
					(start 292.610286 -201.585068)
					(mid 291.949886 -201.585068)
					(end 292.610286 -201.585068)
				)
			)
		)
	)
	(zone
		(layers "In1.Cu" "In2.Cu")
		(hatch none 0.5)
		(connect_pads
			(clearance 0)
		)
		(min_thickness 0.25)
		(keepout
			(tracks not_allowed)
			(vias allowed)
			(pads allowed)
			(copperpour not_allowed)
			(footprints allowed)
		)
		(placement
			(enabled no)
			(sheetname "")
		)
		(fill yes
			(thermal_gap 0.5)
			(thermal_bridge_width 0.5)
			(island_removal_mode 0)
		)
		(polygon
			(pts
				(arc
					(start 446.856358 -11.91768)
					(mid 446.83404 -11.971562)
					(end 446.780158 -11.99388)
				)
				(arc
					(start 445.743584 -11.99388)
					(mid 445.689702 -11.971562)
					(end 445.667384 -11.91768)
				)
				(arc
					(start 445.667384 -10.51814)
					(mid 445.689702 -10.464258)
					(end 445.743584 -10.44194)
				)
				(arc
					(start 446.780158 -10.44194)
					(mid 446.83404 -10.464258)
					(end 446.856358 -10.51814)
				)
			)
		)
	)
	(zone
		(layers "In1.Cu" "In2.Cu")
		(hatch none 0.5)
		(connect_pads
			(clearance 0)
		)
		(min_thickness 0.25)
		(keepout
			(tracks not_allowed)
			(vias allowed)
			(pads allowed)
			(copperpour not_allowed)
			(footprints allowed)
		)
		(placement
			(enabled no)
			(sheetname "")
		)
		(fill yes
			(thermal_gap 0.5)
			(thermal_bridge_width 0.5)
			(island_removal_mode 0)
		)
		(polygon
			(pts
				(arc
					(start 285.066232 -217.73515)
					(mid 284.405832 -217.73515)
					(end 285.066232 -217.73515)
				)
			)
		)
	)
	(zone
		(layers "In1.Cu" "In2.Cu")
		(hatch none 0.5)
		(connect_pads
			(clearance 0)
		)
		(min_thickness 0.25)
		(keepout
			(tracks not_allowed)
			(vias allowed)
			(pads allowed)
			(copperpour not_allowed)
			(footprints allowed)
		)
		(placement
			(enabled no)
			(sheetname "")
		)
		(fill yes
			(thermal_gap 0.5)
			(thermal_bridge_width 0.5)
			(island_removal_mode 0)
		)
		(polygon
			(pts
				(arc
					(start 425.661582 -11.91768)
					(mid 425.639264 -11.971562)
					(end 425.585382 -11.99388)
				)
				(arc
					(start 424.548808 -11.99388)
					(mid 424.494926 -11.971562)
					(end 424.472608 -11.91768)
				)
				(arc
					(start 424.472608 -10.51814)
					(mid 424.494926 -10.464258)
					(end 424.548808 -10.44194)
				)
				(arc
					(start 425.585382 -10.44194)
					(mid 425.639264 -10.464258)
					(end 425.661582 -10.51814)
				)
			)
		)
	)
	(zone
		(layers "In1.Cu" "In2.Cu")
		(hatch none 0.5)
		(connect_pads
			(clearance 0)
		)
		(min_thickness 0.25)
		(keepout
			(tracks not_allowed)
			(vias allowed)
			(pads allowed)
			(copperpour not_allowed)
			(footprints allowed)
		)
		(placement
			(enabled no)
			(sheetname "")
		)
		(fill yes
			(thermal_gap 0.5)
			(thermal_bridge_width 0.5)
			(island_removal_mode 0)
		)
		(polygon
			(pts
				(arc
					(start 439.430414 -270.43507)
					(mid 438.770014 -270.43507)
					(end 439.430414 -270.43507)
				)
			)
		)
	)
	(zone
		(layers "In1.Cu" "In2.Cu")
		(hatch none 0.5)
		(connect_pads
			(clearance 0)
		)
		(min_thickness 0.25)
		(keepout
			(tracks not_allowed)
			(vias allowed)
			(pads allowed)
			(copperpour not_allowed)
			(footprints allowed)
		)
		(placement
			(enabled no)
			(sheetname "")
		)
		(fill yes
			(thermal_gap 0.5)
			(thermal_bridge_width 0.5)
			(island_removal_mode 0)
		)
		(polygon
			(pts
				(arc
					(start 33.026096 -221.135194)
					(mid 32.365696 -221.135194)
					(end 33.026096 -221.135194)
				)
			)
		)
	)
	(zone
		(layers "In1.Cu" "In2.Cu")
		(hatch none 0.5)
		(connect_pads
			(clearance 0)
		)
		(min_thickness 0.25)
		(keepout
			(tracks not_allowed)
			(vias allowed)
			(pads allowed)
			(copperpour not_allowed)
			(footprints allowed)
		)
		(placement
			(enabled no)
			(sheetname "")
		)
		(fill yes
			(thermal_gap 0.5)
			(thermal_bridge_width 0.5)
			(island_removal_mode 0)
		)
		(polygon
			(pts
				(arc
					(start 269.978378 -247.485154)
					(mid 269.317978 -247.485154)
					(end 269.978378 -247.485154)
				)
			)
		)
	)
	(zone
		(layers "In1.Cu" "In2.Cu")
		(hatch none 0.5)
		(connect_pads
			(clearance 0)
		)
		(min_thickness 0.25)
		(keepout
			(tracks not_allowed)
			(vias allowed)
			(pads allowed)
			(copperpour not_allowed)
			(footprints allowed)
		)
		(placement
			(enabled no)
			(sheetname "")
		)
		(fill yes
			(thermal_gap 0.5)
			(thermal_bridge_width 0.5)
			(island_removal_mode 0)
		)
		(polygon
			(pts
				(arc
					(start 25.482296 -207.535272)
					(mid 24.821896 -207.535272)
					(end 25.482296 -207.535272)
				)
			)
		)
	)
	(zone
		(layers "In1.Cu" "In2.Cu")
		(hatch none 0.5)
		(connect_pads
			(clearance 0)
		)
		(min_thickness 0.25)
		(keepout
			(tracks not_allowed)
			(vias allowed)
			(pads allowed)
			(copperpour not_allowed)
			(footprints allowed)
		)
		(placement
			(enabled no)
			(sheetname "")
		)
		(fill yes
			(thermal_gap 0.5)
			(thermal_bridge_width 0.5)
			(island_removal_mode 0)
		)
		(polygon
			(pts
				(arc
					(start 187.390278 -282.335224)
					(mid 186.729878 -282.335224)
					(end 187.390278 -282.335224)
				)
			)
		)
	)
	(zone
		(layers "In1.Cu" "In2.Cu")
		(hatch none 0.5)
		(connect_pads
			(clearance 0)
		)
		(min_thickness 0.25)
		(keepout
			(tracks not_allowed)
			(vias allowed)
			(pads allowed)
			(copperpour not_allowed)
			(footprints allowed)
		)
		(placement
			(enabled no)
			(sheetname "")
		)
		(fill yes
			(thermal_gap 0.5)
			(thermal_bridge_width 0.5)
			(island_removal_mode 0)
		)
		(polygon
			(pts
				(arc
					(start 176.402238 -228.78542)
					(mid 175.741838 -228.78542)
					(end 176.402238 -228.78542)
				)
			)
		)
	)
	(zone
		(layers "In1.Cu" "In2.Cu")
		(hatch none 0.5)
		(connect_pads
			(clearance 0)
		)
		(min_thickness 0.25)
		(keepout
			(tracks not_allowed)
			(vias allowed)
			(pads allowed)
			(copperpour not_allowed)
			(footprints allowed)
		)
		(placement
			(enabled no)
			(sheetname "")
		)
		(fill yes
			(thermal_gap 0.5)
			(thermal_bridge_width 0.5)
			(island_removal_mode 0)
		)
		(polygon
			(pts
				(arc
					(start 420.242238 -254.284988)
					(mid 419.581838 -254.284988)
					(end 420.242238 -254.284988)
				)
			)
		)
	)
	(zone
		(layers "In1.Cu" "In2.Cu")
		(hatch none 0.5)
		(connect_pads
			(clearance 0)
		)
		(min_thickness 0.25)
		(keepout
			(tracks not_allowed)
			(vias allowed)
			(pads allowed)
			(copperpour not_allowed)
			(footprints allowed)
		)
		(placement
			(enabled no)
			(sheetname "")
		)
		(fill yes
			(thermal_gap 0.5)
			(thermal_bridge_width 0.5)
			(island_removal_mode 0)
		)
		(polygon
			(pts
				(arc
					(start 40.57015 -293.38524)
					(mid 39.90975 -293.38524)
					(end 40.57015 -293.38524)
				)
			)
		)
	)
	(zone
		(layers "In1.Cu" "In2.Cu")
		(hatch none 0.5)
		(connect_pads
			(clearance 0)
		)
		(min_thickness 0.25)
		(keepout
			(tracks not_allowed)
			(vias allowed)
			(pads allowed)
			(copperpour not_allowed)
			(footprints allowed)
		)
		(placement
			(enabled no)
			(sheetname "")
		)
		(fill yes
			(thermal_gap 0.5)
			(thermal_bridge_width 0.5)
			(island_removal_mode 0)
		)
		(polygon
			(pts
				(arc
					(start 176.402238 -238.135414)
					(mid 175.741838 -238.135414)
					(end 176.402238 -238.135414)
				)
			)
		)
	)
	(zone
		(layers "In1.Cu" "In2.Cu")
		(hatch none 0.5)
		(connect_pads
			(clearance 0)
		)
		(min_thickness 0.25)
		(keepout
			(tracks not_allowed)
			(vias allowed)
			(pads allowed)
			(copperpour not_allowed)
			(footprints allowed)
		)
		(placement
			(enabled no)
			(sheetname "")
		)
		(fill yes
			(thermal_gap 0.5)
			(thermal_bridge_width 0.5)
			(island_removal_mode 0)
		)
		(polygon
			(pts
				(arc
					(start 199.0344 -278.085296)
					(mid 198.374 -278.085296)
					(end 199.0344 -278.085296)
				)
			)
		)
	)
	(zone
		(layers "In1.Cu" "In2.Cu")
		(hatch none 0.5)
		(connect_pads
			(clearance 0)
		)
		(min_thickness 0.25)
		(keepout
			(tracks not_allowed)
			(vias allowed)
			(pads allowed)
			(copperpour not_allowed)
			(footprints allowed)
		)
		(placement
			(enabled no)
			(sheetname "")
		)
		(fill yes
			(thermal_gap 0.5)
			(thermal_bridge_width 0.5)
			(island_removal_mode 0)
		)
		(polygon
			(pts
				(arc
					(start 454.518268 -270.43507)
					(mid 453.857868 -270.43507)
					(end 454.518268 -270.43507)
				)
			)
		)
	)
	(zone
		(layers "In1.Cu" "In2.Cu")
		(hatch none 0.5)
		(connect_pads
			(clearance 0)
		)
		(min_thickness 0.25)
		(keepout
			(tracks not_allowed)
			(vias allowed)
			(pads allowed)
			(copperpour not_allowed)
			(footprints allowed)
		)
		(placement
			(enabled no)
			(sheetname "")
		)
		(fill yes
			(thermal_gap 0.5)
			(thermal_bridge_width 0.5)
			(island_removal_mode 0)
		)
		(polygon
			(pts
				(arc
					(start 199.0344 -309.535322)
					(mid 198.374 -309.535322)
					(end 199.0344 -309.535322)
				)
			)
		)
	)
	(zone
		(layers "In1.Cu" "In2.Cu")
		(hatch none 0.5)
		(connect_pads
			(clearance 0)
		)
		(min_thickness 0.25)
		(keepout
			(tracks not_allowed)
			(vias allowed)
			(pads allowed)
			(copperpour not_allowed)
			(footprints allowed)
		)
		(placement
			(enabled no)
			(sheetname "")
		)
		(fill yes
			(thermal_gap 0.5)
			(thermal_bridge_width 0.5)
			(island_removal_mode 0)
		)
		(polygon
			(pts
				(arc
					(start 52.214272 -242.385342)
					(mid 51.553872 -242.385342)
					(end 52.214272 -242.385342)
				)
			)
		)
	)
	(zone
		(layers "In1.Cu" "In2.Cu")
		(hatch none 0.5)
		(connect_pads
			(clearance 0)
		)
		(min_thickness 0.25)
		(keepout
			(tracks not_allowed)
			(vias allowed)
			(pads allowed)
			(copperpour not_allowed)
			(footprints allowed)
		)
		(placement
			(enabled no)
			(sheetname "")
		)
		(fill yes
			(thermal_gap 0.5)
			(thermal_bridge_width 0.5)
			(island_removal_mode 0)
		)
		(polygon
			(pts
				(arc
					(start 37.126164 -275.53539)
					(mid 36.465764 -275.53539)
					(end 37.126164 -275.53539)
				)
			)
		)
	)
	(zone
		(layers "In1.Cu" "In2.Cu")
		(hatch none 0.5)
		(connect_pads
			(clearance 0)
		)
		(min_thickness 0.25)
		(keepout
			(tracks not_allowed)
			(vias allowed)
			(pads allowed)
			(copperpour not_allowed)
			(footprints allowed)
		)
		(placement
			(enabled no)
			(sheetname "")
		)
		(fill yes
			(thermal_gap 0.5)
			(thermal_bridge_width 0.5)
			(island_removal_mode 0)
		)
		(polygon
			(pts
				(arc
					(start 48.114204 -312.085228)
					(mid 47.453804 -312.085228)
					(end 48.114204 -312.085228)
				)
			)
		)
	)
	(zone
		(layers "In1.Cu" "In2.Cu")
		(hatch none 0.5)
		(connect_pads
			(clearance 0)
		)
		(min_thickness 0.25)
		(keepout
			(tracks not_allowed)
			(vias allowed)
			(pads allowed)
			(copperpour not_allowed)
			(footprints allowed)
		)
		(placement
			(enabled no)
			(sheetname "")
		)
		(fill yes
			(thermal_gap 0.5)
			(thermal_bridge_width 0.5)
			(island_removal_mode 0)
		)
		(polygon
			(pts
				(arc
					(start 40.57015 -272.98523)
					(mid 39.90975 -272.98523)
					(end 40.57015 -272.98523)
				)
			)
		)
	)
	(zone
		(layers "In1.Cu" "In2.Cu")
		(hatch none 0.5)
		(connect_pads
			(clearance 0)
		)
		(min_thickness 0.25)
		(keepout
			(tracks not_allowed)
			(vias allowed)
			(pads allowed)
			(copperpour not_allowed)
			(footprints allowed)
		)
		(placement
			(enabled no)
			(sheetname "")
		)
		(fill yes
			(thermal_gap 0.5)
			(thermal_bridge_width 0.5)
			(island_removal_mode 0)
		)
		(polygon
			(pts
				(arc
					(start 187.390278 -199.8853)
					(mid 186.729878 -199.8853)
					(end 187.390278 -199.8853)
				)
			)
		)
	)
	(zone
		(layers "In1.Cu" "In2.Cu")
		(hatch none 0.5)
		(connect_pads
			(clearance 0)
		)
		(min_thickness 0.25)
		(keepout
			(tracks not_allowed)
			(vias allowed)
			(pads allowed)
			(copperpour not_allowed)
			(footprints allowed)
		)
		(placement
			(enabled no)
			(sheetname "")
		)
		(fill yes
			(thermal_gap 0.5)
			(thermal_bridge_width 0.5)
			(island_removal_mode 0)
		)
		(polygon
			(pts
				(arc
					(start 187.390278 -235.585254)
					(mid 186.729878 -235.585254)
					(end 187.390278 -235.585254)
				)
			)
		)
	)
	(zone
		(layers "In1.Cu" "In2.Cu")
		(hatch none 0.5)
		(connect_pads
			(clearance 0)
		)
		(min_thickness 0.25)
		(keepout
			(tracks not_allowed)
			(vias allowed)
			(pads allowed)
			(copperpour not_allowed)
			(footprints allowed)
		)
		(placement
			(enabled no)
			(sheetname "")
		)
		(fill yes
			(thermal_gap 0.5)
			(thermal_bridge_width 0.5)
			(island_removal_mode 0)
		)
		(polygon
			(pts
				(arc
					(start 25.482296 -237.285276)
					(mid 24.821896 -237.285276)
					(end 25.482296 -237.285276)
				)
			)
		)
	)
	(zone
		(layers "In1.Cu" "In2.Cu")
		(hatch none 0.5)
		(connect_pads
			(clearance 0)
		)
		(min_thickness 0.25)
		(keepout
			(tracks not_allowed)
			(vias allowed)
			(pads allowed)
			(copperpour not_allowed)
			(footprints allowed)
		)
		(placement
			(enabled no)
			(sheetname "")
		)
		(fill yes
			(thermal_gap 0.5)
			(thermal_bridge_width 0.5)
			(island_removal_mode 0)
		)
		(polygon
			(pts
				(arc
					(start 296.054272 -267.035026)
					(mid 295.393872 -267.035026)
					(end 296.054272 -267.035026)
				)
			)
		)
	)
	(zone
		(layers "In1.Cu" "In2.Cu")
		(hatch none 0.5)
		(connect_pads
			(clearance 0)
		)
		(min_thickness 0.25)
		(keepout
			(tracks not_allowed)
			(vias allowed)
			(pads allowed)
			(copperpour not_allowed)
			(footprints allowed)
		)
		(placement
			(enabled no)
			(sheetname "")
		)
		(fill yes
			(thermal_gap 0.5)
			(thermal_bridge_width 0.5)
			(island_removal_mode 0)
		)
		(polygon
			(pts
				(arc
					(start 194.934332 -215.185244)
					(mid 194.273932 -215.185244)
					(end 194.934332 -215.185244)
				)
			)
		)
	)
	(zone
		(layers "In1.Cu" "In2.Cu")
		(hatch none 0.5)
		(connect_pads
			(clearance 0)
		)
		(min_thickness 0.25)
		(keepout
			(tracks not_allowed)
			(vias allowed)
			(pads allowed)
			(copperpour not_allowed)
			(footprints allowed)
		)
		(placement
			(enabled no)
			(sheetname "")
		)
		(fill yes
			(thermal_gap 0.5)
			(thermal_bridge_width 0.5)
			(island_removal_mode 0)
		)
		(polygon
			(pts
				(arc
					(start 25.482296 -244.935248)
					(mid 24.821896 -244.935248)
					(end 25.482296 -244.935248)
				)
			)
		)
	)
	(zone
		(layers "In1.Cu" "In2.Cu")
		(hatch none 0.5)
		(connect_pads
			(clearance 0)
		)
		(min_thickness 0.25)
		(keepout
			(tracks not_allowed)
			(vias allowed)
			(pads allowed)
			(copperpour not_allowed)
			(footprints allowed)
		)
		(placement
			(enabled no)
			(sheetname "")
		)
		(fill yes
			(thermal_gap 0.5)
			(thermal_bridge_width 0.5)
			(island_removal_mode 0)
		)
		(polygon
			(pts
				(arc
					(start 199.0344 -203.285344)
					(mid 198.374 -203.285344)
					(end 199.0344 -203.285344)
				)
			)
		)
	)
	(zone
		(layers "In1.Cu" "In2.Cu")
		(hatch none 0.5)
		(connect_pads
			(clearance 0)
		)
		(min_thickness 0.25)
		(keepout
			(tracks not_allowed)
			(vias allowed)
			(pads allowed)
			(copperpour not_allowed)
			(footprints allowed)
		)
		(placement
			(enabled no)
			(sheetname "")
		)
		(fill yes
			(thermal_gap 0.5)
			(thermal_bridge_width 0.5)
			(island_removal_mode 0)
		)
		(polygon
			(pts
				(arc
					(start 424.342306 -249.185176)
					(mid 423.681906 -249.185176)
					(end 424.342306 -249.185176)
				)
			)
		)
	)
	(zone
		(layers "In1.Cu" "In2.Cu")
		(hatch none 0.5)
		(connect_pads
			(clearance 0)
		)
		(min_thickness 0.25)
		(keepout
			(tracks not_allowed)
			(vias allowed)
			(pads allowed)
			(copperpour not_allowed)
			(footprints allowed)
		)
		(placement
			(enabled no)
			(sheetname "")
		)
		(fill yes
			(thermal_gap 0.5)
			(thermal_bridge_width 0.5)
			(island_removal_mode 0)
		)
		(polygon
			(pts
				(arc
					(start 450.4182 -265.335004)
					(mid 449.7578 -265.335004)
					(end 450.4182 -265.335004)
				)
			)
		)
	)
	(zone
		(layers "In1.Cu" "In2.Cu")
		(hatch none 0.5)
		(connect_pads
			(clearance 0)
		)
		(min_thickness 0.25)
		(keepout
			(tracks not_allowed)
			(vias allowed)
			(pads allowed)
			(copperpour not_allowed)
			(footprints allowed)
		)
		(placement
			(enabled no)
			(sheetname "")
		)
		(fill yes
			(thermal_gap 0.5)
			(thermal_bridge_width 0.5)
			(island_removal_mode 0)
		)
		(polygon
			(pts
				(arc
					(start 183.946292 -312.935366)
					(mid 183.285892 -312.935366)
					(end 183.946292 -312.935366)
				)
			)
		)
	)
	(zone
		(layers "In1.Cu" "In2.Cu")
		(hatch none 0.5)
		(connect_pads
			(clearance 0)
		)
		(min_thickness 0.25)
		(keepout
			(tracks not_allowed)
			(vias allowed)
			(pads allowed)
			(copperpour not_allowed)
			(footprints allowed)
		)
		(placement
			(enabled no)
			(sheetname "")
		)
		(fill yes
			(thermal_gap 0.5)
			(thermal_bridge_width 0.5)
			(island_removal_mode 0)
		)
		(polygon
			(pts
				(arc
					(start 424.342306 -238.13516)
					(mid 423.681906 -238.13516)
					(end 424.342306 -238.13516)
				)
			)
		)
	)
	(zone
		(layers "In1.Cu" "In2.Cu")
		(hatch none 0.5)
		(connect_pads
			(clearance 0)
		)
		(min_thickness 0.25)
		(keepout
			(tracks not_allowed)
			(vias allowed)
			(pads allowed)
			(copperpour not_allowed)
			(footprints allowed)
		)
		(placement
			(enabled no)
			(sheetname "")
		)
		(fill yes
			(thermal_gap 0.5)
			(thermal_bridge_width 0.5)
			(island_removal_mode 0)
		)
		(polygon
			(pts
				(arc
					(start 22.03831 -292.535356)
					(mid 21.37791 -292.535356)
					(end 22.03831 -292.535356)
				)
			)
		)
	)
	(zone
		(layers "In1.Cu" "In2.Cu")
		(hatch none 0.5)
		(connect_pads
			(clearance 0)
		)
		(min_thickness 0.25)
		(keepout
			(tracks not_allowed)
			(vias allowed)
			(pads allowed)
			(copperpour not_allowed)
			(footprints allowed)
		)
		(placement
			(enabled no)
			(sheetname "")
		)
		(fill yes
			(thermal_gap 0.5)
			(thermal_bridge_width 0.5)
			(island_removal_mode 0)
		)
		(polygon
			(pts
				(arc
					(start 22.03831 -225.385376)
					(mid 21.37791 -225.385376)
					(end 22.03831 -225.385376)
				)
			)
		)
	)
	(zone
		(layers "In1.Cu" "In2.Cu")
		(hatch none 0.5)
		(connect_pads
			(clearance 0)
		)
		(min_thickness 0.25)
		(keepout
			(tracks not_allowed)
			(vias allowed)
			(pads allowed)
			(copperpour not_allowed)
			(footprints allowed)
		)
		(placement
			(enabled no)
			(sheetname "")
		)
		(fill yes
			(thermal_gap 0.5)
			(thermal_bridge_width 0.5)
			(island_removal_mode 0)
		)
		(polygon
			(pts
				(arc
					(start 37.126164 -289.135312)
					(mid 36.465764 -289.135312)
					(end 37.126164 -289.135312)
				)
			)
		)
	)
	(zone
		(layers "In1.Cu" "In2.Cu")
		(hatch none 0.5)
		(connect_pads
			(clearance 0)
		)
		(min_thickness 0.25)
		(keepout
			(tracks not_allowed)
			(vias allowed)
			(pads allowed)
			(copperpour not_allowed)
			(footprints allowed)
		)
		(placement
			(enabled no)
			(sheetname "")
		)
		(fill yes
			(thermal_gap 0.5)
			(thermal_bridge_width 0.5)
			(island_removal_mode 0)
		)
		(polygon
			(pts
				(arc
					(start 176.402238 -234.73537)
					(mid 175.741838 -234.73537)
					(end 176.402238 -234.73537)
				)
			)
		)
	)
	(zone
		(layers "In1.Cu" "In2.Cu")
		(hatch none 0.5)
		(connect_pads
			(clearance 0)
		)
		(min_thickness 0.25)
		(keepout
			(tracks not_allowed)
			(vias allowed)
			(pads allowed)
			(copperpour not_allowed)
			(footprints allowed)
		)
		(placement
			(enabled no)
			(sheetname "")
		)
		(fill yes
			(thermal_gap 0.5)
			(thermal_bridge_width 0.5)
			(island_removal_mode 0)
		)
		(polygon
			(pts
				(arc
					(start 427.786292 -289.985196)
					(mid 427.125892 -289.985196)
					(end 427.786292 -289.985196)
				)
			)
		)
	)
	(zone
		(layers "In1.Cu" "In2.Cu")
		(hatch none 0.5)
		(connect_pads
			(clearance 0)
		)
		(min_thickness 0.25)
		(keepout
			(tracks not_allowed)
			(vias allowed)
			(pads allowed)
			(copperpour not_allowed)
			(footprints allowed)
		)
		(placement
			(enabled no)
			(sheetname "")
		)
		(fill yes
			(thermal_gap 0.5)
			(thermal_bridge_width 0.5)
			(island_removal_mode 0)
		)
		(polygon
			(pts
				(arc
					(start 33.026096 -198.185278)
					(mid 32.365696 -198.185278)
					(end 33.026096 -198.185278)
				)
			)
		)
	)
	(zone
		(layers "In1.Cu" "In2.Cu")
		(hatch none 0.5)
		(connect_pads
			(clearance 0)
		)
		(min_thickness 0.25)
		(keepout
			(tracks not_allowed)
			(vias allowed)
			(pads allowed)
			(copperpour not_allowed)
			(footprints allowed)
		)
		(placement
			(enabled no)
			(sheetname "")
		)
		(fill yes
			(thermal_gap 0.5)
			(thermal_bridge_width 0.5)
			(island_removal_mode 0)
		)
		(polygon
			(pts
				(arc
					(start 424.342306 -279.785064)
					(mid 423.681906 -279.785064)
					(end 424.342306 -279.785064)
				)
			)
		)
	)
	(zone
		(layers "In1.Cu" "In2.Cu")
		(hatch none 0.5)
		(connect_pads
			(clearance 0)
		)
		(min_thickness 0.25)
		(keepout
			(tracks not_allowed)
			(vias allowed)
			(pads allowed)
			(copperpour not_allowed)
			(footprints allowed)
		)
		(placement
			(enabled no)
			(sheetname "")
		)
		(fill yes
			(thermal_gap 0.5)
			(thermal_bridge_width 0.5)
			(island_removal_mode 0)
		)
		(polygon
			(pts
				(arc
					(start 18.218404 -421.805354)
					(mid 18.233283 -421.769433)
					(end 18.269204 -421.754554)
				)
				(arc
					(start 18.777204 -421.754554)
					(mid 18.813125 -421.769433)
					(end 18.828004 -421.805354)
				)
				(arc
					(start 18.828004 -422.46169)
					(mid 18.813125 -422.497611)
					(end 18.777204 -422.51249)
				)
				(arc
					(start 18.269204 -422.51249)
					(mid 18.233283 -422.497611)
					(end 18.218404 -422.46169)
				)
			)
		)
	)
	(zone
		(layers "In1.Cu" "In2.Cu")
		(hatch none 0.5)
		(connect_pads
			(clearance 0)
		)
		(min_thickness 0.25)
		(keepout
			(tracks not_allowed)
			(vias allowed)
			(pads allowed)
			(copperpour not_allowed)
			(footprints allowed)
		)
		(placement
			(enabled no)
			(sheetname "")
		)
		(fill yes
			(thermal_gap 0.5)
			(thermal_bridge_width 0.5)
			(island_removal_mode 0)
		)
		(polygon
			(pts
				(arc
					(start 176.402238 -279.785318)
					(mid 175.741838 -279.785318)
					(end 176.402238 -279.785318)
				)
			)
		)
	)
	(zone
		(layers "In1.Cu" "In2.Cu")
		(hatch none 0.5)
		(connect_pads
			(clearance 0)
		)
		(min_thickness 0.25)
		(keepout
			(tracks not_allowed)
			(vias allowed)
			(pads allowed)
			(copperpour not_allowed)
			(footprints allowed)
		)
		(placement
			(enabled no)
			(sheetname "")
		)
		(fill yes
			(thermal_gap 0.5)
			(thermal_bridge_width 0.5)
			(island_removal_mode 0)
		)
		(polygon
			(pts
				(arc
					(start 202.478132 -284.035246)
					(mid 201.817732 -284.035246)
					(end 202.478132 -284.035246)
				)
			)
		)
	)
	(zone
		(layers "In1.Cu" "In2.Cu")
		(hatch none 0.5)
		(connect_pads
			(clearance 0)
		)
		(min_thickness 0.25)
		(keepout
			(tracks not_allowed)
			(vias allowed)
			(pads allowed)
			(copperpour not_allowed)
			(footprints allowed)
		)
		(placement
			(enabled no)
			(sheetname "")
		)
		(fill yes
			(thermal_gap 0.5)
			(thermal_bridge_width 0.5)
			(island_removal_mode 0)
		)
		(polygon
			(pts
				(arc
					(start 44.670218 -225.385376)
					(mid 44.009818 -225.385376)
					(end 44.670218 -225.385376)
				)
			)
		)
	)
	(zone
		(layers "In1.Cu" "In2.Cu")
		(hatch none 0.5)
		(connect_pads
			(clearance 0)
		)
		(min_thickness 0.25)
		(keepout
			(tracks not_allowed)
			(vias allowed)
			(pads allowed)
			(copperpour not_allowed)
			(footprints allowed)
		)
		(placement
			(enabled no)
			(sheetname "")
		)
		(fill yes
			(thermal_gap 0.5)
			(thermal_bridge_width 0.5)
			(island_removal_mode 0)
		)
		(polygon
			(pts
				(arc
					(start 285.066232 -228.785166)
					(mid 284.405832 -228.785166)
					(end 285.066232 -228.785166)
				)
			)
		)
	)
	(zone
		(layers "In1.Cu" "In2.Cu")
		(hatch none 0.5)
		(connect_pads
			(clearance 0)
		)
		(min_thickness 0.25)
		(keepout
			(tracks not_allowed)
			(vias allowed)
			(pads allowed)
			(copperpour not_allowed)
			(footprints allowed)
		)
		(placement
			(enabled no)
			(sheetname "")
		)
		(fill yes
			(thermal_gap 0.5)
			(thermal_bridge_width 0.5)
			(island_removal_mode 0)
		)
		(polygon
			(pts
				(arc
					(start 450.4182 -218.585034)
					(mid 449.7578 -218.585034)
					(end 450.4182 -218.585034)
				)
			)
		)
	)
	(zone
		(layers "In1.Cu" "In2.Cu")
		(hatch none 0.5)
		(connect_pads
			(clearance 0)
		)
		(min_thickness 0.25)
		(keepout
			(tracks not_allowed)
			(vias allowed)
			(pads allowed)
			(copperpour not_allowed)
			(footprints allowed)
		)
		(placement
			(enabled no)
			(sheetname "")
		)
		(fill yes
			(thermal_gap 0.5)
			(thermal_bridge_width 0.5)
			(island_removal_mode 0)
		)
		(polygon
			(pts
				(arc
					(start 37.126164 -200.735438)
					(mid 36.465764 -200.735438)
					(end 37.126164 -200.735438)
				)
			)
		)
	)
	(zone
		(layers "In1.Cu" "In2.Cu")
		(hatch none 0.5)
		(connect_pads
			(clearance 0)
		)
		(min_thickness 0.25)
		(keepout
			(tracks not_allowed)
			(vias allowed)
			(pads allowed)
			(copperpour not_allowed)
			(footprints allowed)
		)
		(placement
			(enabled no)
			(sheetname "")
		)
		(fill yes
			(thermal_gap 0.5)
			(thermal_bridge_width 0.5)
			(island_removal_mode 0)
		)
		(polygon
			(pts
				(arc
					(start 285.066232 -219.435172)
					(mid 284.405832 -219.435172)
					(end 285.066232 -219.435172)
				)
			)
		)
	)
	(zone
		(layers "In1.Cu" "In2.Cu")
		(hatch none 0.5)
		(connect_pads
			(clearance 0)
		)
		(min_thickness 0.25)
		(keepout
			(tracks not_allowed)
			(vias allowed)
			(pads allowed)
			(copperpour not_allowed)
			(footprints allowed)
		)
		(placement
			(enabled no)
			(sheetname "")
		)
		(fill yes
			(thermal_gap 0.5)
			(thermal_bridge_width 0.5)
			(island_removal_mode 0)
		)
		(polygon
			(pts
				(arc
					(start 187.390278 -293.38524)
					(mid 186.729878 -293.38524)
					(end 187.390278 -293.38524)
				)
			)
		)
	)
	(zone
		(layers "In1.Cu" "In2.Cu")
		(hatch none 0.5)
		(connect_pads
			(clearance 0)
		)
		(min_thickness 0.25)
		(keepout
			(tracks not_allowed)
			(vias allowed)
			(pads allowed)
			(copperpour not_allowed)
			(footprints allowed)
		)
		(placement
			(enabled no)
			(sheetname "")
		)
		(fill yes
			(thermal_gap 0.5)
			(thermal_bridge_width 0.5)
			(island_removal_mode 0)
		)
		(polygon
			(pts
				(arc
					(start 176.402238 -227.085398)
					(mid 175.741838 -227.085398)
					(end 176.402238 -227.085398)
				)
			)
		)
	)
	(zone
		(layers "In1.Cu" "In2.Cu")
		(hatch none 0.5)
		(connect_pads
			(clearance 0)
		)
		(min_thickness 0.25)
		(keepout
			(tracks not_allowed)
			(vias allowed)
			(pads allowed)
			(copperpour not_allowed)
			(footprints allowed)
		)
		(placement
			(enabled no)
			(sheetname "")
		)
		(fill yes
			(thermal_gap 0.5)
			(thermal_bridge_width 0.5)
			(island_removal_mode 0)
		)
		(polygon
			(pts
				(arc
					(start 33.026096 -318.035432)
					(mid 32.365696 -318.035432)
					(end 33.026096 -318.035432)
				)
			)
		)
	)
	(zone
		(layers "In1.Cu" "In2.Cu")
		(hatch none 0.5)
		(connect_pads
			(clearance 0)
		)
		(min_thickness 0.25)
		(keepout
			(tracks not_allowed)
			(vias allowed)
			(pads allowed)
			(copperpour not_allowed)
			(footprints allowed)
		)
		(placement
			(enabled no)
			(sheetname "")
		)
		(fill yes
			(thermal_gap 0.5)
			(thermal_bridge_width 0.5)
			(island_removal_mode 0)
		)
		(polygon
			(pts
				(arc
					(start 176.402238 -298.485306)
					(mid 175.741838 -298.485306)
					(end 176.402238 -298.485306)
				)
			)
		)
	)
	(zone
		(layers "In1.Cu" "In2.Cu")
		(hatch none 0.5)
		(connect_pads
			(clearance 0)
		)
		(min_thickness 0.25)
		(keepout
			(tracks not_allowed)
			(vias allowed)
			(pads allowed)
			(copperpour not_allowed)
			(footprints allowed)
		)
		(placement
			(enabled no)
			(sheetname "")
		)
		(fill yes
			(thermal_gap 0.5)
			(thermal_bridge_width 0.5)
			(island_removal_mode 0)
		)
		(polygon
			(pts
				(arc
					(start 398.752314 -7.672324)
					(mid 398.774632 -7.618442)
					(end 398.828514 -7.596124)
				)
				(arc
					(start 399.865088 -7.596124)
					(mid 399.91897 -7.618442)
					(end 399.941288 -7.672324)
				)
				(arc
					(start 399.941288 -9.071864)
					(mid 399.91897 -9.125746)
					(end 399.865088 -9.148064)
				)
				(arc
					(start 398.828514 -9.148064)
					(mid 398.774632 -9.125746)
					(end 398.752314 -9.071864)
				)
			)
		)
	)
	(zone
		(layers "In1.Cu" "In2.Cu")
		(hatch none 0.5)
		(connect_pads
			(clearance 0)
		)
		(min_thickness 0.25)
		(keepout
			(tracks not_allowed)
			(vias allowed)
			(pads allowed)
			(copperpour not_allowed)
			(footprints allowed)
		)
		(placement
			(enabled no)
			(sheetname "")
		)
		(fill yes
			(thermal_gap 0.5)
			(thermal_bridge_width 0.5)
			(island_removal_mode 0)
		)
		(polygon
			(pts
				(arc
					(start 424.342306 -312.935112)
					(mid 423.681906 -312.935112)
					(end 424.342306 -312.935112)
				)
			)
		)
	)
	(zone
		(layers "In1.Cu" "In2.Cu")
		(hatch none 0.5)
		(connect_pads
			(clearance 0)
		)
		(min_thickness 0.25)
		(keepout
			(tracks not_allowed)
			(vias allowed)
			(pads allowed)
			(copperpour not_allowed)
			(footprints allowed)
		)
		(placement
			(enabled no)
			(sheetname "")
		)
		(fill yes
			(thermal_gap 0.5)
			(thermal_bridge_width 0.5)
			(island_removal_mode 0)
		)
		(polygon
			(pts
				(arc
					(start 435.330346 -244.934994)
					(mid 434.669946 -244.934994)
					(end 435.330346 -244.934994)
				)
			)
		)
	)
	(zone
		(layers "In1.Cu" "In2.Cu")
		(hatch none 0.5)
		(connect_pads
			(clearance 0)
		)
		(min_thickness 0.25)
		(keepout
			(tracks not_allowed)
			(vias allowed)
			(pads allowed)
			(copperpour not_allowed)
			(footprints allowed)
		)
		(placement
			(enabled no)
			(sheetname "")
		)
		(fill yes
			(thermal_gap 0.5)
			(thermal_bridge_width 0.5)
			(island_removal_mode 0)
		)
		(polygon
			(pts
				(arc
					(start 191.490346 -206.685388)
					(mid 190.829946 -206.685388)
					(end 191.490346 -206.685388)
				)
			)
		)
	)
	(zone
		(layers "In1.Cu" "In2.Cu")
		(hatch none 0.5)
		(connect_pads
			(clearance 0)
		)
		(min_thickness 0.25)
		(keepout
			(tracks not_allowed)
			(vias allowed)
			(pads allowed)
			(copperpour not_allowed)
			(footprints allowed)
		)
		(placement
			(enabled no)
			(sheetname "")
		)
		(fill yes
			(thermal_gap 0.5)
			(thermal_bridge_width 0.5)
			(island_removal_mode 0)
		)
		(polygon
			(pts
				(arc
					(start 439.430414 -276.38502)
					(mid 438.770014 -276.38502)
					(end 439.430414 -276.38502)
				)
			)
		)
	)
	(zone
		(layers "In1.Cu" "In2.Cu")
		(hatch none 0.5)
		(connect_pads
			(clearance 0)
		)
		(min_thickness 0.25)
		(keepout
			(tracks not_allowed)
			(vias allowed)
			(pads allowed)
			(copperpour not_allowed)
			(footprints allowed)
		)
		(placement
			(enabled no)
			(sheetname "")
		)
		(fill yes
			(thermal_gap 0.5)
			(thermal_bridge_width 0.5)
			(island_removal_mode 0)
		)
		(polygon
			(pts
				(arc
					(start 435.330346 -268.735048)
					(mid 434.669946 -268.735048)
					(end 435.330346 -268.735048)
				)
			)
		)
	)
	(zone
		(layers "In1.Cu" "In2.Cu")
		(hatch none 0.5)
		(connect_pads
			(clearance 0)
		)
		(min_thickness 0.25)
		(keepout
			(tracks not_allowed)
			(vias allowed)
			(pads allowed)
			(copperpour not_allowed)
			(footprints allowed)
		)
		(placement
			(enabled no)
			(sheetname "")
		)
		(fill yes
			(thermal_gap 0.5)
			(thermal_bridge_width 0.5)
			(island_removal_mode 0)
		)
		(polygon
			(pts
				(arc
					(start 277.522432 -315.485018)
					(mid 276.862032 -315.485018)
					(end 277.522432 -315.485018)
				)
			)
		)
	)
	(zone
		(layers "In1.Cu" "In2.Cu")
		(hatch none 0.5)
		(connect_pads
			(clearance 0)
		)
		(min_thickness 0.25)
		(keepout
			(tracks not_allowed)
			(vias allowed)
			(pads allowed)
			(copperpour not_allowed)
			(footprints allowed)
		)
		(placement
			(enabled no)
			(sheetname "")
		)
		(fill yes
			(thermal_gap 0.5)
			(thermal_bridge_width 0.5)
			(island_removal_mode 0)
		)
		(polygon
			(pts
				(arc
					(start 29.582364 -236.435392)
					(mid 28.921964 -236.435392)
					(end 29.582364 -236.435392)
				)
			)
		)
	)
	(zone
		(layers "In1.Cu" "In2.Cu")
		(hatch none 0.5)
		(connect_pads
			(clearance 0)
		)
		(min_thickness 0.25)
		(keepout
			(tracks not_allowed)
			(vias allowed)
			(pads allowed)
			(copperpour not_allowed)
			(footprints allowed)
		)
		(placement
			(enabled no)
			(sheetname "")
		)
		(fill yes
			(thermal_gap 0.5)
			(thermal_bridge_width 0.5)
			(island_removal_mode 0)
		)
		(polygon
			(pts
				(arc
					(start 48.114204 -280.635202)
					(mid 47.453804 -280.635202)
					(end 48.114204 -280.635202)
				)
			)
		)
	)
	(zone
		(layers "In1.Cu" "In2.Cu")
		(hatch none 0.5)
		(connect_pads
			(clearance 0)
		)
		(min_thickness 0.25)
		(keepout
			(tracks not_allowed)
			(vias allowed)
			(pads allowed)
			(copperpour not_allowed)
			(footprints allowed)
		)
		(placement
			(enabled no)
			(sheetname "")
		)
		(fill yes
			(thermal_gap 0.5)
			(thermal_bridge_width 0.5)
			(island_removal_mode 0)
		)
		(polygon
			(pts
				(arc
					(start 33.026096 -244.935248)
					(mid 32.365696 -244.935248)
					(end 33.026096 -244.935248)
				)
			)
		)
	)
	(zone
		(layers "In1.Cu" "In2.Cu")
		(hatch none 0.5)
		(connect_pads
			(clearance 0)
		)
		(min_thickness 0.25)
		(keepout
			(tracks not_allowed)
			(vias allowed)
			(pads allowed)
			(copperpour not_allowed)
			(footprints allowed)
		)
		(placement
			(enabled no)
			(sheetname "")
		)
		(fill yes
			(thermal_gap 0.5)
			(thermal_bridge_width 0.5)
			(island_removal_mode 0)
		)
		(polygon
			(pts
				(arc
					(start 199.0344 -283.185362)
					(mid 198.374 -283.185362)
					(end 199.0344 -283.185362)
				)
			)
		)
	)
	(zone
		(layers "In1.Cu" "In2.Cu")
		(hatch none 0.5)
		(connect_pads
			(clearance 0)
		)
		(min_thickness 0.25)
		(keepout
			(tracks not_allowed)
			(vias allowed)
			(pads allowed)
			(copperpour not_allowed)
			(footprints allowed)
		)
		(placement
			(enabled no)
			(sheetname "")
		)
		(fill yes
			(thermal_gap 0.5)
			(thermal_bridge_width 0.5)
			(island_removal_mode 0)
		)
		(polygon
			(pts
				(arc
					(start 292.610286 -203.28509)
					(mid 291.949886 -203.28509)
					(end 292.610286 -203.28509)
				)
			)
		)
	)
	(zone
		(layers "In1.Cu" "In2.Cu")
		(hatch none 0.5)
		(connect_pads
			(clearance 0)
		)
		(min_thickness 0.25)
		(keepout
			(tracks not_allowed)
			(vias allowed)
			(pads allowed)
			(copperpour not_allowed)
			(footprints allowed)
		)
		(placement
			(enabled no)
			(sheetname "")
		)
		(fill yes
			(thermal_gap 0.5)
			(thermal_bridge_width 0.5)
			(island_removal_mode 0)
		)
		(polygon
			(pts
				(arc
					(start 179.846224 -221.135194)
					(mid 179.185824 -221.135194)
					(end 179.846224 -221.135194)
				)
			)
		)
	)
	(zone
		(layers "In1.Cu" "In2.Cu")
		(hatch none 0.5)
		(connect_pads
			(clearance 0)
		)
		(min_thickness 0.25)
		(keepout
			(tracks not_allowed)
			(vias allowed)
			(pads allowed)
			(copperpour not_allowed)
			(footprints allowed)
		)
		(placement
			(enabled no)
			(sheetname "")
		)
		(fill yes
			(thermal_gap 0.5)
			(thermal_bridge_width 0.5)
			(island_removal_mode 0)
		)
		(polygon
			(pts
				(arc
					(start 179.846224 -227.935282)
					(mid 179.185824 -227.935282)
					(end 179.846224 -227.935282)
				)
			)
		)
	)
	(zone
		(layers "In1.Cu" "In2.Cu")
		(hatch none 0.5)
		(connect_pads
			(clearance 0)
		)
		(min_thickness 0.25)
		(keepout
			(tracks not_allowed)
			(vias allowed)
			(pads allowed)
			(copperpour not_allowed)
			(footprints allowed)
		)
		(placement
			(enabled no)
			(sheetname "")
		)
		(fill yes
			(thermal_gap 0.5)
			(thermal_bridge_width 0.5)
			(island_removal_mode 0)
		)
		(polygon
			(pts
				(arc
					(start 176.402238 -254.285242)
					(mid 175.741838 -254.285242)
					(end 176.402238 -254.285242)
				)
			)
		)
	)
	(zone
		(layers "In1.Cu" "In2.Cu")
		(hatch none 0.5)
		(connect_pads
			(clearance 0)
		)
		(min_thickness 0.25)
		(keepout
			(tracks not_allowed)
			(vias allowed)
			(pads allowed)
			(copperpour not_allowed)
			(footprints allowed)
		)
		(placement
			(enabled no)
			(sheetname "")
		)
		(fill yes
			(thermal_gap 0.5)
			(thermal_bridge_width 0.5)
			(island_removal_mode 0)
		)
		(polygon
			(pts
				(arc
					(start 269.978378 -301.885096)
					(mid 269.317978 -301.885096)
					(end 269.978378 -301.885096)
				)
			)
		)
	)
	(zone
		(layers "In1.Cu" "In2.Cu")
		(hatch none 0.5)
		(connect_pads
			(clearance 0)
		)
		(min_thickness 0.25)
		(keepout
			(tracks not_allowed)
			(vias allowed)
			(pads allowed)
			(copperpour not_allowed)
			(footprints allowed)
		)
		(placement
			(enabled no)
			(sheetname "")
		)
		(fill yes
			(thermal_gap 0.5)
			(thermal_bridge_width 0.5)
			(island_removal_mode 0)
		)
		(polygon
			(pts
				(arc
					(start 280.966164 -230.485188)
					(mid 280.305764 -230.485188)
					(end 280.966164 -230.485188)
				)
			)
		)
	)
	(zone
		(layers "In1.Cu" "In2.Cu")
		(hatch none 0.5)
		(connect_pads
			(clearance 0)
		)
		(min_thickness 0.25)
		(keepout
			(tracks not_allowed)
			(vias allowed)
			(pads allowed)
			(copperpour not_allowed)
			(footprints allowed)
		)
		(placement
			(enabled no)
			(sheetname "")
		)
		(fill yes
			(thermal_gap 0.5)
			(thermal_bridge_width 0.5)
			(island_removal_mode 0)
		)
		(polygon
			(pts
				(arc
					(start 435.330346 -308.685184)
					(mid 434.669946 -308.685184)
					(end 435.330346 -308.685184)
				)
			)
		)
	)
	(zone
		(layers "In1.Cu" "In2.Cu")
		(hatch none 0.5)
		(connect_pads
			(clearance 0)
		)
		(min_thickness 0.25)
		(keepout
			(tracks not_allowed)
			(vias allowed)
			(pads allowed)
			(copperpour not_allowed)
			(footprints allowed)
		)
		(placement
			(enabled no)
			(sheetname "")
		)
		(fill yes
			(thermal_gap 0.5)
			(thermal_bridge_width 0.5)
			(island_removal_mode 0)
		)
		(polygon
			(pts
				(arc
					(start 179.846224 -233.885232)
					(mid 179.185824 -233.885232)
					(end 179.846224 -233.885232)
				)
			)
		)
	)
	(zone
		(layers "In1.Cu" "In2.Cu")
		(hatch none 0.5)
		(connect_pads
			(clearance 0)
		)
		(min_thickness 0.25)
		(keepout
			(tracks not_allowed)
			(vias allowed)
			(pads allowed)
			(copperpour not_allowed)
			(footprints allowed)
		)
		(placement
			(enabled no)
			(sheetname "")
		)
		(fill yes
			(thermal_gap 0.5)
			(thermal_bridge_width 0.5)
			(island_removal_mode 0)
		)
		(polygon
			(pts
				(arc
					(start 300.15434 -296.78503)
					(mid 299.49394 -296.78503)
					(end 300.15434 -296.78503)
				)
			)
		)
	)
	(zone
		(layers "In1.Cu" "In2.Cu")
		(hatch none 0.5)
		(connect_pads
			(clearance 0)
		)
		(min_thickness 0.25)
		(keepout
			(tracks not_allowed)
			(vias allowed)
			(pads allowed)
			(copperpour not_allowed)
			(footprints allowed)
		)
		(placement
			(enabled no)
			(sheetname "")
		)
		(fill yes
			(thermal_gap 0.5)
			(thermal_bridge_width 0.5)
			(island_removal_mode 0)
		)
		(polygon
			(pts
				(arc
					(start 194.934332 -233.885232)
					(mid 194.273932 -233.885232)
					(end 194.934332 -233.885232)
				)
			)
		)
	)
	(zone
		(layers "In1.Cu" "In2.Cu")
		(hatch none 0.5)
		(connect_pads
			(clearance 0)
		)
		(min_thickness 0.25)
		(keepout
			(tracks not_allowed)
			(vias allowed)
			(pads allowed)
			(copperpour not_allowed)
			(footprints allowed)
		)
		(placement
			(enabled no)
			(sheetname "")
		)
		(fill yes
			(thermal_gap 0.5)
			(thermal_bridge_width 0.5)
			(island_removal_mode 0)
		)
		(polygon
			(pts
				(arc
					(start 446.974468 -283.185108)
					(mid 446.314068 -283.185108)
					(end 446.974468 -283.185108)
				)
			)
		)
	)
	(zone
		(layers "In1.Cu" "In2.Cu")
		(hatch none 0.5)
		(connect_pads
			(clearance 0)
		)
		(min_thickness 0.25)
		(keepout
			(tracks not_allowed)
			(vias allowed)
			(pads allowed)
			(copperpour not_allowed)
			(footprints allowed)
		)
		(placement
			(enabled no)
			(sheetname "")
		)
		(fill yes
			(thermal_gap 0.5)
			(thermal_bridge_width 0.5)
			(island_removal_mode 0)
		)
		(polygon
			(pts
				(arc
					(start 44.670218 -242.385342)
					(mid 44.009818 -242.385342)
					(end 44.670218 -242.385342)
				)
			)
		)
	)
	(zone
		(layers "In1.Cu" "In2.Cu")
		(hatch none 0.5)
		(connect_pads
			(clearance 0)
		)
		(min_thickness 0.25)
		(keepout
			(tracks not_allowed)
			(vias allowed)
			(pads allowed)
			(copperpour not_allowed)
			(footprints allowed)
		)
		(placement
			(enabled no)
			(sheetname "")
		)
		(fill yes
			(thermal_gap 0.5)
			(thermal_bridge_width 0.5)
			(island_removal_mode 0)
		)
		(polygon
			(pts
				(arc
					(start 48.114204 -244.935248)
					(mid 47.453804 -244.935248)
					(end 48.114204 -244.935248)
				)
			)
		)
	)
	(zone
		(layers "In1.Cu" "In2.Cu")
		(hatch none 0.5)
		(connect_pads
			(clearance 0)
		)
		(min_thickness 0.25)
		(keepout
			(tracks not_allowed)
			(vias allowed)
			(pads allowed)
			(copperpour not_allowed)
			(footprints allowed)
		)
		(placement
			(enabled no)
			(sheetname "")
		)
		(fill yes
			(thermal_gap 0.5)
			(thermal_bridge_width 0.5)
			(island_removal_mode 0)
		)
		(polygon
			(pts
				(arc
					(start 40.57015 -213.485222)
					(mid 39.90975 -213.485222)
					(end 40.57015 -213.485222)
				)
			)
		)
	)
	(zone
		(layers "In1.Cu" "In2.Cu")
		(hatch none 0.5)
		(connect_pads
			(clearance 0)
		)
		(min_thickness 0.25)
		(keepout
			(tracks not_allowed)
			(vias allowed)
			(pads allowed)
			(copperpour not_allowed)
			(footprints allowed)
		)
		(placement
			(enabled no)
			(sheetname "")
		)
		(fill yes
			(thermal_gap 0.5)
			(thermal_bridge_width 0.5)
			(island_removal_mode 0)
		)
		(polygon
			(pts
				(arc
					(start 435.330346 -250.03506)
					(mid 434.669946 -250.03506)
					(end 435.330346 -250.03506)
				)
			)
		)
	)
	(zone
		(layers "In1.Cu" "In2.Cu")
		(hatch none 0.5)
		(connect_pads
			(clearance 0)
		)
		(min_thickness 0.25)
		(keepout
			(tracks not_allowed)
			(vias allowed)
			(pads allowed)
			(copperpour not_allowed)
			(footprints allowed)
		)
		(placement
			(enabled no)
			(sheetname "")
		)
		(fill yes
			(thermal_gap 0.5)
			(thermal_bridge_width 0.5)
			(island_removal_mode 0)
		)
		(polygon
			(pts
				(arc
					(start 439.430414 -223.6851)
					(mid 438.770014 -223.6851)
					(end 439.430414 -223.6851)
				)
			)
		)
	)
	(zone
		(layers "In1.Cu" "In2.Cu")
		(hatch none 0.5)
		(connect_pads
			(clearance 0)
		)
		(min_thickness 0.25)
		(keepout
			(tracks not_allowed)
			(vias allowed)
			(pads allowed)
			(copperpour not_allowed)
			(footprints allowed)
		)
		(placement
			(enabled no)
			(sheetname "")
		)
		(fill yes
			(thermal_gap 0.5)
			(thermal_bridge_width 0.5)
			(island_removal_mode 0)
		)
		(polygon
			(pts
				(arc
					(start 135.22198 -28.06192)
					(mid 135.186059 -28.076799)
					(end 135.17118 -28.11272)
				)
				(arc
					(start 135.17118 -29.38272)
					(mid 135.186059 -29.418641)
					(end 135.22198 -29.43352)
				)
				(arc
					(start 135.50138 -29.43352)
					(mid 135.537301 -29.418641)
					(end 135.55218 -29.38272)
				)
				(arc
					(start 135.55218 -28.11272)
					(mid 135.537301 -28.076799)
					(end 135.50138 -28.06192)
				)
			)
		)
	)
	(zone
		(layers "In1.Cu" "In2.Cu")
		(hatch none 0.5)
		(connect_pads
			(clearance 0)
		)
		(min_thickness 0.25)
		(keepout
			(tracks not_allowed)
			(vias allowed)
			(pads allowed)
			(copperpour not_allowed)
			(footprints allowed)
		)
		(placement
			(enabled no)
			(sheetname "")
		)
		(fill yes
			(thermal_gap 0.5)
			(thermal_bridge_width 0.5)
			(island_removal_mode 0)
		)
		(polygon
			(pts
				(arc
					(start 52.214272 -208.38541)
					(mid 51.553872 -208.38541)
					(end 52.214272 -208.38541)
				)
			)
		)
	)
	(zone
		(layers "In1.Cu" "In2.Cu")
		(hatch none 0.5)
		(connect_pads
			(clearance 0)
		)
		(min_thickness 0.25)
		(keepout
			(tracks not_allowed)
			(vias allowed)
			(pads allowed)
			(copperpour not_allowed)
			(footprints allowed)
		)
		(placement
			(enabled no)
			(sheetname "")
		)
		(fill yes
			(thermal_gap 0.5)
			(thermal_bridge_width 0.5)
			(island_removal_mode 0)
		)
		(polygon
			(pts
				(arc
					(start 269.978378 -294.235124)
					(mid 269.317978 -294.235124)
					(end 269.978378 -294.235124)
				)
			)
		)
	)
	(zone
		(layers "In1.Cu" "In2.Cu")
		(hatch none 0.5)
		(connect_pads
			(clearance 0)
		)
		(min_thickness 0.25)
		(keepout
			(tracks not_allowed)
			(vias allowed)
			(pads allowed)
			(copperpour not_allowed)
			(footprints allowed)
		)
		(placement
			(enabled no)
			(sheetname "")
		)
		(fill yes
			(thermal_gap 0.5)
			(thermal_bridge_width 0.5)
			(island_removal_mode 0)
		)
		(polygon
			(pts
				(arc
					(start 187.390278 -261.935214)
					(mid 186.729878 -261.935214)
					(end 187.390278 -261.935214)
				)
			)
		)
	)
	(zone
		(layers "In1.Cu" "In2.Cu")
		(hatch none 0.5)
		(connect_pads
			(clearance 0)
		)
		(min_thickness 0.25)
		(keepout
			(tracks not_allowed)
			(vias allowed)
			(pads allowed)
			(copperpour not_allowed)
			(footprints allowed)
		)
		(placement
			(enabled no)
			(sheetname "")
		)
		(fill yes
			(thermal_gap 0.5)
			(thermal_bridge_width 0.5)
			(island_removal_mode 0)
		)
		(polygon
			(pts
				(arc
					(start 427.786292 -238.985044)
					(mid 427.125892 -238.985044)
					(end 427.786292 -238.985044)
				)
			)
		)
	)
	(zone
		(layers "In1.Cu" "In2.Cu")
		(hatch none 0.5)
		(connect_pads
			(clearance 0)
		)
		(min_thickness 0.25)
		(keepout
			(tracks not_allowed)
			(vias allowed)
			(pads allowed)
			(copperpour not_allowed)
			(footprints allowed)
		)
		(placement
			(enabled no)
			(sheetname "")
		)
		(fill yes
			(thermal_gap 0.5)
			(thermal_bridge_width 0.5)
			(island_removal_mode 0)
		)
		(polygon
			(pts
				(arc
					(start 183.946292 -262.785352)
					(mid 183.285892 -262.785352)
					(end 183.946292 -262.785352)
				)
			)
		)
	)
	(zone
		(layers "In1.Cu" "In2.Cu")
		(hatch none 0.5)
		(connect_pads
			(clearance 0)
		)
		(min_thickness 0.25)
		(keepout
			(tracks not_allowed)
			(vias allowed)
			(pads allowed)
			(copperpour not_allowed)
			(footprints allowed)
		)
		(placement
			(enabled no)
			(sheetname "")
		)
		(fill yes
			(thermal_gap 0.5)
			(thermal_bridge_width 0.5)
			(island_removal_mode 0)
		)
		(polygon
			(pts
				(arc
					(start 48.114204 -216.885266)
					(mid 47.453804 -216.885266)
					(end 48.114204 -216.885266)
				)
			)
		)
	)
	(zone
		(layers "In1.Cu" "In2.Cu")
		(hatch none 0.5)
		(connect_pads
			(clearance 0)
		)
		(min_thickness 0.25)
		(keepout
			(tracks not_allowed)
			(vias allowed)
			(pads allowed)
			(copperpour not_allowed)
			(footprints allowed)
		)
		(placement
			(enabled no)
			(sheetname "")
		)
		(fill yes
			(thermal_gap 0.5)
			(thermal_bridge_width 0.5)
			(island_removal_mode 0)
		)
		(polygon
			(pts
				(arc
					(start 285.066232 -225.385122)
					(mid 284.405832 -225.385122)
					(end 285.066232 -225.385122)
				)
			)
		)
	)
	(zone
		(layers "In1.Cu" "In2.Cu")
		(hatch none 0.5)
		(connect_pads
			(clearance 0)
		)
		(min_thickness 0.25)
		(keepout
			(tracks not_allowed)
			(vias allowed)
			(pads allowed)
			(copperpour not_allowed)
			(footprints allowed)
		)
		(placement
			(enabled no)
			(sheetname "")
		)
		(fill yes
			(thermal_gap 0.5)
			(thermal_bridge_width 0.5)
			(island_removal_mode 0)
		)
		(polygon
			(pts
				(arc
					(start 435.330346 -316.335156)
					(mid 434.669946 -316.335156)
					(end 435.330346 -316.335156)
				)
			)
		)
	)
	(zone
		(layers "In1.Cu" "In2.Cu")
		(hatch none 0.5)
		(connect_pads
			(clearance 0)
		)
		(min_thickness 0.25)
		(keepout
			(tracks not_allowed)
			(vias allowed)
			(pads allowed)
			(copperpour not_allowed)
			(footprints allowed)
		)
		(placement
			(enabled no)
			(sheetname "")
		)
		(fill yes
			(thermal_gap 0.5)
			(thermal_bridge_width 0.5)
			(island_removal_mode 0)
		)
		(polygon
			(pts
				(arc
					(start 424.342306 -294.235124)
					(mid 423.681906 -294.235124)
					(end 424.342306 -294.235124)
				)
			)
		)
	)
	(zone
		(layers "In1.Cu" "In2.Cu")
		(hatch none 0.5)
		(connect_pads
			(clearance 0)
		)
		(min_thickness 0.25)
		(keepout
			(tracks not_allowed)
			(vias allowed)
			(pads allowed)
			(copperpour not_allowed)
			(footprints allowed)
		)
		(placement
			(enabled no)
			(sheetname "")
		)
		(fill yes
			(thermal_gap 0.5)
			(thermal_bridge_width 0.5)
			(island_removal_mode 0)
		)
		(polygon
			(pts
				(arc
					(start 179.846224 -215.185244)
					(mid 179.185824 -215.185244)
					(end 179.846224 -215.185244)
				)
			)
		)
	)
	(zone
		(layers "In1.Cu" "In2.Cu")
		(hatch none 0.5)
		(connect_pads
			(clearance 0)
		)
		(min_thickness 0.25)
		(keepout
			(tracks not_allowed)
			(vias allowed)
			(pads allowed)
			(copperpour not_allowed)
			(footprints allowed)
		)
		(placement
			(enabled no)
			(sheetname "")
		)
		(fill yes
			(thermal_gap 0.5)
			(thermal_bridge_width 0.5)
			(island_removal_mode 0)
		)
		(polygon
			(pts
				(arc
					(start 44.670218 -233.035348)
					(mid 44.009818 -233.035348)
					(end 44.670218 -233.035348)
				)
			)
		)
	)
	(zone
		(layers "In1.Cu" "In2.Cu")
		(hatch none 0.5)
		(connect_pads
			(clearance 0)
		)
		(min_thickness 0.25)
		(keepout
			(tracks not_allowed)
			(vias allowed)
			(pads allowed)
			(copperpour not_allowed)
			(footprints allowed)
		)
		(placement
			(enabled no)
			(sheetname "")
		)
		(fill yes
			(thermal_gap 0.5)
			(thermal_bridge_width 0.5)
			(island_removal_mode 0)
		)
		(polygon
			(pts
				(arc
					(start 13.937996 -101.256846)
					(mid 13.960314 -101.202964)
					(end 14.014196 -101.180646)
				)
				(arc
					(start 14.615668 -101.180646)
					(mid 14.66955 -101.202964)
					(end 14.691868 -101.256846)
				)
				(arc
					(start 14.691868 -101.841046)
					(mid 14.66955 -101.894928)
					(end 14.615668 -101.917246)
				)
				(arc
					(start 14.014196 -101.917246)
					(mid 13.960314 -101.894928)
					(end 13.937996 -101.841046)
				)
			)
		)
	)
	(zone
		(layers "In1.Cu" "In2.Cu")
		(hatch none 0.5)
		(connect_pads
			(clearance 0)
		)
		(min_thickness 0.25)
		(keepout
			(tracks not_allowed)
			(vias allowed)
			(pads allowed)
			(copperpour not_allowed)
			(footprints allowed)
		)
		(placement
			(enabled no)
			(sheetname "")
		)
		(fill yes
			(thermal_gap 0.5)
			(thermal_bridge_width 0.5)
			(island_removal_mode 0)
		)
		(polygon
			(pts
				(arc
					(start 81.272634 -408.860244)
					(mid 81.294952 -408.914126)
					(end 81.348834 -408.936444)
				)
				(arc
					(start 81.544414 -408.936444)
					(mid 81.56629 -408.933312)
					(end 81.586324 -408.923998)
				)
				(arc
					(start 81.879948 -408.731466)
					(mid 81.921604 -408.719064)
					(end 81.96326 -408.731466)
				)
				(arc
					(start 82.258154 -408.923998)
					(mid 82.278078 -408.933234)
					(end 82.29981 -408.936444)
				)
				(arc
					(start 82.494374 -408.936444)
					(mid 82.548256 -408.914126)
					(end 82.570574 -408.860244)
				)
				(arc
					(start 82.570574 -408.174444)
					(mid 82.548256 -408.120562)
					(end 82.494374 -408.098244)
				)
				(arc
					(start 82.29981 -408.098244)
					(mid 82.278066 -408.101412)
					(end 82.258154 -408.11069)
				)
				(arc
					(start 81.96199 -408.303476)
					(mid 81.920306 -408.315698)
					(end 81.878678 -408.303222)
				)
				(arc
					(start 81.585054 -408.11069)
					(mid 81.56513 -408.101454)
					(end 81.543398 -408.098244)
				)
				(arc
					(start 81.348834 -408.098244)
					(mid 81.294952 -408.120562)
					(end 81.272634 -408.174444)
				)
			)
		)
	)
	(zone
		(layers "In1.Cu" "In2.Cu")
		(hatch none 0.5)
		(connect_pads
			(clearance 0)
		)
		(min_thickness 0.25)
		(keepout
			(tracks not_allowed)
			(vias allowed)
			(pads allowed)
			(copperpour not_allowed)
			(footprints allowed)
		)
		(placement
			(enabled no)
			(sheetname "")
		)
		(fill yes
			(thermal_gap 0.5)
			(thermal_bridge_width 0.5)
			(island_removal_mode 0)
		)
		(polygon
			(pts
				(arc
					(start 398.141444 -11.91768)
					(mid 398.119126 -11.971562)
					(end 398.065244 -11.99388)
				)
				(arc
					(start 397.02867 -11.99388)
					(mid 396.974788 -11.971562)
					(end 396.95247 -11.91768)
				)
				(arc
					(start 396.95247 -10.51814)
					(mid 396.974788 -10.464258)
					(end 397.02867 -10.44194)
				)
				(arc
					(start 398.065244 -10.44194)
					(mid 398.119126 -10.464258)
					(end 398.141444 -10.51814)
				)
			)
		)
	)
	(zone
		(layers "In1.Cu" "In2.Cu")
		(hatch none 0.5)
		(connect_pads
			(clearance 0)
		)
		(min_thickness 0.25)
		(keepout
			(tracks not_allowed)
			(vias allowed)
			(pads allowed)
			(copperpour not_allowed)
			(footprints allowed)
		)
		(placement
			(enabled no)
			(sheetname "")
		)
		(fill yes
			(thermal_gap 0.5)
			(thermal_bridge_width 0.5)
			(island_removal_mode 0)
		)
		(polygon
			(pts
				(arc
					(start 37.126164 -306.135278)
					(mid 36.465764 -306.135278)
					(end 37.126164 -306.135278)
				)
			)
		)
	)
	(zone
		(layers "In1.Cu" "In2.Cu")
		(hatch none 0.5)
		(connect_pads
			(clearance 0)
		)
		(min_thickness 0.25)
		(keepout
			(tracks not_allowed)
			(vias allowed)
			(pads allowed)
			(copperpour not_allowed)
			(footprints allowed)
		)
		(placement
			(enabled no)
			(sheetname "")
		)
		(fill yes
			(thermal_gap 0.5)
			(thermal_bridge_width 0.5)
			(island_removal_mode 0)
		)
		(polygon
			(pts
				(arc
					(start 172.30217 -263.635236)
					(mid 171.64177 -263.635236)
					(end 172.30217 -263.635236)
				)
			)
		)
	)
	(zone
		(layers "In1.Cu" "In2.Cu")
		(hatch none 0.5)
		(connect_pads
			(clearance 0)
		)
		(min_thickness 0.25)
		(keepout
			(tracks not_allowed)
			(vias allowed)
			(pads allowed)
			(copperpour not_allowed)
			(footprints allowed)
		)
		(placement
			(enabled no)
			(sheetname "")
		)
		(fill yes
			(thermal_gap 0.5)
			(thermal_bridge_width 0.5)
			(island_removal_mode 0)
		)
		(polygon
			(pts
				(arc
					(start 442.8744 -204.134974)
					(mid 442.214 -204.134974)
					(end 442.8744 -204.134974)
				)
			)
		)
	)
	(zone
		(layers "In1.Cu" "In2.Cu")
		(hatch none 0.5)
		(connect_pads
			(clearance 0)
		)
		(min_thickness 0.25)
		(keepout
			(tracks not_allowed)
			(vias allowed)
			(pads allowed)
			(copperpour not_allowed)
			(footprints allowed)
		)
		(placement
			(enabled no)
			(sheetname "")
		)
		(fill yes
			(thermal_gap 0.5)
			(thermal_bridge_width 0.5)
			(island_removal_mode 0)
		)
		(polygon
			(pts
				(arc
					(start 450.4182 -207.535018)
					(mid 449.7578 -207.535018)
					(end 450.4182 -207.535018)
				)
			)
		)
	)
	(zone
		(layers "In1.Cu" "In2.Cu")
		(hatch none 0.5)
		(connect_pads
			(clearance 0)
		)
		(min_thickness 0.25)
		(keepout
			(tracks not_allowed)
			(vias allowed)
			(pads allowed)
			(copperpour not_allowed)
			(footprints allowed)
		)
		(placement
			(enabled no)
			(sheetname "")
		)
		(fill yes
			(thermal_gap 0.5)
			(thermal_bridge_width 0.5)
			(island_removal_mode 0)
		)
		(polygon
			(pts
				(arc
					(start 431.88636 -312.935112)
					(mid 431.22596 -312.935112)
					(end 431.88636 -312.935112)
				)
			)
		)
	)
	(zone
		(layers "In1.Cu" "In2.Cu")
		(hatch none 0.5)
		(connect_pads
			(clearance 0)
		)
		(min_thickness 0.25)
		(keepout
			(tracks not_allowed)
			(vias allowed)
			(pads allowed)
			(copperpour not_allowed)
			(footprints allowed)
		)
		(placement
			(enabled no)
			(sheetname "")
		)
		(fill yes
			(thermal_gap 0.5)
			(thermal_bridge_width 0.5)
			(island_removal_mode 0)
		)
		(polygon
			(pts
				(arc
					(start 300.15434 -266.185142)
					(mid 299.49394 -266.185142)
					(end 300.15434 -266.185142)
				)
			)
		)
	)
	(zone
		(layers "In1.Cu" "In2.Cu")
		(hatch none 0.5)
		(connect_pads
			(clearance 0)
		)
		(min_thickness 0.25)
		(keepout
			(tracks not_allowed)
			(vias allowed)
			(pads allowed)
			(copperpour not_allowed)
			(footprints allowed)
		)
		(placement
			(enabled no)
			(sheetname "")
		)
		(fill yes
			(thermal_gap 0.5)
			(thermal_bridge_width 0.5)
			(island_removal_mode 0)
		)
		(polygon
			(pts
				(arc
					(start 176.402238 -238.985298)
					(mid 175.741838 -238.985298)
					(end 176.402238 -238.985298)
				)
			)
		)
	)
	(zone
		(layers "In1.Cu" "In2.Cu")
		(hatch none 0.5)
		(connect_pads
			(clearance 0)
		)
		(min_thickness 0.25)
		(keepout
			(tracks not_allowed)
			(vias allowed)
			(pads allowed)
			(copperpour not_allowed)
			(footprints allowed)
		)
		(placement
			(enabled no)
			(sheetname "")
		)
		(fill yes
			(thermal_gap 0.5)
			(thermal_bridge_width 0.5)
			(island_removal_mode 0)
		)
		(polygon
			(pts
				(arc
					(start 199.0344 -284.885384)
					(mid 198.374 -284.885384)
					(end 199.0344 -284.885384)
				)
			)
		)
	)
	(zone
		(layers "In1.Cu" "In2.Cu")
		(hatch none 0.5)
		(connect_pads
			(clearance 0)
		)
		(min_thickness 0.25)
		(keepout
			(tracks not_allowed)
			(vias allowed)
			(pads allowed)
			(copperpour not_allowed)
			(footprints allowed)
		)
		(placement
			(enabled no)
			(sheetname "")
		)
		(fill yes
			(thermal_gap 0.5)
			(thermal_bridge_width 0.5)
			(island_removal_mode 0)
		)
		(polygon
			(pts
				(arc
					(start 431.88636 -245.785132)
					(mid 431.22596 -245.785132)
					(end 431.88636 -245.785132)
				)
			)
		)
	)
	(zone
		(layers "In1.Cu" "In2.Cu")
		(hatch none 0.5)
		(connect_pads
			(clearance 0)
		)
		(min_thickness 0.25)
		(keepout
			(tracks not_allowed)
			(vias allowed)
			(pads allowed)
			(copperpour not_allowed)
			(footprints allowed)
		)
		(placement
			(enabled no)
			(sheetname "")
		)
		(fill yes
			(thermal_gap 0.5)
			(thermal_bridge_width 0.5)
			(island_removal_mode 0)
		)
		(polygon
			(pts
				(arc
					(start 202.478132 -308.685438)
					(mid 201.817732 -308.685438)
					(end 202.478132 -308.685438)
				)
			)
		)
	)
	(zone
		(layers "In1.Cu" "In2.Cu")
		(hatch none 0.5)
		(connect_pads
			(clearance 0)
		)
		(min_thickness 0.25)
		(keepout
			(tracks not_allowed)
			(vias allowed)
			(pads allowed)
			(copperpour not_allowed)
			(footprints allowed)
		)
		(placement
			(enabled no)
			(sheetname "")
		)
		(fill yes
			(thermal_gap 0.5)
			(thermal_bridge_width 0.5)
			(island_removal_mode 0)
		)
		(polygon
			(pts
				(arc
					(start 179.846224 -251.735336)
					(mid 179.185824 -251.735336)
					(end 179.846224 -251.735336)
				)
			)
		)
	)
	(zone
		(layers "In1.Cu" "In2.Cu")
		(hatch none 0.5)
		(connect_pads
			(clearance 0)
		)
		(min_thickness 0.25)
		(keepout
			(tracks not_allowed)
			(vias allowed)
			(pads allowed)
			(copperpour not_allowed)
			(footprints allowed)
		)
		(placement
			(enabled no)
			(sheetname "")
		)
		(fill yes
			(thermal_gap 0.5)
			(thermal_bridge_width 0.5)
			(island_removal_mode 0)
		)
		(polygon
			(pts
				(arc
					(start 420.242238 -299.33519)
					(mid 419.581838 -299.33519)
					(end 420.242238 -299.33519)
				)
			)
		)
	)
	(zone
		(layers "In1.Cu" "In2.Cu")
		(hatch none 0.5)
		(connect_pads
			(clearance 0)
		)
		(min_thickness 0.25)
		(keepout
			(tracks not_allowed)
			(vias allowed)
			(pads allowed)
			(copperpour not_allowed)
			(footprints allowed)
		)
		(placement
			(enabled no)
			(sheetname "")
		)
		(fill yes
			(thermal_gap 0.5)
			(thermal_bridge_width 0.5)
			(island_removal_mode 0)
		)
		(polygon
			(pts
				(arc
					(start 199.0344 -240.68532)
					(mid 198.374 -240.68532)
					(end 199.0344 -240.68532)
				)
			)
		)
	)
	(zone
		(layers "In1.Cu" "In2.Cu")
		(hatch none 0.5)
		(connect_pads
			(clearance 0)
		)
		(min_thickness 0.25)
		(keepout
			(tracks not_allowed)
			(vias allowed)
			(pads allowed)
			(copperpour not_allowed)
			(footprints allowed)
		)
		(placement
			(enabled no)
			(sheetname "")
		)
		(fill yes
			(thermal_gap 0.5)
			(thermal_bridge_width 0.5)
			(island_removal_mode 0)
		)
		(polygon
			(pts
				(arc
					(start 48.114204 -204.135228)
					(mid 47.453804 -204.135228)
					(end 48.114204 -204.135228)
				)
			)
		)
	)
	(zone
		(layers "In1.Cu" "In2.Cu")
		(hatch none 0.5)
		(connect_pads
			(clearance 0)
		)
		(min_thickness 0.25)
		(keepout
			(tracks not_allowed)
			(vias allowed)
			(pads allowed)
			(copperpour not_allowed)
			(footprints allowed)
		)
		(placement
			(enabled no)
			(sheetname "")
		)
		(fill yes
			(thermal_gap 0.5)
			(thermal_bridge_width 0.5)
			(island_removal_mode 0)
		)
		(polygon
			(pts
				(arc
					(start 179.846224 -306.985416)
					(mid 179.185824 -306.985416)
					(end 179.846224 -306.985416)
				)
			)
		)
	)
	(zone
		(layers "In1.Cu" "In2.Cu")
		(hatch none 0.5)
		(connect_pads
			(clearance 0)
		)
		(min_thickness 0.25)
		(keepout
			(tracks not_allowed)
			(vias allowed)
			(pads allowed)
			(copperpour not_allowed)
			(footprints allowed)
		)
		(placement
			(enabled no)
			(sheetname "")
		)
		(fill yes
			(thermal_gap 0.5)
			(thermal_bridge_width 0.5)
			(island_removal_mode 0)
		)
		(polygon
			(pts
				(arc
					(start 52.214272 -201.585322)
					(mid 51.553872 -201.585322)
					(end 52.214272 -201.585322)
				)
			)
		)
	)
	(zone
		(layers "In1.Cu" "In2.Cu")
		(hatch none 0.5)
		(connect_pads
			(clearance 0)
		)
		(min_thickness 0.25)
		(keepout
			(tracks not_allowed)
			(vias allowed)
			(pads allowed)
			(copperpour not_allowed)
			(footprints allowed)
		)
		(placement
			(enabled no)
			(sheetname "")
		)
		(fill yes
			(thermal_gap 0.5)
			(thermal_bridge_width 0.5)
			(island_removal_mode 0)
		)
		(polygon
			(pts
				(arc
					(start 17.938242 -224.535238)
					(mid 17.277842 -224.535238)
					(end 17.938242 -224.535238)
				)
			)
		)
	)
	(zone
		(layers "In1.Cu" "In2.Cu")
		(hatch none 0.5)
		(connect_pads
			(clearance 0)
		)
		(min_thickness 0.25)
		(keepout
			(tracks not_allowed)
			(vias allowed)
			(pads allowed)
			(copperpour not_allowed)
			(footprints allowed)
		)
		(placement
			(enabled no)
			(sheetname "")
		)
		(fill yes
			(thermal_gap 0.5)
			(thermal_bridge_width 0.5)
			(island_removal_mode 0)
		)
		(polygon
			(pts
				(arc
					(start 29.582364 -210.085432)
					(mid 28.921964 -210.085432)
					(end 29.582364 -210.085432)
				)
			)
		)
	)
	(zone
		(layers "In1.Cu" "In2.Cu")
		(hatch none 0.5)
		(connect_pads
			(clearance 0)
		)
		(min_thickness 0.25)
		(keepout
			(tracks not_allowed)
			(vias allowed)
			(pads allowed)
			(copperpour not_allowed)
			(footprints allowed)
		)
		(placement
			(enabled no)
			(sheetname "")
		)
		(fill yes
			(thermal_gap 0.5)
			(thermal_bridge_width 0.5)
			(island_removal_mode 0)
		)
		(polygon
			(pts
				(arc
					(start 29.582364 -240.68532)
					(mid 28.921964 -240.68532)
					(end 29.582364 -240.68532)
				)
			)
		)
	)
	(zone
		(layers "In1.Cu" "In2.Cu")
		(hatch none 0.5)
		(connect_pads
			(clearance 0)
		)
		(min_thickness 0.25)
		(keepout
			(tracks not_allowed)
			(vias allowed)
			(pads allowed)
			(copperpour not_allowed)
			(footprints allowed)
		)
		(placement
			(enabled no)
			(sheetname "")
		)
		(fill yes
			(thermal_gap 0.5)
			(thermal_bridge_width 0.5)
			(island_removal_mode 0)
		)
		(polygon
			(pts
				(arc
					(start 454.518268 -303.585118)
					(mid 453.857868 -303.585118)
					(end 454.518268 -303.585118)
				)
			)
		)
	)
	(zone
		(layers "In1.Cu" "In2.Cu")
		(hatch none 0.5)
		(connect_pads
			(clearance 0)
		)
		(min_thickness 0.25)
		(keepout
			(tracks not_allowed)
			(vias allowed)
			(pads allowed)
			(copperpour not_allowed)
			(footprints allowed)
		)
		(placement
			(enabled no)
			(sheetname "")
		)
		(fill yes
			(thermal_gap 0.5)
			(thermal_bridge_width 0.5)
			(island_removal_mode 0)
		)
		(polygon
			(pts
				(arc
					(start 40.57015 -254.285242)
					(mid 39.90975 -254.285242)
					(end 40.57015 -254.285242)
				)
			)
		)
	)
	(zone
		(layers "In1.Cu" "In2.Cu")
		(hatch none 0.5)
		(connect_pads
			(clearance 0)
		)
		(min_thickness 0.25)
		(keepout
			(tracks not_allowed)
			(vias allowed)
			(pads allowed)
			(copperpour not_allowed)
			(footprints allowed)
		)
		(placement
			(enabled no)
			(sheetname "")
		)
		(fill yes
			(thermal_gap 0.5)
			(thermal_bridge_width 0.5)
			(island_removal_mode 0)
		)
		(polygon
			(pts
				(arc
					(start 191.490346 -250.885198)
					(mid 190.829946 -250.885198)
					(end 191.490346 -250.885198)
				)
			)
		)
	)
	(zone
		(layers "In1.Cu" "In2.Cu")
		(hatch none 0.5)
		(connect_pads
			(clearance 0)
		)
		(min_thickness 0.25)
		(keepout
			(tracks not_allowed)
			(vias allowed)
			(pads allowed)
			(copperpour not_allowed)
			(footprints allowed)
		)
		(placement
			(enabled no)
			(sheetname "")
		)
		(fill yes
			(thermal_gap 0.5)
			(thermal_bridge_width 0.5)
			(island_removal_mode 0)
		)
		(polygon
			(pts
				(arc
					(start 40.57015 -304.435256)
					(mid 39.90975 -304.435256)
					(end 40.57015 -304.435256)
				)
			)
		)
	)
	(zone
		(layers "In1.Cu" "In2.Cu")
		(hatch none 0.5)
		(connect_pads
			(clearance 0)
		)
		(min_thickness 0.25)
		(keepout
			(tracks not_allowed)
			(vias allowed)
			(pads allowed)
			(copperpour not_allowed)
			(footprints allowed)
		)
		(placement
			(enabled no)
			(sheetname "")
		)
		(fill yes
			(thermal_gap 0.5)
			(thermal_bridge_width 0.5)
			(island_removal_mode 0)
		)
		(polygon
			(pts
				(arc
					(start 273.422364 -288.285174)
					(mid 272.761964 -288.285174)
					(end 273.422364 -288.285174)
				)
			)
		)
	)
	(zone
		(layers "In1.Cu" "In2.Cu")
		(hatch none 0.5)
		(connect_pads
			(clearance 0)
		)
		(min_thickness 0.25)
		(keepout
			(tracks not_allowed)
			(vias allowed)
			(pads allowed)
			(copperpour not_allowed)
			(footprints allowed)
		)
		(placement
			(enabled no)
			(sheetname "")
		)
		(fill yes
			(thermal_gap 0.5)
			(thermal_bridge_width 0.5)
			(island_removal_mode 0)
		)
		(polygon
			(pts
				(arc
					(start 202.478132 -302.735234)
					(mid 201.817732 -302.735234)
					(end 202.478132 -302.735234)
				)
			)
		)
	)
	(zone
		(layers "In1.Cu" "In2.Cu")
		(hatch none 0.5)
		(connect_pads
			(clearance 0)
		)
		(min_thickness 0.25)
		(keepout
			(tracks not_allowed)
			(vias allowed)
			(pads allowed)
			(copperpour not_allowed)
			(footprints allowed)
		)
		(placement
			(enabled no)
			(sheetname "")
		)
		(fill yes
			(thermal_gap 0.5)
			(thermal_bridge_width 0.5)
			(island_removal_mode 0)
		)
		(polygon
			(pts
				(arc
					(start 285.066232 -313.784996)
					(mid 284.405832 -313.784996)
					(end 285.066232 -313.784996)
				)
			)
		)
	)
	(zone
		(layers "In1.Cu" "In2.Cu")
		(hatch none 0.5)
		(connect_pads
			(clearance 0)
		)
		(min_thickness 0.25)
		(keepout
			(tracks not_allowed)
			(vias allowed)
			(pads allowed)
			(copperpour not_allowed)
			(footprints allowed)
		)
		(placement
			(enabled no)
			(sheetname "")
		)
		(fill yes
			(thermal_gap 0.5)
			(thermal_bridge_width 0.5)
			(island_removal_mode 0)
		)
		(polygon
			(pts
				(arc
					(start 33.026096 -282.335224)
					(mid 32.365696 -282.335224)
					(end 33.026096 -282.335224)
				)
			)
		)
	)
	(zone
		(layers "In1.Cu" "In2.Cu")
		(hatch none 0.5)
		(connect_pads
			(clearance 0)
		)
		(min_thickness 0.25)
		(keepout
			(tracks not_allowed)
			(vias allowed)
			(pads allowed)
			(copperpour not_allowed)
			(footprints allowed)
		)
		(placement
			(enabled no)
			(sheetname "")
		)
		(fill yes
			(thermal_gap 0.5)
			(thermal_bridge_width 0.5)
			(island_removal_mode 0)
		)
		(polygon
			(pts
				(arc
					(start 296.054272 -230.485188)
					(mid 295.393872 -230.485188)
					(end 296.054272 -230.485188)
				)
			)
		)
	)
	(zone
		(layers "In1.Cu" "In2.Cu")
		(hatch none 0.5)
		(connect_pads
			(clearance 0)
		)
		(min_thickness 0.25)
		(keepout
			(tracks not_allowed)
			(vias allowed)
			(pads allowed)
			(copperpour not_allowed)
			(footprints allowed)
		)
		(placement
			(enabled no)
			(sheetname "")
		)
		(fill yes
			(thermal_gap 0.5)
			(thermal_bridge_width 0.5)
			(island_removal_mode 0)
		)
		(polygon
			(pts
				(arc
					(start 431.88636 -306.135024)
					(mid 431.22596 -306.135024)
					(end 431.88636 -306.135024)
				)
			)
		)
	)
	(zone
		(layers "In1.Cu" "In2.Cu")
		(hatch none 0.5)
		(connect_pads
			(clearance 0)
		)
		(min_thickness 0.25)
		(keepout
			(tracks not_allowed)
			(vias allowed)
			(pads allowed)
			(copperpour not_allowed)
			(footprints allowed)
		)
		(placement
			(enabled no)
			(sheetname "")
		)
		(fill yes
			(thermal_gap 0.5)
			(thermal_bridge_width 0.5)
			(island_removal_mode 0)
		)
		(polygon
			(pts
				(arc
					(start 37.126164 -249.18543)
					(mid 36.465764 -249.18543)
					(end 37.126164 -249.18543)
				)
			)
		)
	)
	(zone
		(layers "In1.Cu" "In2.Cu")
		(hatch none 0.5)
		(connect_pads
			(clearance 0)
		)
		(min_thickness 0.25)
		(keepout
			(tracks not_allowed)
			(vias allowed)
			(pads allowed)
			(copperpour not_allowed)
			(footprints allowed)
		)
		(placement
			(enabled no)
			(sheetname "")
		)
		(fill yes
			(thermal_gap 0.5)
			(thermal_bridge_width 0.5)
			(island_removal_mode 0)
		)
		(polygon
			(pts
				(arc
					(start 269.978378 -267.885164)
					(mid 269.317978 -267.885164)
					(end 269.978378 -267.885164)
				)
			)
		)
	)
	(zone
		(layers "In1.Cu" "In2.Cu")
		(hatch none 0.5)
		(connect_pads
			(clearance 0)
		)
		(min_thickness 0.25)
		(keepout
			(tracks not_allowed)
			(vias allowed)
			(pads allowed)
			(copperpour not_allowed)
			(footprints allowed)
		)
		(placement
			(enabled no)
			(sheetname "")
		)
		(fill yes
			(thermal_gap 0.5)
			(thermal_bridge_width 0.5)
			(island_removal_mode 0)
		)
		(polygon
			(pts
				(arc
					(start 442.8744 -226.235006)
					(mid 442.214 -226.235006)
					(end 442.8744 -226.235006)
				)
			)
		)
	)
	(zone
		(layers "In1.Cu" "In2.Cu")
		(hatch none 0.5)
		(connect_pads
			(clearance 0)
		)
		(min_thickness 0.25)
		(keepout
			(tracks not_allowed)
			(vias allowed)
			(pads allowed)
			(copperpour not_allowed)
			(footprints allowed)
		)
		(placement
			(enabled no)
			(sheetname "")
		)
		(fill yes
			(thermal_gap 0.5)
			(thermal_bridge_width 0.5)
			(island_removal_mode 0)
		)
		(polygon
			(pts
				(arc
					(start 300.15434 -273.835114)
					(mid 299.49394 -273.835114)
					(end 300.15434 -273.835114)
				)
			)
		)
	)
	(zone
		(layers "In1.Cu" "In2.Cu")
		(hatch none 0.5)
		(connect_pads
			(clearance 0)
		)
		(min_thickness 0.25)
		(keepout
			(tracks not_allowed)
			(vias allowed)
			(pads allowed)
			(copperpour not_allowed)
			(footprints allowed)
		)
		(placement
			(enabled no)
			(sheetname "")
		)
		(fill yes
			(thermal_gap 0.5)
			(thermal_bridge_width 0.5)
			(island_removal_mode 0)
		)
		(polygon
			(pts
				(arc
					(start 155.323794 -375.906284)
					(mid 155.343718 -375.91552)
					(end 155.36545 -375.91873)
				)
				(arc
					(start 155.560014 -375.91873)
					(mid 155.613896 -375.896412)
					(end 155.636214 -375.84253)
				)
				(arc
					(start 155.636214 -375.15673)
					(mid 155.613896 -375.102848)
					(end 155.560014 -375.08053)
				)
				(arc
					(start 155.36545 -375.08053)
					(mid 155.343706 -375.083698)
					(end 155.323794 -375.092976)
				)
				(arc
					(start 155.02763 -375.285762)
					(mid 154.985946 -375.297984)
					(end 154.944318 -375.285508)
				)
				(arc
					(start 154.650694 -375.092976)
					(mid 154.63077 -375.08374)
					(end 154.609038 -375.08053)
				)
				(arc
					(start 154.414474 -375.08053)
					(mid 154.360592 -375.102848)
					(end 154.338274 -375.15673)
				)
				(arc
					(start 154.338274 -375.84253)
					(mid 154.360592 -375.896412)
					(end 154.414474 -375.91873)
				)
				(arc
					(start 154.610308 -375.91873)
					(mid 154.632052 -375.915562)
					(end 154.651964 -375.906284)
				)
				(arc
					(start 154.945588 -375.713752)
					(mid 154.987244 -375.70135)
					(end 155.0289 -375.713752)
				)
			)
		)
	)
	(zone
		(layers "In1.Cu" "In2.Cu")
		(hatch none 0.5)
		(connect_pads
			(clearance 0)
		)
		(min_thickness 0.25)
		(keepout
			(tracks not_allowed)
			(vias allowed)
			(pads allowed)
			(copperpour not_allowed)
			(footprints allowed)
		)
		(placement
			(enabled no)
			(sheetname "")
		)
		(fill yes
			(thermal_gap 0.5)
			(thermal_bridge_width 0.5)
			(island_removal_mode 0)
		)
		(polygon
			(pts
				(arc
					(start 44.670218 -264.485374)
					(mid 44.009818 -264.485374)
					(end 44.670218 -264.485374)
				)
			)
		)
	)
	(zone
		(layers "In1.Cu" "In2.Cu")
		(hatch none 0.5)
		(connect_pads
			(clearance 0)
		)
		(min_thickness 0.25)
		(keepout
			(tracks not_allowed)
			(vias allowed)
			(pads allowed)
			(copperpour not_allowed)
			(footprints allowed)
		)
		(placement
			(enabled no)
			(sheetname "")
		)
		(fill yes
			(thermal_gap 0.5)
			(thermal_bridge_width 0.5)
			(island_removal_mode 0)
		)
		(polygon
			(pts
				(arc
					(start 172.30217 -202.435206)
					(mid 171.64177 -202.435206)
					(end 172.30217 -202.435206)
				)
			)
		)
	)
	(zone
		(layers "In1.Cu" "In2.Cu")
		(hatch none 0.5)
		(connect_pads
			(clearance 0)
		)
		(min_thickness 0.25)
		(keepout
			(tracks not_allowed)
			(vias allowed)
			(pads allowed)
			(copperpour not_allowed)
			(footprints allowed)
		)
		(placement
			(enabled no)
			(sheetname "")
		)
		(fill yes
			(thermal_gap 0.5)
			(thermal_bridge_width 0.5)
			(island_removal_mode 0)
		)
		(polygon
			(pts
				(arc
					(start 392.434318 -388.647178)
					(mid 392.425082 -388.667102)
					(end 392.421872 -388.688834)
				)
				(arc
					(start 392.421872 -388.883398)
					(mid 392.44419 -388.93728)
					(end 392.498072 -388.959598)
				)
				(arc
					(start 393.183872 -388.959598)
					(mid 393.237754 -388.93728)
					(end 393.260072 -388.883398)
				)
				(arc
					(start 393.260072 -388.688834)
					(mid 393.256904 -388.66709)
					(end 393.247626 -388.647178)
				)
				(arc
					(start 393.05484 -388.351014)
					(mid 393.042618 -388.30933)
					(end 393.055094 -388.267702)
				)
				(arc
					(start 393.247626 -387.974078)
					(mid 393.256862 -387.954154)
					(end 393.260072 -387.932422)
				)
				(arc
					(start 393.260072 -387.737858)
					(mid 393.237754 -387.683976)
					(end 393.183872 -387.661658)
				)
				(arc
					(start 392.498072 -387.661658)
					(mid 392.44419 -387.683976)
					(end 392.421872 -387.737858)
				)
				(arc
					(start 392.421872 -387.933692)
					(mid 392.42504 -387.955436)
					(end 392.434318 -387.975348)
				)
				(arc
					(start 392.62685 -388.268972)
					(mid 392.639252 -388.310628)
					(end 392.62685 -388.352284)
				)
			)
		)
	)
	(zone
		(layers "In1.Cu" "In2.Cu")
		(hatch none 0.5)
		(connect_pads
			(clearance 0)
		)
		(min_thickness 0.25)
		(keepout
			(tracks not_allowed)
			(vias allowed)
			(pads allowed)
			(copperpour not_allowed)
			(footprints allowed)
		)
		(placement
			(enabled no)
			(sheetname "")
		)
		(fill yes
			(thermal_gap 0.5)
			(thermal_bridge_width 0.5)
			(island_removal_mode 0)
		)
		(polygon
			(pts
				(arc
					(start 420.242238 -222.834962)
					(mid 419.581838 -222.834962)
					(end 420.242238 -222.834962)
				)
			)
		)
	)
	(zone
		(layers "In1.Cu" "In2.Cu")
		(hatch none 0.5)
		(connect_pads
			(clearance 0)
		)
		(min_thickness 0.25)
		(keepout
			(tracks not_allowed)
			(vias allowed)
			(pads allowed)
			(copperpour not_allowed)
			(footprints allowed)
		)
		(placement
			(enabled no)
			(sheetname "")
		)
		(fill yes
			(thermal_gap 0.5)
			(thermal_bridge_width 0.5)
			(island_removal_mode 0)
		)
		(polygon
			(pts
				(arc
					(start 48.114204 -277.235412)
					(mid 47.453804 -277.235412)
					(end 48.114204 -277.235412)
				)
			)
		)
	)
	(zone
		(layers "In1.Cu" "In2.Cu")
		(hatch none 0.5)
		(connect_pads
			(clearance 0)
		)
		(min_thickness 0.25)
		(keepout
			(tracks not_allowed)
			(vias allowed)
			(pads allowed)
			(copperpour not_allowed)
			(footprints allowed)
		)
		(placement
			(enabled no)
			(sheetname "")
		)
		(fill yes
			(thermal_gap 0.5)
			(thermal_bridge_width 0.5)
			(island_removal_mode 0)
		)
		(polygon
			(pts
				(arc
					(start 292.610286 -264.48512)
					(mid 291.949886 -264.48512)
					(end 292.610286 -264.48512)
				)
			)
		)
	)
	(zone
		(layers "In1.Cu" "In2.Cu")
		(hatch none 0.5)
		(connect_pads
			(clearance 0)
		)
		(min_thickness 0.25)
		(keepout
			(tracks not_allowed)
			(vias allowed)
			(pads allowed)
			(copperpour not_allowed)
			(footprints allowed)
		)
		(placement
			(enabled no)
			(sheetname "")
		)
		(fill yes
			(thermal_gap 0.5)
			(thermal_bridge_width 0.5)
			(island_removal_mode 0)
		)
		(polygon
			(pts
				(arc
					(start 25.482296 -289.98545)
					(mid 24.821896 -289.98545)
					(end 25.482296 -289.98545)
				)
			)
		)
	)
	(zone
		(layers "In1.Cu" "In2.Cu")
		(hatch none 0.5)
		(connect_pads
			(clearance 0)
		)
		(min_thickness 0.25)
		(keepout
			(tracks not_allowed)
			(vias allowed)
			(pads allowed)
			(copperpour not_allowed)
			(footprints allowed)
		)
		(placement
			(enabled no)
			(sheetname "")
		)
		(fill yes
			(thermal_gap 0.5)
			(thermal_bridge_width 0.5)
			(island_removal_mode 0)
		)
		(polygon
			(pts
				(arc
					(start 103.621078 -292.411404)
					(mid 103.316278 -292.716204)
					(end 103.621078 -293.021004)
				)
				(arc
					(start 104.561132 -293.021004)
					(mid 104.865932 -292.716204)
					(end 104.561132 -292.411404)
				)
			)
		)
	)
	(zone
		(layers "In1.Cu" "In2.Cu")
		(hatch none 0.5)
		(connect_pads
			(clearance 0)
		)
		(min_thickness 0.25)
		(keepout
			(tracks not_allowed)
			(vias allowed)
			(pads allowed)
			(copperpour not_allowed)
			(footprints allowed)
		)
		(placement
			(enabled no)
			(sheetname "")
		)
		(fill yes
			(thermal_gap 0.5)
			(thermal_bridge_width 0.5)
			(island_removal_mode 0)
		)
		(polygon
			(pts
				(arc
					(start 17.938242 -213.485222)
					(mid 17.277842 -213.485222)
					(end 17.938242 -213.485222)
				)
			)
		)
	)
	(zone
		(layers "In1.Cu" "In2.Cu")
		(hatch none 0.5)
		(connect_pads
			(clearance 0)
		)
		(min_thickness 0.25)
		(keepout
			(tracks not_allowed)
			(vias allowed)
			(pads allowed)
			(copperpour not_allowed)
			(footprints allowed)
		)
		(placement
			(enabled no)
			(sheetname "")
		)
		(fill yes
			(thermal_gap 0.5)
			(thermal_bridge_width 0.5)
			(island_removal_mode 0)
		)
		(polygon
			(pts
				(arc
					(start 288.510218 -305.28514)
					(mid 287.849818 -305.28514)
					(end 288.510218 -305.28514)
				)
			)
		)
	)
	(zone
		(layers "In1.Cu" "In2.Cu")
		(hatch none 0.5)
		(connect_pads
			(clearance 0)
		)
		(min_thickness 0.25)
		(keepout
			(tracks not_allowed)
			(vias allowed)
			(pads allowed)
			(copperpour not_allowed)
			(footprints allowed)
		)
		(placement
			(enabled no)
			(sheetname "")
		)
		(fill yes
			(thermal_gap 0.5)
			(thermal_bridge_width 0.5)
			(island_removal_mode 0)
		)
		(polygon
			(pts
				(arc
					(start 25.482296 -295.9354)
					(mid 24.821896 -295.9354)
					(end 25.482296 -295.9354)
				)
			)
		)
	)
	(zone
		(layers "In1.Cu" "In2.Cu")
		(hatch none 0.5)
		(connect_pads
			(clearance 0)
		)
		(min_thickness 0.25)
		(keepout
			(tracks not_allowed)
			(vias allowed)
			(pads allowed)
			(copperpour not_allowed)
			(footprints allowed)
		)
		(placement
			(enabled no)
			(sheetname "")
		)
		(fill yes
			(thermal_gap 0.5)
			(thermal_bridge_width 0.5)
			(island_removal_mode 0)
		)
		(polygon
			(pts
				(arc
					(start 37.126164 -233.035348)
					(mid 36.465764 -233.035348)
					(end 37.126164 -233.035348)
				)
			)
		)
	)
	(zone
		(layers "In1.Cu" "In2.Cu")
		(hatch none 0.5)
		(connect_pads
			(clearance 0)
		)
		(min_thickness 0.25)
		(keepout
			(tracks not_allowed)
			(vias allowed)
			(pads allowed)
			(copperpour not_allowed)
			(footprints allowed)
		)
		(placement
			(enabled no)
			(sheetname "")
		)
		(fill yes
			(thermal_gap 0.5)
			(thermal_bridge_width 0.5)
			(island_removal_mode 0)
		)
		(polygon
			(pts
				(arc
					(start 435.330346 -277.235158)
					(mid 434.669946 -277.235158)
					(end 435.330346 -277.235158)
				)
			)
		)
	)
	(zone
		(layers "In1.Cu" "In2.Cu")
		(hatch none 0.5)
		(connect_pads
			(clearance 0)
		)
		(min_thickness 0.25)
		(keepout
			(tracks not_allowed)
			(vias allowed)
			(pads allowed)
			(copperpour not_allowed)
			(footprints allowed)
		)
		(placement
			(enabled no)
			(sheetname "")
		)
		(fill yes
			(thermal_gap 0.5)
			(thermal_bridge_width 0.5)
			(island_removal_mode 0)
		)
		(polygon
			(pts
				(arc
					(start 40.57015 -224.535238)
					(mid 39.90975 -224.535238)
					(end 40.57015 -224.535238)
				)
			)
		)
	)
	(zone
		(layers "In1.Cu" "In2.Cu" "In3.Cu")
		(hatch none 0.5)
		(connect_pads
			(clearance 0)
		)
		(min_thickness 0.25)
		(keepout
			(tracks not_allowed)
			(vias allowed)
			(pads allowed)
			(copperpour not_allowed)
			(footprints allowed)
		)
		(placement
			(enabled no)
			(sheetname "")
		)
		(fill yes
			(thermal_gap 0.5)
			(thermal_bridge_width 0.5)
			(island_removal_mode 0)
		)
		(polygon
			(pts
				(arc
					(start 100.500942 -232.839514)
					(mid 100.196142 -233.144314)
					(end 100.500942 -233.449114)
				)
				(arc
					(start 101.440996 -233.449114)
					(mid 101.745796 -233.144314)
					(end 101.440996 -232.839514)
				)
			)
		)
	)
	(zone
		(layers "In1.Cu" "In2.Cu" "In3.Cu")
		(hatch none 0.5)
		(connect_pads
			(clearance 0)
		)
		(min_thickness 0.25)
		(keepout
			(tracks not_allowed)
			(vias allowed)
			(pads allowed)
			(copperpour not_allowed)
			(footprints allowed)
		)
		(placement
			(enabled no)
			(sheetname "")
		)
		(fill yes
			(thermal_gap 0.5)
			(thermal_bridge_width 0.5)
			(island_removal_mode 0)
		)
		(polygon
			(pts
				(arc
					(start 362.064808 -233.649266)
					(mid 361.760008 -233.954066)
					(end 362.064808 -234.258866)
				)
				(arc
					(start 363.004862 -234.258866)
					(mid 363.309662 -233.954066)
					(end 363.004862 -233.649266)
				)
			)
		)
	)
	(zone
		(layers "In1.Cu" "In2.Cu" "In3.Cu")
		(hatch none 0.5)
		(connect_pads
			(clearance 0)
		)
		(min_thickness 0.25)
		(keepout
			(tracks not_allowed)
			(vias allowed)
			(pads allowed)
			(copperpour not_allowed)
			(footprints allowed)
		)
		(placement
			(enabled no)
			(sheetname "")
		)
		(fill yes
			(thermal_gap 0.5)
			(thermal_bridge_width 0.5)
			(island_removal_mode 0)
		)
		(polygon
			(pts
				(arc
					(start 108.49102 -233.64952)
					(mid 108.18622 -233.95432)
					(end 108.49102 -234.25912)
				)
				(arc
					(start 109.431074 -234.25912)
					(mid 109.735874 -233.95432)
					(end 109.431074 -233.64952)
				)
			)
		)
	)
	(zone
		(layers "In1.Cu" "In2.Cu" "In3.Cu")
		(hatch none 0.5)
		(connect_pads
			(clearance 0)
		)
		(min_thickness 0.25)
		(keepout
			(tracks not_allowed)
			(vias allowed)
			(pads allowed)
			(copperpour not_allowed)
			(footprints allowed)
		)
		(placement
			(enabled no)
			(sheetname "")
		)
		(fill yes
			(thermal_gap 0.5)
			(thermal_bridge_width 0.5)
			(island_removal_mode 0)
		)
		(polygon
			(pts
				(arc
					(start 116.774722 -289.17138)
					(mid 116.469922 -289.47618)
					(end 116.774722 -289.78098)
				)
				(arc
					(start 117.714776 -289.78098)
					(mid 118.019576 -289.47618)
					(end 117.714776 -289.17138)
				)
			)
		)
	)
	(zone
		(layers "In1.Cu" "In2.Cu" "In3.Cu")
		(hatch none 0.5)
		(connect_pads
			(clearance 0)
		)
		(min_thickness 0.25)
		(keepout
			(tracks not_allowed)
			(vias allowed)
			(pads allowed)
			(copperpour not_allowed)
			(footprints allowed)
		)
		(placement
			(enabled no)
			(sheetname "")
		)
		(fill yes
			(thermal_gap 0.5)
			(thermal_bridge_width 0.5)
			(island_removal_mode 0)
		)
		(polygon
			(pts
				(arc
					(start 373.174768 -285.931356)
					(mid 372.869968 -286.236156)
					(end 373.174768 -286.540956)
				)
				(arc
					(start 374.114822 -286.540956)
					(mid 374.419622 -286.236156)
					(end 374.114822 -285.931356)
				)
			)
		)
	)
	(zone
		(layers "In1.Cu" "In2.Cu" "In3.Cu")
		(hatch none 0.5)
		(connect_pads
			(clearance 0)
		)
		(min_thickness 0.25)
		(keepout
			(tracks not_allowed)
			(vias allowed)
			(pads allowed)
			(copperpour not_allowed)
			(footprints allowed)
		)
		(placement
			(enabled no)
			(sheetname "")
		)
		(fill yes
			(thermal_gap 0.5)
			(thermal_bridge_width 0.5)
			(island_removal_mode 0)
		)
		(polygon
			(pts
				(arc
					(start 362.064808 -232.029254)
					(mid 361.760008 -232.334054)
					(end 362.064808 -232.638854)
				)
				(arc
					(start 363.004862 -232.638854)
					(mid 363.309662 -232.334054)
					(end 363.004862 -232.029254)
				)
			)
		)
	)
	(zone
		(layers "In1.Cu" "In2.Cu" "In3.Cu")
		(hatch none 0.5)
		(connect_pads
			(clearance 0)
		)
		(min_thickness 0.25)
		(keepout
			(tracks not_allowed)
			(vias allowed)
			(pads allowed)
			(copperpour not_allowed)
			(footprints allowed)
		)
		(placement
			(enabled no)
			(sheetname "")
		)
		(fill yes
			(thermal_gap 0.5)
			(thermal_bridge_width 0.5)
			(island_removal_mode 0)
		)
		(polygon
			(pts
				(arc
					(start 125.2347 -289.17138)
					(mid 124.9299 -289.47618)
					(end 125.2347 -289.78098)
				)
				(arc
					(start 126.174754 -289.78098)
					(mid 126.479554 -289.47618)
					(end 126.174754 -289.17138)
				)
			)
		)
	)
	(zone
		(layers "In1.Cu" "In2.Cu" "In3.Cu")
		(hatch none 0.5)
		(connect_pads
			(clearance 0)
		)
		(min_thickness 0.25)
		(keepout
			(tracks not_allowed)
			(vias allowed)
			(pads allowed)
			(copperpour not_allowed)
			(footprints allowed)
		)
		(placement
			(enabled no)
			(sheetname "")
		)
		(fill yes
			(thermal_gap 0.5)
			(thermal_bridge_width 0.5)
			(island_removal_mode 0)
		)
		(polygon
			(pts
				(arc
					(start 370.054886 -236.079284)
					(mid 369.750086 -236.384084)
					(end 370.054886 -236.688884)
				)
				(arc
					(start 370.99494 -236.688884)
					(mid 371.29974 -236.384084)
					(end 370.99494 -236.079284)
				)
			)
		)
	)
	(zone
		(layers "In1.Cu" "In2.Cu" "In3.Cu")
		(hatch none 0.5)
		(connect_pads
			(clearance 0)
		)
		(min_thickness 0.25)
		(keepout
			(tracks not_allowed)
			(vias allowed)
			(pads allowed)
			(copperpour not_allowed)
			(footprints allowed)
		)
		(placement
			(enabled no)
			(sheetname "")
		)
		(fill yes
			(thermal_gap 0.5)
			(thermal_bridge_width 0.5)
			(island_removal_mode 0)
		)
		(polygon
			(pts
				(arc
					(start 364.414816 -234.459272)
					(mid 364.110016 -234.764072)
					(end 364.414816 -235.068872)
				)
				(arc
					(start 365.35487 -235.068872)
					(mid 365.65967 -234.764072)
					(end 365.35487 -234.459272)
				)
			)
		)
	)
	(zone
		(layers "In1.Cu" "In2.Cu" "In3.Cu")
		(hatch none 0.5)
		(connect_pads
			(clearance 0)
		)
		(min_thickness 0.25)
		(keepout
			(tracks not_allowed)
			(vias allowed)
			(pads allowed)
			(copperpour not_allowed)
			(footprints allowed)
		)
		(placement
			(enabled no)
			(sheetname "")
		)
		(fill yes
			(thermal_gap 0.5)
			(thermal_bridge_width 0.5)
			(island_removal_mode 0)
		)
		(polygon
			(pts
				(arc
					(start 367.234724 -232.83926)
					(mid 366.929924 -233.14406)
					(end 367.234724 -233.44886)
				)
				(arc
					(start 368.174778 -233.44886)
					(mid 368.479578 -233.14406)
					(end 368.174778 -232.83926)
				)
			)
		)
	)
	(zone
		(layers "In1.Cu" "In2.Cu" "In3.Cu")
		(hatch none 0.5)
		(connect_pads
			(clearance 0)
		)
		(min_thickness 0.25)
		(keepout
			(tracks not_allowed)
			(vias allowed)
			(pads allowed)
			(copperpour not_allowed)
			(footprints allowed)
		)
		(placement
			(enabled no)
			(sheetname "")
		)
		(fill yes
			(thermal_gap 0.5)
			(thermal_bridge_width 0.5)
			(island_removal_mode 0)
		)
		(polygon
			(pts
				(arc
					(start 106.141012 -231.219502)
					(mid 105.836212 -231.524302)
					(end 106.141012 -231.829102)
				)
				(arc
					(start 107.081066 -231.829102)
					(mid 107.385866 -231.524302)
					(end 107.081066 -231.219502)
				)
			)
		)
	)
	(zone
		(layers "In1.Cu" "In2.Cu" "In3.Cu")
		(hatch none 0.5)
		(connect_pads
			(clearance 0)
		)
		(min_thickness 0.25)
		(keepout
			(tracks not_allowed)
			(vias allowed)
			(pads allowed)
			(copperpour not_allowed)
			(footprints allowed)
		)
		(placement
			(enabled no)
			(sheetname "")
		)
		(fill yes
			(thermal_gap 0.5)
			(thermal_bridge_width 0.5)
			(island_removal_mode 0)
		)
		(polygon
			(pts
				(arc
					(start 114.424714 -288.361374)
					(mid 114.119914 -288.666174)
					(end 114.424714 -288.970974)
				)
				(arc
					(start 115.364768 -288.970974)
					(mid 115.669568 -288.666174)
					(end 115.364768 -288.361374)
				)
			)
		)
	)
	(zone
		(layers "In1.Cu" "In2.Cu" "In3.Cu")
		(hatch none 0.5)
		(connect_pads
			(clearance 0)
		)
		(min_thickness 0.25)
		(keepout
			(tracks not_allowed)
			(vias allowed)
			(pads allowed)
			(copperpour not_allowed)
			(footprints allowed)
		)
		(placement
			(enabled no)
			(sheetname "")
		)
		(fill yes
			(thermal_gap 0.5)
			(thermal_bridge_width 0.5)
			(island_removal_mode 0)
		)
		(polygon
			(pts
				(arc
					(start 373.174768 -290.791138)
					(mid 372.869968 -291.095938)
					(end 373.174768 -291.400738)
				)
				(arc
					(start 374.114822 -291.400738)
					(mid 374.419622 -291.095938)
					(end 374.114822 -290.791138)
				)
			)
		)
	)
	(zone
		(layers "In1.Cu" "In2.Cu" "In3.Cu")
		(hatch none 0.5)
		(connect_pads
			(clearance 0)
		)
		(min_thickness 0.25)
		(keepout
			(tracks not_allowed)
			(vias allowed)
			(pads allowed)
			(copperpour not_allowed)
			(footprints allowed)
		)
		(placement
			(enabled no)
			(sheetname "")
		)
		(fill yes
			(thermal_gap 0.5)
			(thermal_bridge_width 0.5)
			(island_removal_mode 0)
		)
		(polygon
			(pts
				(arc
					(start 372.874794 -236.079284)
					(mid 372.569994 -236.384084)
					(end 372.874794 -236.688884)
				)
				(arc
					(start 373.814848 -236.688884)
					(mid 374.119648 -236.384084)
					(end 373.814848 -236.079284)
				)
			)
		)
	)
	(zone
		(layers "In1.Cu" "In2.Cu" "In3.Cu")
		(hatch none 0.5)
		(connect_pads
			(clearance 0)
		)
		(min_thickness 0.25)
		(keepout
			(tracks not_allowed)
			(vias allowed)
			(pads allowed)
			(copperpour not_allowed)
			(footprints allowed)
		)
		(placement
			(enabled no)
			(sheetname "")
		)
		(fill yes
			(thermal_gap 0.5)
			(thermal_bridge_width 0.5)
			(island_removal_mode 0)
		)
		(polygon
			(pts
				(arc
					(start 367.234724 -234.459272)
					(mid 366.929924 -234.764072)
					(end 367.234724 -235.068872)
				)
				(arc
					(start 368.174778 -235.068872)
					(mid 368.479578 -234.764072)
					(end 368.174778 -234.459272)
				)
			)
		)
	)
	(zone
		(layers "In1.Cu" "In2.Cu" "In3.Cu")
		(hatch none 0.5)
		(connect_pads
			(clearance 0)
		)
		(min_thickness 0.25)
		(keepout
			(tracks not_allowed)
			(vias allowed)
			(pads allowed)
			(copperpour not_allowed)
			(footprints allowed)
		)
		(placement
			(enabled no)
			(sheetname "")
		)
		(fill yes
			(thermal_gap 0.5)
			(thermal_bridge_width 0.5)
			(island_removal_mode 0)
		)
		(polygon
			(pts
				(arc
					(start 364.71479 -290.791138)
					(mid 364.40999 -291.095938)
					(end 364.71479 -291.400738)
				)
				(arc
					(start 365.654844 -291.400738)
					(mid 365.959644 -291.095938)
					(end 365.654844 -290.791138)
				)
			)
		)
	)
	(zone
		(layers "In1.Cu" "In2.Cu" "In3.Cu")
		(hatch none 0.5)
		(connect_pads
			(clearance 0)
		)
		(min_thickness 0.25)
		(keepout
			(tracks not_allowed)
			(vias allowed)
			(pads allowed)
			(copperpour not_allowed)
			(footprints allowed)
		)
		(placement
			(enabled no)
			(sheetname "")
		)
		(fill yes
			(thermal_gap 0.5)
			(thermal_bridge_width 0.5)
			(island_removal_mode 0)
		)
		(polygon
			(pts
				(arc
					(start 364.414816 -231.219248)
					(mid 364.110016 -231.524048)
					(end 364.414816 -231.828848)
				)
				(arc
					(start 365.35487 -231.828848)
					(mid 365.65967 -231.524048)
					(end 365.35487 -231.219248)
				)
			)
		)
	)
	(zone
		(layers "In1.Cu" "In2.Cu" "In3.Cu")
		(hatch none 0.5)
		(connect_pads
			(clearance 0)
		)
		(min_thickness 0.25)
		(keepout
			(tracks not_allowed)
			(vias allowed)
			(pads allowed)
			(copperpour not_allowed)
			(footprints allowed)
		)
		(placement
			(enabled no)
			(sheetname "")
		)
		(fill yes
			(thermal_gap 0.5)
			(thermal_bridge_width 0.5)
			(island_removal_mode 0)
		)
		(polygon
			(pts
				(arc
					(start 108.49102 -235.269532)
					(mid 108.18622 -235.574332)
					(end 108.49102 -235.879132)
				)
				(arc
					(start 109.431074 -235.879132)
					(mid 109.735874 -235.574332)
					(end 109.431074 -235.269532)
				)
			)
		)
	)
	(zone
		(layers "In1.Cu" "In2.Cu" "In3.Cu")
		(hatch none 0.5)
		(connect_pads
			(clearance 0)
		)
		(min_thickness 0.25)
		(keepout
			(tracks not_allowed)
			(vias allowed)
			(pads allowed)
			(copperpour not_allowed)
			(footprints allowed)
		)
		(placement
			(enabled no)
			(sheetname "")
		)
		(fill yes
			(thermal_gap 0.5)
			(thermal_bridge_width 0.5)
			(island_removal_mode 0)
		)
		(polygon
			(pts
				(arc
					(start 370.35486 -289.171126)
					(mid 370.05006 -289.475926)
					(end 370.35486 -289.780726)
				)
				(arc
					(start 371.294914 -289.780726)
					(mid 371.599714 -289.475926)
					(end 371.294914 -289.171126)
				)
			)
		)
	)
	(zone
		(layers "In1.Cu" "In2.Cu" "In3.Cu")
		(hatch none 0.5)
		(connect_pads
			(clearance 0)
		)
		(min_thickness 0.25)
		(keepout
			(tracks not_allowed)
			(vias allowed)
			(pads allowed)
			(copperpour not_allowed)
			(footprints allowed)
		)
		(placement
			(enabled no)
			(sheetname "")
		)
		(fill yes
			(thermal_gap 0.5)
			(thermal_bridge_width 0.5)
			(island_removal_mode 0)
		)
		(polygon
			(pts
				(arc
					(start 364.71479 -289.171126)
					(mid 364.40999 -289.475926)
					(end 364.71479 -289.780726)
				)
				(arc
					(start 365.654844 -289.780726)
					(mid 365.959644 -289.475926)
					(end 365.654844 -289.171126)
				)
			)
		)
	)
	(zone
		(layers "In1.Cu" "In2.Cu" "In3.Cu")
		(hatch none 0.5)
		(connect_pads
			(clearance 0)
		)
		(min_thickness 0.25)
		(keepout
			(tracks not_allowed)
			(vias allowed)
			(pads allowed)
			(copperpour not_allowed)
			(footprints allowed)
		)
		(placement
			(enabled no)
			(sheetname "")
		)
		(fill yes
			(thermal_gap 0.5)
			(thermal_bridge_width 0.5)
			(island_removal_mode 0)
		)
		(polygon
			(pts
				(arc
					(start 119.59463 -287.551622)
					(mid 119.28983 -287.856422)
					(end 119.59463 -288.161222)
				)
				(arc
					(start 120.534684 -288.161222)
					(mid 120.839484 -287.856422)
					(end 120.534684 -287.551622)
				)
			)
		)
	)
	(zone
		(layers "In1.Cu" "In2.Cu" "In3.Cu")
		(hatch none 0.5)
		(connect_pads
			(clearance 0)
		)
		(min_thickness 0.25)
		(keepout
			(tracks not_allowed)
			(vias allowed)
			(pads allowed)
			(copperpour not_allowed)
			(footprints allowed)
		)
		(placement
			(enabled no)
			(sheetname "")
		)
		(fill yes
			(thermal_gap 0.5)
			(thermal_bridge_width 0.5)
			(island_removal_mode 0)
		)
		(polygon
			(pts
				(arc
					(start 362.364782 -289.981132)
					(mid 362.059982 -290.285932)
					(end 362.364782 -290.590732)
				)
				(arc
					(start 363.304836 -290.590732)
					(mid 363.609636 -290.285932)
					(end 363.304836 -289.981132)
				)
			)
		)
	)
	(zone
		(layers "In1.Cu" "In2.Cu" "In3.Cu")
		(hatch none 0.5)
		(connect_pads
			(clearance 0)
		)
		(min_thickness 0.25)
		(keepout
			(tracks not_allowed)
			(vias allowed)
			(pads allowed)
			(copperpour not_allowed)
			(footprints allowed)
		)
		(placement
			(enabled no)
			(sheetname "")
		)
		(fill yes
			(thermal_gap 0.5)
			(thermal_bridge_width 0.5)
			(island_removal_mode 0)
		)
		(polygon
			(pts
				(arc
					(start 367.534698 -287.551368)
					(mid 367.229898 -287.856168)
					(end 367.534698 -288.160968)
				)
				(arc
					(start 368.474752 -288.160968)
					(mid 368.779552 -287.856168)
					(end 368.474752 -287.551368)
				)
			)
		)
	)
	(zone
		(layers "In1.Cu" "In2.Cu" "In3.Cu")
		(hatch none 0.5)
		(connect_pads
			(clearance 0)
		)
		(min_thickness 0.25)
		(keepout
			(tracks not_allowed)
			(vias allowed)
			(pads allowed)
			(copperpour not_allowed)
			(footprints allowed)
		)
		(placement
			(enabled no)
			(sheetname "")
		)
		(fill yes
			(thermal_gap 0.5)
			(thermal_bridge_width 0.5)
			(island_removal_mode 0)
		)
		(polygon
			(pts
				(arc
					(start 100.500942 -234.459526)
					(mid 100.196142 -234.764326)
					(end 100.500942 -235.069126)
				)
				(arc
					(start 101.440996 -235.069126)
					(mid 101.745796 -234.764326)
					(end 101.440996 -234.459526)
				)
			)
		)
	)
	(zone
		(layers "In1.Cu" "In2.Cu" "In3.Cu")
		(hatch none 0.5)
		(connect_pads
			(clearance 0)
		)
		(min_thickness 0.25)
		(keepout
			(tracks not_allowed)
			(vias allowed)
			(pads allowed)
			(copperpour not_allowed)
			(footprints allowed)
		)
		(placement
			(enabled no)
			(sheetname "")
		)
		(fill yes
			(thermal_gap 0.5)
			(thermal_bridge_width 0.5)
			(island_removal_mode 0)
		)
		(polygon
			(pts
				(arc
					(start 122.414792 -287.551622)
					(mid 122.109992 -287.856422)
					(end 122.414792 -288.161222)
				)
				(arc
					(start 123.354846 -288.161222)
					(mid 123.659646 -287.856422)
					(end 123.354846 -287.551622)
				)
			)
		)
	)
	(zone
		(layers "In1.Cu" "In2.Cu" "In3.Cu")
		(hatch none 0.5)
		(connect_pads
			(clearance 0)
		)
		(min_thickness 0.25)
		(keepout
			(tracks not_allowed)
			(vias allowed)
			(pads allowed)
			(copperpour not_allowed)
			(footprints allowed)
		)
		(placement
			(enabled no)
			(sheetname "")
		)
		(fill yes
			(thermal_gap 0.5)
			(thermal_bridge_width 0.5)
			(island_removal_mode 0)
		)
		(polygon
			(pts
				(arc
					(start 116.774722 -287.551622)
					(mid 116.469922 -287.856422)
					(end 116.774722 -288.161222)
				)
				(arc
					(start 117.714776 -288.161222)
					(mid 118.019576 -287.856422)
					(end 117.714776 -287.551622)
				)
			)
		)
	)
	(zone
		(layers "In1.Cu" "In2.Cu" "In3.Cu")
		(hatch none 0.5)
		(connect_pads
			(clearance 0)
		)
		(min_thickness 0.25)
		(keepout
			(tracks not_allowed)
			(vias allowed)
			(pads allowed)
			(copperpour not_allowed)
			(footprints allowed)
		)
		(placement
			(enabled no)
			(sheetname "")
		)
		(fill yes
			(thermal_gap 0.5)
			(thermal_bridge_width 0.5)
			(island_removal_mode 0)
		)
		(polygon
			(pts
				(arc
					(start 370.054886 -231.219248)
					(mid 369.750086 -231.524048)
					(end 370.054886 -231.828848)
				)
				(arc
					(start 370.99494 -231.828848)
					(mid 371.29974 -231.524048)
					(end 370.99494 -231.219248)
				)
			)
		)
	)
	(zone
		(layers "In1.Cu" "In2.Cu" "In3.Cu")
		(hatch none 0.5)
		(connect_pads
			(clearance 0)
		)
		(min_thickness 0.25)
		(keepout
			(tracks not_allowed)
			(vias allowed)
			(pads allowed)
			(copperpour not_allowed)
			(footprints allowed)
		)
		(placement
			(enabled no)
			(sheetname "")
		)
		(fill yes
			(thermal_gap 0.5)
			(thermal_bridge_width 0.5)
			(island_removal_mode 0)
		)
		(polygon
			(pts
				(arc
					(start 116.774722 -290.791392)
					(mid 116.469922 -291.096192)
					(end 116.774722 -291.400992)
				)
				(arc
					(start 117.714776 -291.400992)
					(mid 118.019576 -291.096192)
					(end 117.714776 -290.791392)
				)
			)
		)
	)
	(zone
		(layers "In1.Cu" "In2.Cu" "In3.Cu")
		(hatch none 0.5)
		(connect_pads
			(clearance 0)
		)
		(min_thickness 0.25)
		(keepout
			(tracks not_allowed)
			(vias allowed)
			(pads allowed)
			(copperpour not_allowed)
			(footprints allowed)
		)
		(placement
			(enabled no)
			(sheetname "")
		)
		(fill yes
			(thermal_gap 0.5)
			(thermal_bridge_width 0.5)
			(island_removal_mode 0)
		)
		(polygon
			(pts
				(arc
					(start 100.500942 -236.079538)
					(mid 100.196142 -236.384338)
					(end 100.500942 -236.689138)
				)
				(arc
					(start 101.440996 -236.689138)
					(mid 101.745796 -236.384338)
					(end 101.440996 -236.079538)
				)
			)
		)
	)
	(zone
		(layers "In1.Cu" "In2.Cu" "In3.Cu")
		(hatch none 0.5)
		(connect_pads
			(clearance 0)
		)
		(min_thickness 0.25)
		(keepout
			(tracks not_allowed)
			(vias allowed)
			(pads allowed)
			(copperpour not_allowed)
			(footprints allowed)
		)
		(placement
			(enabled no)
			(sheetname "")
		)
		(fill yes
			(thermal_gap 0.5)
			(thermal_bridge_width 0.5)
			(island_removal_mode 0)
		)
		(polygon
			(pts
				(arc
					(start 106.141012 -234.459526)
					(mid 105.836212 -234.764326)
					(end 106.141012 -235.069126)
				)
				(arc
					(start 107.081066 -235.069126)
					(mid 107.385866 -234.764326)
					(end 107.081066 -234.459526)
				)
			)
		)
	)
	(zone
		(layers "In1.Cu" "In2.Cu" "In3.Cu")
		(hatch none 0.5)
		(connect_pads
			(clearance 0)
		)
		(min_thickness 0.25)
		(keepout
			(tracks not_allowed)
			(vias allowed)
			(pads allowed)
			(copperpour not_allowed)
			(footprints allowed)
		)
		(placement
			(enabled no)
			(sheetname "")
		)
		(fill yes
			(thermal_gap 0.5)
			(thermal_bridge_width 0.5)
			(island_removal_mode 0)
		)
		(polygon
			(pts
				(arc
					(start 97.681034 -236.079538)
					(mid 97.376234 -236.384338)
					(end 97.681034 -236.689138)
				)
				(arc
					(start 98.621088 -236.689138)
					(mid 98.925888 -236.384338)
					(end 98.621088 -236.079538)
				)
			)
		)
	)
	(zone
		(layers "In1.Cu" "In2.Cu" "In3.Cu")
		(hatch none 0.5)
		(connect_pads
			(clearance 0)
		)
		(min_thickness 0.25)
		(keepout
			(tracks not_allowed)
			(vias allowed)
			(pads allowed)
			(copperpour not_allowed)
			(footprints allowed)
		)
		(placement
			(enabled no)
			(sheetname "")
		)
		(fill yes
			(thermal_gap 0.5)
			(thermal_bridge_width 0.5)
			(island_removal_mode 0)
		)
		(polygon
			(pts
				(arc
					(start 103.321104 -231.219502)
					(mid 103.016304 -231.524302)
					(end 103.321104 -231.829102)
				)
				(arc
					(start 104.261158 -231.829102)
					(mid 104.565958 -231.524302)
					(end 104.261158 -231.219502)
				)
			)
		)
	)
	(zone
		(layers "In1.Cu" "In2.Cu" "In3.Cu")
		(hatch none 0.5)
		(connect_pads
			(clearance 0)
		)
		(min_thickness 0.25)
		(keepout
			(tracks not_allowed)
			(vias allowed)
			(pads allowed)
			(copperpour not_allowed)
			(footprints allowed)
		)
		(placement
			(enabled no)
			(sheetname "")
		)
		(fill yes
			(thermal_gap 0.5)
			(thermal_bridge_width 0.5)
			(island_removal_mode 0)
		)
		(polygon
			(pts
				(arc
					(start 114.424714 -289.981386)
					(mid 114.119914 -290.286186)
					(end 114.424714 -290.590986)
				)
				(arc
					(start 115.364768 -290.590986)
					(mid 115.669568 -290.286186)
					(end 115.364768 -289.981386)
				)
			)
		)
	)
	(zone
		(layers "In1.Cu" "In2.Cu" "In3.Cu")
		(hatch none 0.5)
		(connect_pads
			(clearance 0)
		)
		(min_thickness 0.25)
		(keepout
			(tracks not_allowed)
			(vias allowed)
			(pads allowed)
			(copperpour not_allowed)
			(footprints allowed)
		)
		(placement
			(enabled no)
			(sheetname "")
		)
		(fill yes
			(thermal_gap 0.5)
			(thermal_bridge_width 0.5)
			(island_removal_mode 0)
		)
		(polygon
			(pts
				(arc
					(start 372.874794 -232.83926)
					(mid 372.569994 -233.14406)
					(end 372.874794 -233.44886)
				)
				(arc
					(start 373.814848 -233.44886)
					(mid 374.119648 -233.14406)
					(end 373.814848 -232.83926)
				)
			)
		)
	)
	(zone
		(layers "In1.Cu" "In2.Cu" "In3.Cu")
		(hatch none 0.5)
		(connect_pads
			(clearance 0)
		)
		(min_thickness 0.25)
		(keepout
			(tracks not_allowed)
			(vias allowed)
			(pads allowed)
			(copperpour not_allowed)
			(footprints allowed)
		)
		(placement
			(enabled no)
			(sheetname "")
		)
		(fill yes
			(thermal_gap 0.5)
			(thermal_bridge_width 0.5)
			(island_removal_mode 0)
		)
		(polygon
			(pts
				(arc
					(start 370.35486 -287.551368)
					(mid 370.05006 -287.856168)
					(end 370.35486 -288.160968)
				)
				(arc
					(start 371.294914 -288.160968)
					(mid 371.599714 -287.856168)
					(end 371.294914 -287.551368)
				)
			)
		)
	)
	(zone
		(layers "In1.Cu" "In2.Cu" "In3.Cu")
		(hatch none 0.5)
		(connect_pads
			(clearance 0)
		)
		(min_thickness 0.25)
		(keepout
			(tracks not_allowed)
			(vias allowed)
			(pads allowed)
			(copperpour not_allowed)
			(footprints allowed)
		)
		(placement
			(enabled no)
			(sheetname "")
		)
		(fill yes
			(thermal_gap 0.5)
			(thermal_bridge_width 0.5)
			(island_removal_mode 0)
		)
		(polygon
			(pts
				(arc
					(start 373.174768 -287.551368)
					(mid 372.869968 -287.856168)
					(end 373.174768 -288.160968)
				)
				(arc
					(start 374.114822 -288.160968)
					(mid 374.419622 -287.856168)
					(end 374.114822 -287.551368)
				)
			)
		)
	)
	(zone
		(layers "In1.Cu" "In2.Cu" "In3.Cu")
		(hatch none 0.5)
		(connect_pads
			(clearance 0)
		)
		(min_thickness 0.25)
		(keepout
			(tracks not_allowed)
			(vias allowed)
			(pads allowed)
			(copperpour not_allowed)
			(footprints allowed)
		)
		(placement
			(enabled no)
			(sheetname "")
		)
		(fill yes
			(thermal_gap 0.5)
			(thermal_bridge_width 0.5)
			(island_removal_mode 0)
		)
		(polygon
			(pts
				(arc
					(start 362.064808 -235.269278)
					(mid 361.760008 -235.574078)
					(end 362.064808 -235.878878)
				)
				(arc
					(start 363.004862 -235.878878)
					(mid 363.309662 -235.574078)
					(end 363.004862 -235.269278)
				)
			)
		)
	)
	(zone
		(layers "In1.Cu" "In2.Cu" "In3.Cu")
		(hatch none 0.5)
		(connect_pads
			(clearance 0)
		)
		(min_thickness 0.25)
		(keepout
			(tracks not_allowed)
			(vias allowed)
			(pads allowed)
			(copperpour not_allowed)
			(footprints allowed)
		)
		(placement
			(enabled no)
			(sheetname "")
		)
		(fill yes
			(thermal_gap 0.5)
			(thermal_bridge_width 0.5)
			(island_removal_mode 0)
		)
		(polygon
			(pts
				(arc
					(start 373.174768 -289.171126)
					(mid 372.869968 -289.475926)
					(end 373.174768 -289.780726)
				)
				(arc
					(start 374.114822 -289.780726)
					(mid 374.419622 -289.475926)
					(end 374.114822 -289.171126)
				)
			)
		)
	)
	(zone
		(layers "In1.Cu" "In2.Cu" "In3.Cu")
		(hatch none 0.5)
		(connect_pads
			(clearance 0)
		)
		(min_thickness 0.25)
		(keepout
			(tracks not_allowed)
			(vias allowed)
			(pads allowed)
			(copperpour not_allowed)
			(footprints allowed)
		)
		(placement
			(enabled no)
			(sheetname "")
		)
		(fill yes
			(thermal_gap 0.5)
			(thermal_bridge_width 0.5)
			(island_removal_mode 0)
		)
		(polygon
			(pts
				(arc
					(start 370.054886 -234.459272)
					(mid 369.750086 -234.764072)
					(end 370.054886 -235.068872)
				)
				(arc
					(start 370.99494 -235.068872)
					(mid 371.29974 -234.764072)
					(end 370.99494 -234.459272)
				)
			)
		)
	)
	(zone
		(layers "In1.Cu" "In2.Cu" "In3.Cu")
		(hatch none 0.5)
		(connect_pads
			(clearance 0)
		)
		(min_thickness 0.25)
		(keepout
			(tracks not_allowed)
			(vias allowed)
			(pads allowed)
			(copperpour not_allowed)
			(footprints allowed)
		)
		(placement
			(enabled no)
			(sheetname "")
		)
		(fill yes
			(thermal_gap 0.5)
			(thermal_bridge_width 0.5)
			(island_removal_mode 0)
		)
		(polygon
			(pts
				(arc
					(start 370.35486 -290.791138)
					(mid 370.05006 -291.095938)
					(end 370.35486 -291.400738)
				)
				(arc
					(start 371.294914 -291.400738)
					(mid 371.599714 -291.095938)
					(end 371.294914 -290.791138)
				)
			)
		)
	)
	(zone
		(layers "In1.Cu" "In2.Cu" "In3.Cu")
		(hatch none 0.5)
		(connect_pads
			(clearance 0)
		)
		(min_thickness 0.25)
		(keepout
			(tracks not_allowed)
			(vias allowed)
			(pads allowed)
			(copperpour not_allowed)
			(footprints allowed)
		)
		(placement
			(enabled no)
			(sheetname "")
		)
		(fill yes
			(thermal_gap 0.5)
			(thermal_bridge_width 0.5)
			(island_removal_mode 0)
		)
		(polygon
			(pts
				(arc
					(start 367.534698 -289.171126)
					(mid 367.229898 -289.475926)
					(end 367.534698 -289.780726)
				)
				(arc
					(start 368.474752 -289.780726)
					(mid 368.779552 -289.475926)
					(end 368.474752 -289.171126)
				)
			)
		)
	)
	(zone
		(layers "In1.Cu" "In2.Cu" "In3.Cu")
		(hatch none 0.5)
		(connect_pads
			(clearance 0)
		)
		(min_thickness 0.25)
		(keepout
			(tracks not_allowed)
			(vias allowed)
			(pads allowed)
			(copperpour not_allowed)
			(footprints allowed)
		)
		(placement
			(enabled no)
			(sheetname "")
		)
		(fill yes
			(thermal_gap 0.5)
			(thermal_bridge_width 0.5)
			(island_removal_mode 0)
		)
		(polygon
			(pts
				(arc
					(start 106.141012 -232.839514)
					(mid 105.836212 -233.144314)
					(end 106.141012 -233.449114)
				)
				(arc
					(start 107.081066 -233.449114)
					(mid 107.385866 -233.144314)
					(end 107.081066 -232.839514)
				)
			)
		)
	)
	(zone
		(layers "In1.Cu" "In2.Cu" "In3.Cu")
		(hatch none 0.5)
		(connect_pads
			(clearance 0)
		)
		(min_thickness 0.25)
		(keepout
			(tracks not_allowed)
			(vias allowed)
			(pads allowed)
			(copperpour not_allowed)
			(footprints allowed)
		)
		(placement
			(enabled no)
			(sheetname "")
		)
		(fill yes
			(thermal_gap 0.5)
			(thermal_bridge_width 0.5)
			(island_removal_mode 0)
		)
		(polygon
			(pts
				(arc
					(start 119.59463 -289.17138)
					(mid 119.28983 -289.47618)
					(end 119.59463 -289.78098)
				)
				(arc
					(start 120.534684 -289.78098)
					(mid 120.839484 -289.47618)
					(end 120.534684 -289.17138)
				)
			)
		)
	)
	(zone
		(layers "In1.Cu" "In2.Cu" "In3.Cu")
		(hatch none 0.5)
		(connect_pads
			(clearance 0)
		)
		(min_thickness 0.25)
		(keepout
			(tracks not_allowed)
			(vias allowed)
			(pads allowed)
			(copperpour not_allowed)
			(footprints allowed)
		)
		(placement
			(enabled no)
			(sheetname "")
		)
		(fill yes
			(thermal_gap 0.5)
			(thermal_bridge_width 0.5)
			(island_removal_mode 0)
		)
		(polygon
			(pts
				(arc
					(start 122.414792 -289.17138)
					(mid 122.109992 -289.47618)
					(end 122.414792 -289.78098)
				)
				(arc
					(start 123.354846 -289.78098)
					(mid 123.659646 -289.47618)
					(end 123.354846 -289.17138)
				)
			)
		)
	)
	(zone
		(layers "In1.Cu" "In2.Cu" "In3.Cu")
		(hatch none 0.5)
		(connect_pads
			(clearance 0)
		)
		(min_thickness 0.25)
		(keepout
			(tracks not_allowed)
			(vias allowed)
			(pads allowed)
			(copperpour not_allowed)
			(footprints allowed)
		)
		(placement
			(enabled no)
			(sheetname "")
		)
		(fill yes
			(thermal_gap 0.5)
			(thermal_bridge_width 0.5)
			(island_removal_mode 0)
		)
		(polygon
			(pts
				(arc
					(start 114.424714 -286.741362)
					(mid 114.119914 -287.046162)
					(end 114.424714 -287.350962)
				)
				(arc
					(start 115.364768 -287.350962)
					(mid 115.669568 -287.046162)
					(end 115.364768 -286.741362)
				)
			)
		)
	)
	(zone
		(layers "In1.Cu" "In2.Cu" "In3.Cu")
		(hatch none 0.5)
		(connect_pads
			(clearance 0)
		)
		(min_thickness 0.25)
		(keepout
			(tracks not_allowed)
			(vias allowed)
			(pads allowed)
			(copperpour not_allowed)
			(footprints allowed)
		)
		(placement
			(enabled no)
			(sheetname "")
		)
		(fill yes
			(thermal_gap 0.5)
			(thermal_bridge_width 0.5)
			(island_removal_mode 0)
		)
		(polygon
			(pts
				(arc
					(start 370.054886 -232.83926)
					(mid 369.750086 -233.14406)
					(end 370.054886 -233.44886)
				)
				(arc
					(start 370.99494 -233.44886)
					(mid 371.29974 -233.14406)
					(end 370.99494 -232.83926)
				)
			)
		)
	)
	(zone
		(layers "In1.Cu" "In2.Cu" "In3.Cu")
		(hatch none 0.5)
		(connect_pads
			(clearance 0)
		)
		(min_thickness 0.25)
		(keepout
			(tracks not_allowed)
			(vias allowed)
			(pads allowed)
			(copperpour not_allowed)
			(footprints allowed)
		)
		(placement
			(enabled no)
			(sheetname "")
		)
		(fill yes
			(thermal_gap 0.5)
			(thermal_bridge_width 0.5)
			(island_removal_mode 0)
		)
		(polygon
			(pts
				(arc
					(start 119.59463 -290.791392)
					(mid 119.28983 -291.096192)
					(end 119.59463 -291.400992)
				)
				(arc
					(start 120.534684 -291.400992)
					(mid 120.839484 -291.096192)
					(end 120.534684 -290.791392)
				)
			)
		)
	)
	(zone
		(layers "In1.Cu" "In2.Cu" "In3.Cu")
		(hatch none 0.5)
		(connect_pads
			(clearance 0)
		)
		(min_thickness 0.25)
		(keepout
			(tracks not_allowed)
			(vias allowed)
			(pads allowed)
			(copperpour not_allowed)
			(footprints allowed)
		)
		(placement
			(enabled no)
			(sheetname "")
		)
		(fill yes
			(thermal_gap 0.5)
			(thermal_bridge_width 0.5)
			(island_removal_mode 0)
		)
		(polygon
			(pts
				(arc
					(start 125.2347 -285.93161)
					(mid 124.9299 -286.23641)
					(end 125.2347 -286.54121)
				)
				(arc
					(start 126.174754 -286.54121)
					(mid 126.479554 -286.23641)
					(end 126.174754 -285.93161)
				)
			)
		)
	)
	(zone
		(layers "In1.Cu" "In2.Cu" "In3.Cu")
		(hatch none 0.5)
		(connect_pads
			(clearance 0)
		)
		(min_thickness 0.25)
		(keepout
			(tracks not_allowed)
			(vias allowed)
			(pads allowed)
			(copperpour not_allowed)
			(footprints allowed)
		)
		(placement
			(enabled no)
			(sheetname "")
		)
		(fill yes
			(thermal_gap 0.5)
			(thermal_bridge_width 0.5)
			(island_removal_mode 0)
		)
		(polygon
			(pts
				(arc
					(start 97.681034 -234.459526)
					(mid 97.376234 -234.764326)
					(end 97.681034 -235.069126)
				)
				(arc
					(start 98.621088 -235.069126)
					(mid 98.925888 -234.764326)
					(end 98.621088 -234.459526)
				)
			)
		)
	)
	(zone
		(layers "In1.Cu" "In2.Cu" "In3.Cu")
		(hatch none 0.5)
		(connect_pads
			(clearance 0)
		)
		(min_thickness 0.25)
		(keepout
			(tracks not_allowed)
			(vias allowed)
			(pads allowed)
			(copperpour not_allowed)
			(footprints allowed)
		)
		(placement
			(enabled no)
			(sheetname "")
		)
		(fill yes
			(thermal_gap 0.5)
			(thermal_bridge_width 0.5)
			(island_removal_mode 0)
		)
		(polygon
			(pts
				(arc
					(start 367.234724 -231.219248)
					(mid 366.929924 -231.524048)
					(end 367.234724 -231.828848)
				)
				(arc
					(start 368.174778 -231.828848)
					(mid 368.479578 -231.524048)
					(end 368.174778 -231.219248)
				)
			)
		)
	)
	(zone
		(layers "In1.Cu" "In2.Cu" "In3.Cu")
		(hatch none 0.5)
		(connect_pads
			(clearance 0)
		)
		(min_thickness 0.25)
		(keepout
			(tracks not_allowed)
			(vias allowed)
			(pads allowed)
			(copperpour not_allowed)
			(footprints allowed)
		)
		(placement
			(enabled no)
			(sheetname "")
		)
		(fill yes
			(thermal_gap 0.5)
			(thermal_bridge_width 0.5)
			(island_removal_mode 0)
		)
		(polygon
			(pts
				(arc
					(start 103.321104 -232.839514)
					(mid 103.016304 -233.144314)
					(end 103.321104 -233.449114)
				)
				(arc
					(start 104.261158 -233.449114)
					(mid 104.565958 -233.144314)
					(end 104.261158 -232.839514)
				)
			)
		)
	)
	(zone
		(layers "In1.Cu" "In2.Cu" "In3.Cu")
		(hatch none 0.5)
		(connect_pads
			(clearance 0)
		)
		(min_thickness 0.25)
		(keepout
			(tracks not_allowed)
			(vias allowed)
			(pads allowed)
			(copperpour not_allowed)
			(footprints allowed)
		)
		(placement
			(enabled no)
			(sheetname "")
		)
		(fill yes
			(thermal_gap 0.5)
			(thermal_bridge_width 0.5)
			(island_removal_mode 0)
		)
		(polygon
			(pts
				(arc
					(start 103.321104 -234.459526)
					(mid 103.016304 -234.764326)
					(end 103.321104 -235.069126)
				)
				(arc
					(start 104.261158 -235.069126)
					(mid 104.565958 -234.764326)
					(end 104.261158 -234.459526)
				)
			)
		)
	)
	(zone
		(layers "In1.Cu" "In2.Cu" "In3.Cu")
		(hatch none 0.5)
		(connect_pads
			(clearance 0)
		)
		(min_thickness 0.25)
		(keepout
			(tracks not_allowed)
			(vias allowed)
			(pads allowed)
			(copperpour not_allowed)
			(footprints allowed)
		)
		(placement
			(enabled no)
			(sheetname "")
		)
		(fill yes
			(thermal_gap 0.5)
			(thermal_bridge_width 0.5)
			(island_removal_mode 0)
		)
		(polygon
			(pts
				(arc
					(start 364.414816 -232.83926)
					(mid 364.110016 -233.14406)
					(end 364.414816 -233.44886)
				)
				(arc
					(start 365.35487 -233.44886)
					(mid 365.65967 -233.14406)
					(end 365.35487 -232.83926)
				)
			)
		)
	)
	(zone
		(layers "In1.Cu" "In2.Cu" "In3.Cu")
		(hatch none 0.5)
		(connect_pads
			(clearance 0)
		)
		(min_thickness 0.25)
		(keepout
			(tracks not_allowed)
			(vias allowed)
			(pads allowed)
			(copperpour not_allowed)
			(footprints allowed)
		)
		(placement
			(enabled no)
			(sheetname "")
		)
		(fill yes
			(thermal_gap 0.5)
			(thermal_bridge_width 0.5)
			(island_removal_mode 0)
		)
		(polygon
			(pts
				(arc
					(start 100.500942 -231.219502)
					(mid 100.196142 -231.524302)
					(end 100.500942 -231.829102)
				)
				(arc
					(start 101.440996 -231.829102)
					(mid 101.745796 -231.524302)
					(end 101.440996 -231.219502)
				)
			)
		)
	)
	(zone
		(layers "In1.Cu" "In2.Cu" "In3.Cu")
		(hatch none 0.5)
		(connect_pads
			(clearance 0)
		)
		(min_thickness 0.25)
		(keepout
			(tracks not_allowed)
			(vias allowed)
			(pads allowed)
			(copperpour not_allowed)
			(footprints allowed)
		)
		(placement
			(enabled no)
			(sheetname "")
		)
		(fill yes
			(thermal_gap 0.5)
			(thermal_bridge_width 0.5)
			(island_removal_mode 0)
		)
		(polygon
			(pts
				(arc
					(start 367.534698 -290.791138)
					(mid 367.229898 -291.095938)
					(end 367.534698 -291.400738)
				)
				(arc
					(start 368.474752 -291.400738)
					(mid 368.779552 -291.095938)
					(end 368.474752 -290.791138)
				)
			)
		)
	)
	(zone
		(layers "In1.Cu" "In2.Cu" "In3.Cu")
		(hatch none 0.5)
		(connect_pads
			(clearance 0)
		)
		(min_thickness 0.25)
		(keepout
			(tracks not_allowed)
			(vias allowed)
			(pads allowed)
			(copperpour not_allowed)
			(footprints allowed)
		)
		(placement
			(enabled no)
			(sheetname "")
		)
		(fill yes
			(thermal_gap 0.5)
			(thermal_bridge_width 0.5)
			(island_removal_mode 0)
		)
		(polygon
			(pts
				(arc
					(start 108.49102 -232.029508)
					(mid 108.18622 -232.334308)
					(end 108.49102 -232.639108)
				)
				(arc
					(start 109.431074 -232.639108)
					(mid 109.735874 -232.334308)
					(end 109.431074 -232.029508)
				)
			)
		)
	)
	(zone
		(layers "In1.Cu" "In2.Cu" "In3.Cu")
		(hatch none 0.5)
		(connect_pads
			(clearance 0)
		)
		(min_thickness 0.25)
		(keepout
			(tracks not_allowed)
			(vias allowed)
			(pads allowed)
			(copperpour not_allowed)
			(footprints allowed)
		)
		(placement
			(enabled no)
			(sheetname "")
		)
		(fill yes
			(thermal_gap 0.5)
			(thermal_bridge_width 0.5)
			(island_removal_mode 0)
		)
		(polygon
			(pts
				(arc
					(start 125.2347 -290.791392)
					(mid 124.9299 -291.096192)
					(end 125.2347 -291.400992)
				)
				(arc
					(start 126.174754 -291.400992)
					(mid 126.479554 -291.096192)
					(end 126.174754 -290.791392)
				)
			)
		)
	)
	(zone
		(layers "In1.Cu" "In2.Cu" "In3.Cu")
		(hatch none 0.5)
		(connect_pads
			(clearance 0)
		)
		(min_thickness 0.25)
		(keepout
			(tracks not_allowed)
			(vias allowed)
			(pads allowed)
			(copperpour not_allowed)
			(footprints allowed)
		)
		(placement
			(enabled no)
			(sheetname "")
		)
		(fill yes
			(thermal_gap 0.5)
			(thermal_bridge_width 0.5)
			(island_removal_mode 0)
		)
		(polygon
			(pts
				(arc
					(start 364.71479 -287.551368)
					(mid 364.40999 -287.856168)
					(end 364.71479 -288.160968)
				)
				(arc
					(start 365.654844 -288.160968)
					(mid 365.959644 -287.856168)
					(end 365.654844 -287.551368)
				)
			)
		)
	)
	(zone
		(layers "In1.Cu" "In2.Cu" "In3.Cu")
		(hatch none 0.5)
		(connect_pads
			(clearance 0)
		)
		(min_thickness 0.25)
		(keepout
			(tracks not_allowed)
			(vias allowed)
			(pads allowed)
			(copperpour not_allowed)
			(footprints allowed)
		)
		(placement
			(enabled no)
			(sheetname "")
		)
		(fill yes
			(thermal_gap 0.5)
			(thermal_bridge_width 0.5)
			(island_removal_mode 0)
		)
		(polygon
			(pts
				(arc
					(start 362.364782 -288.36112)
					(mid 362.059982 -288.66592)
					(end 362.364782 -288.97072)
				)
				(arc
					(start 363.304836 -288.97072)
					(mid 363.609636 -288.66592)
					(end 363.304836 -288.36112)
				)
			)
		)
	)
	(zone
		(layers "In1.Cu" "In2.Cu" "In3.Cu")
		(hatch none 0.5)
		(connect_pads
			(clearance 0)
		)
		(min_thickness 0.25)
		(keepout
			(tracks not_allowed)
			(vias allowed)
			(pads allowed)
			(copperpour not_allowed)
			(footprints allowed)
		)
		(placement
			(enabled no)
			(sheetname "")
		)
		(fill yes
			(thermal_gap 0.5)
			(thermal_bridge_width 0.5)
			(island_removal_mode 0)
		)
		(polygon
			(pts
				(arc
					(start 372.874794 -234.459272)
					(mid 372.569994 -234.764072)
					(end 372.874794 -235.068872)
				)
				(arc
					(start 373.814848 -235.068872)
					(mid 374.119648 -234.764072)
					(end 373.814848 -234.459272)
				)
			)
		)
	)
	(zone
		(layers "In1.Cu" "In2.Cu" "In3.Cu")
		(hatch none 0.5)
		(connect_pads
			(clearance 0)
		)
		(min_thickness 0.25)
		(keepout
			(tracks not_allowed)
			(vias allowed)
			(pads allowed)
			(copperpour not_allowed)
			(footprints allowed)
		)
		(placement
			(enabled no)
			(sheetname "")
		)
		(fill yes
			(thermal_gap 0.5)
			(thermal_bridge_width 0.5)
			(island_removal_mode 0)
		)
		(polygon
			(pts
				(arc
					(start 362.364782 -286.741108)
					(mid 362.059982 -287.045908)
					(end 362.364782 -287.350708)
				)
				(arc
					(start 363.304836 -287.350708)
					(mid 363.609636 -287.045908)
					(end 363.304836 -286.741108)
				)
			)
		)
	)
	(zone
		(layers "In1.Cu" "In2.Cu" "In3.Cu")
		(hatch none 0.5)
		(connect_pads
			(clearance 0)
		)
		(min_thickness 0.25)
		(keepout
			(tracks not_allowed)
			(vias allowed)
			(pads allowed)
			(copperpour not_allowed)
			(footprints allowed)
		)
		(placement
			(enabled no)
			(sheetname "")
		)
		(fill yes
			(thermal_gap 0.5)
			(thermal_bridge_width 0.5)
			(island_removal_mode 0)
		)
		(polygon
			(pts
				(arc
					(start 122.414792 -290.791392)
					(mid 122.109992 -291.096192)
					(end 122.414792 -291.400992)
				)
				(arc
					(start 123.354846 -291.400992)
					(mid 123.659646 -291.096192)
					(end 123.354846 -290.791392)
				)
			)
		)
	)
	(zone
		(layers "In1.Cu" "In2.Cu" "In3.Cu")
		(hatch none 0.5)
		(connect_pads
			(clearance 0)
		)
		(min_thickness 0.25)
		(keepout
			(tracks not_allowed)
			(vias allowed)
			(pads allowed)
			(copperpour not_allowed)
			(footprints allowed)
		)
		(placement
			(enabled no)
			(sheetname "")
		)
		(fill yes
			(thermal_gap 0.5)
			(thermal_bridge_width 0.5)
			(island_removal_mode 0)
		)
		(polygon
			(pts
				(arc
					(start 97.681034 -232.839514)
					(mid 97.376234 -233.144314)
					(end 97.681034 -233.449114)
				)
				(arc
					(start 98.621088 -233.449114)
					(mid 98.925888 -233.144314)
					(end 98.621088 -232.839514)
				)
			)
		)
	)
	(zone
		(layers "In1.Cu" "In2.Cu" "In3.Cu")
		(hatch none 0.5)
		(connect_pads
			(clearance 0)
		)
		(min_thickness 0.25)
		(keepout
			(tracks not_allowed)
			(vias allowed)
			(pads allowed)
			(copperpour not_allowed)
			(footprints allowed)
		)
		(placement
			(enabled no)
			(sheetname "")
		)
		(fill yes
			(thermal_gap 0.5)
			(thermal_bridge_width 0.5)
			(island_removal_mode 0)
		)
		(polygon
			(pts
				(arc
					(start 125.2347 -287.551622)
					(mid 124.9299 -287.856422)
					(end 125.2347 -288.161222)
				)
				(arc
					(start 126.174754 -288.161222)
					(mid 126.479554 -287.856422)
					(end 126.174754 -287.551622)
				)
			)
		)
	)
	(zone
		(layers "In1.Cu" "In2.Cu" "In3.Cu" "In4.Cu")
		(hatch none 0.5)
		(connect_pads
			(clearance 0)
		)
		(min_thickness 0.25)
		(keepout
			(tracks not_allowed)
			(vias allowed)
			(pads allowed)
			(copperpour not_allowed)
			(footprints allowed)
		)
		(placement
			(enabled no)
			(sheetname "")
		)
		(fill yes
			(thermal_gap 0.5)
			(thermal_bridge_width 0.5)
			(island_removal_mode 0)
		)
		(polygon
			(pts
				(arc
					(start 356.731062 -286.741108)
					(mid 356.426262 -287.045908)
					(end 356.731062 -287.350708)
				)
				(arc
					(start 357.671116 -287.350708)
					(mid 357.975916 -287.045908)
					(end 357.671116 -286.741108)
				)
			)
		)
	)
	(zone
		(layers "In1.Cu" "In2.Cu" "In3.Cu" "In4.Cu")
		(hatch none 0.5)
		(connect_pads
			(clearance 0)
		)
		(min_thickness 0.25)
		(keepout
			(tracks not_allowed)
			(vias allowed)
			(pads allowed)
			(copperpour not_allowed)
			(footprints allowed)
		)
		(placement
			(enabled no)
			(sheetname "")
		)
		(fill yes
			(thermal_gap 0.5)
			(thermal_bridge_width 0.5)
			(island_removal_mode 0)
		)
		(polygon
			(pts
				(arc
					(start 348.741238 -287.551368)
					(mid 348.436438 -287.856168)
					(end 348.741238 -288.160968)
				)
				(arc
					(start 349.681292 -288.160968)
					(mid 349.986092 -287.856168)
					(end 349.681292 -287.551368)
				)
			)
		)
	)
	(zone
		(layers "In1.Cu" "In2.Cu" "In3.Cu" "In4.Cu")
		(hatch none 0.5)
		(connect_pads
			(clearance 0)
		)
		(min_thickness 0.25)
		(keepout
			(tracks not_allowed)
			(vias allowed)
			(pads allowed)
			(copperpour not_allowed)
			(footprints allowed)
		)
		(placement
			(enabled no)
			(sheetname "")
		)
		(fill yes
			(thermal_gap 0.5)
			(thermal_bridge_width 0.5)
			(island_removal_mode 0)
		)
		(polygon
			(pts
				(arc
					(start 106.440986 -290.791392)
					(mid 106.136186 -291.096192)
					(end 106.440986 -291.400992)
				)
				(arc
					(start 107.38104 -291.400992)
					(mid 107.68584 -291.096192)
					(end 107.38104 -290.791392)
				)
			)
		)
	)
	(zone
		(layers "In1.Cu" "In2.Cu" "In3.Cu" "In4.Cu")
		(hatch none 0.5)
		(connect_pads
			(clearance 0)
		)
		(min_thickness 0.25)
		(keepout
			(tracks not_allowed)
			(vias allowed)
			(pads allowed)
			(copperpour not_allowed)
			(footprints allowed)
		)
		(placement
			(enabled no)
			(sheetname "")
		)
		(fill yes
			(thermal_gap 0.5)
			(thermal_bridge_width 0.5)
			(island_removal_mode 0)
		)
		(polygon
			(pts
				(arc
					(start 108.790994 -286.741362)
					(mid 108.486194 -287.046162)
					(end 108.790994 -287.350962)
				)
				(arc
					(start 109.731048 -287.350962)
					(mid 110.035848 -287.046162)
					(end 109.731048 -286.741362)
				)
			)
		)
	)
	(zone
		(layers "In1.Cu" "In2.Cu" "In3.Cu" "In4.Cu")
		(hatch none 0.5)
		(connect_pads
			(clearance 0)
		)
		(min_thickness 0.25)
		(keepout
			(tracks not_allowed)
			(vias allowed)
			(pads allowed)
			(copperpour not_allowed)
			(footprints allowed)
		)
		(placement
			(enabled no)
			(sheetname "")
		)
		(fill yes
			(thermal_gap 0.5)
			(thermal_bridge_width 0.5)
			(island_removal_mode 0)
		)
		(polygon
			(pts
				(arc
					(start 354.381054 -289.171126)
					(mid 354.076254 -289.475926)
					(end 354.381054 -289.780726)
				)
				(arc
					(start 355.321108 -289.780726)
					(mid 355.625908 -289.475926)
					(end 355.321108 -289.171126)
				)
			)
		)
	)
	(zone
		(layers "In1.Cu" "In2.Cu" "In3.Cu" "In4.Cu")
		(hatch none 0.5)
		(connect_pads
			(clearance 0)
		)
		(min_thickness 0.25)
		(keepout
			(tracks not_allowed)
			(vias allowed)
			(pads allowed)
			(copperpour not_allowed)
			(footprints allowed)
		)
		(placement
			(enabled no)
			(sheetname "")
		)
		(fill yes
			(thermal_gap 0.5)
			(thermal_bridge_width 0.5)
			(island_removal_mode 0)
		)
		(polygon
			(pts
				(arc
					(start 351.561146 -287.551368)
					(mid 351.256346 -287.856168)
					(end 351.561146 -288.160968)
				)
				(arc
					(start 352.5012 -288.160968)
					(mid 352.806 -287.856168)
					(end 352.5012 -287.551368)
				)
			)
		)
	)
	(zone
		(layers "In1.Cu" "In2.Cu" "In3.Cu" "In4.Cu")
		(hatch none 0.5)
		(connect_pads
			(clearance 0)
		)
		(min_thickness 0.25)
		(keepout
			(tracks not_allowed)
			(vias allowed)
			(pads allowed)
			(copperpour not_allowed)
			(footprints allowed)
		)
		(placement
			(enabled no)
			(sheetname "")
		)
		(fill yes
			(thermal_gap 0.5)
			(thermal_bridge_width 0.5)
			(island_removal_mode 0)
		)
		(polygon
			(pts
				(arc
					(start 103.621078 -290.791392)
					(mid 103.316278 -291.096192)
					(end 103.621078 -291.400992)
				)
				(arc
					(start 104.561132 -291.400992)
					(mid 104.865932 -291.096192)
					(end 104.561132 -290.791392)
				)
			)
		)
	)
	(zone
		(layers "In1.Cu" "In2.Cu" "In3.Cu" "In4.Cu")
		(hatch none 0.5)
		(connect_pads
			(clearance 0)
		)
		(min_thickness 0.25)
		(keepout
			(tracks not_allowed)
			(vias allowed)
			(pads allowed)
			(copperpour not_allowed)
			(footprints allowed)
		)
		(placement
			(enabled no)
			(sheetname "")
		)
		(fill yes
			(thermal_gap 0.5)
			(thermal_bridge_width 0.5)
			(island_removal_mode 0)
		)
		(polygon
			(pts
				(arc
					(start 354.381054 -287.551368)
					(mid 354.076254 -287.856168)
					(end 354.381054 -288.160968)
				)
				(arc
					(start 355.321108 -288.160968)
					(mid 355.625908 -287.856168)
					(end 355.321108 -287.551368)
				)
			)
		)
	)
	(zone
		(layers "In1.Cu" "In2.Cu" "In3.Cu" "In4.Cu")
		(hatch none 0.5)
		(connect_pads
			(clearance 0)
		)
		(min_thickness 0.25)
		(keepout
			(tracks not_allowed)
			(vias allowed)
			(pads allowed)
			(copperpour not_allowed)
			(footprints allowed)
		)
		(placement
			(enabled no)
			(sheetname "")
		)
		(fill yes
			(thermal_gap 0.5)
			(thermal_bridge_width 0.5)
			(island_removal_mode 0)
		)
		(polygon
			(pts
				(arc
					(start 100.80117 -290.791392)
					(mid 100.49637 -291.096192)
					(end 100.80117 -291.400992)
				)
				(arc
					(start 101.741224 -291.400992)
					(mid 102.046024 -291.096192)
					(end 101.741224 -290.791392)
				)
			)
		)
	)
	(zone
		(layers "In1.Cu" "In2.Cu" "In3.Cu" "In4.Cu")
		(hatch none 0.5)
		(connect_pads
			(clearance 0)
		)
		(min_thickness 0.25)
		(keepout
			(tracks not_allowed)
			(vias allowed)
			(pads allowed)
			(copperpour not_allowed)
			(footprints allowed)
		)
		(placement
			(enabled no)
			(sheetname "")
		)
		(fill yes
			(thermal_gap 0.5)
			(thermal_bridge_width 0.5)
			(island_removal_mode 0)
		)
		(polygon
			(pts
				(arc
					(start 345.921076 -287.551368)
					(mid 345.616276 -287.856168)
					(end 345.921076 -288.160968)
				)
				(arc
					(start 346.86113 -288.160968)
					(mid 347.16593 -287.856168)
					(end 346.86113 -287.551368)
				)
			)
		)
	)
	(zone
		(layers "In1.Cu" "In2.Cu" "In3.Cu" "In4.Cu")
		(hatch none 0.5)
		(connect_pads
			(clearance 0)
		)
		(min_thickness 0.25)
		(keepout
			(tracks not_allowed)
			(vias allowed)
			(pads allowed)
			(copperpour not_allowed)
			(footprints allowed)
		)
		(placement
			(enabled no)
			(sheetname "")
		)
		(fill yes
			(thermal_gap 0.5)
			(thermal_bridge_width 0.5)
			(island_removal_mode 0)
		)
		(polygon
			(pts
				(arc
					(start 356.731062 -289.981132)
					(mid 356.426262 -290.285932)
					(end 356.731062 -290.590732)
				)
				(arc
					(start 357.671116 -290.590732)
					(mid 357.975916 -290.285932)
					(end 357.671116 -289.981132)
				)
			)
		)
	)
	(zone
		(layers "In1.Cu" "In2.Cu" "In3.Cu" "In4.Cu")
		(hatch none 0.5)
		(connect_pads
			(clearance 0)
		)
		(min_thickness 0.25)
		(keepout
			(tracks not_allowed)
			(vias allowed)
			(pads allowed)
			(copperpour not_allowed)
			(footprints allowed)
		)
		(placement
			(enabled no)
			(sheetname "")
		)
		(fill yes
			(thermal_gap 0.5)
			(thermal_bridge_width 0.5)
			(island_removal_mode 0)
		)
		(polygon
			(pts
				(arc
					(start 97.981008 -287.551622)
					(mid 97.676208 -287.856422)
					(end 97.981008 -288.161222)
				)
				(arc
					(start 98.921062 -288.161222)
					(mid 99.225862 -287.856422)
					(end 98.921062 -287.551622)
				)
			)
		)
	)
	(zone
		(layers "In1.Cu" "In2.Cu" "In3.Cu" "In4.Cu")
		(hatch none 0.5)
		(connect_pads
			(clearance 0)
		)
		(min_thickness 0.25)
		(keepout
			(tracks not_allowed)
			(vias allowed)
			(pads allowed)
			(copperpour not_allowed)
			(footprints allowed)
		)
		(placement
			(enabled no)
			(sheetname "")
		)
		(fill yes
			(thermal_gap 0.5)
			(thermal_bridge_width 0.5)
			(island_removal_mode 0)
		)
		(polygon
			(pts
				(arc
					(start 354.381054 -290.791138)
					(mid 354.076254 -291.095938)
					(end 354.381054 -291.400738)
				)
				(arc
					(start 355.321108 -291.400738)
					(mid 355.625908 -291.095938)
					(end 355.321108 -290.791138)
				)
			)
		)
	)
	(zone
		(layers "In1.Cu" "In2.Cu" "In3.Cu" "In4.Cu")
		(hatch none 0.5)
		(connect_pads
			(clearance 0)
		)
		(min_thickness 0.25)
		(keepout
			(tracks not_allowed)
			(vias allowed)
			(pads allowed)
			(copperpour not_allowed)
			(footprints allowed)
		)
		(placement
			(enabled no)
			(sheetname "")
		)
		(fill yes
			(thermal_gap 0.5)
			(thermal_bridge_width 0.5)
			(island_removal_mode 0)
		)
		(polygon
			(pts
				(arc
					(start 97.981008 -285.93161)
					(mid 97.676208 -286.23641)
					(end 97.981008 -286.54121)
				)
				(arc
					(start 98.921062 -286.54121)
					(mid 99.225862 -286.23641)
					(end 98.921062 -285.93161)
				)
			)
		)
	)
	(zone
		(layers "In1.Cu" "In2.Cu" "In3.Cu" "In4.Cu")
		(hatch none 0.5)
		(connect_pads
			(clearance 0)
		)
		(min_thickness 0.25)
		(keepout
			(tracks not_allowed)
			(vias allowed)
			(pads allowed)
			(copperpour not_allowed)
			(footprints allowed)
		)
		(placement
			(enabled no)
			(sheetname "")
		)
		(fill yes
			(thermal_gap 0.5)
			(thermal_bridge_width 0.5)
			(island_removal_mode 0)
		)
		(polygon
			(pts
				(arc
					(start 97.981008 -289.17138)
					(mid 97.676208 -289.47618)
					(end 97.981008 -289.78098)
				)
				(arc
					(start 98.921062 -289.78098)
					(mid 99.225862 -289.47618)
					(end 98.921062 -289.17138)
				)
			)
		)
	)
	(zone
		(layers "In1.Cu" "In2.Cu" "In3.Cu" "In4.Cu")
		(hatch none 0.5)
		(connect_pads
			(clearance 0)
		)
		(min_thickness 0.25)
		(keepout
			(tracks not_allowed)
			(vias allowed)
			(pads allowed)
			(copperpour not_allowed)
			(footprints allowed)
		)
		(placement
			(enabled no)
			(sheetname "")
		)
		(fill yes
			(thermal_gap 0.5)
			(thermal_bridge_width 0.5)
			(island_removal_mode 0)
		)
		(polygon
			(pts
				(arc
					(start 345.921076 -289.171126)
					(mid 345.616276 -289.475926)
					(end 345.921076 -289.780726)
				)
				(arc
					(start 346.86113 -289.780726)
					(mid 347.16593 -289.475926)
					(end 346.86113 -289.171126)
				)
			)
		)
	)
	(zone
		(layers "In1.Cu" "In2.Cu" "In3.Cu" "In4.Cu")
		(hatch none 0.5)
		(connect_pads
			(clearance 0)
		)
		(min_thickness 0.25)
		(keepout
			(tracks not_allowed)
			(vias allowed)
			(pads allowed)
			(copperpour not_allowed)
			(footprints allowed)
		)
		(placement
			(enabled no)
			(sheetname "")
		)
		(fill yes
			(thermal_gap 0.5)
			(thermal_bridge_width 0.5)
			(island_removal_mode 0)
		)
		(polygon
			(pts
				(arc
					(start 106.440986 -287.551622)
					(mid 106.136186 -287.856422)
					(end 106.440986 -288.161222)
				)
				(arc
					(start 107.38104 -288.161222)
					(mid 107.68584 -287.856422)
					(end 107.38104 -287.551622)
				)
			)
		)
	)
	(zone
		(layers "In1.Cu" "In2.Cu" "In3.Cu" "In4.Cu")
		(hatch none 0.5)
		(connect_pads
			(clearance 0)
		)
		(min_thickness 0.25)
		(keepout
			(tracks not_allowed)
			(vias allowed)
			(pads allowed)
			(copperpour not_allowed)
			(footprints allowed)
		)
		(placement
			(enabled no)
			(sheetname "")
		)
		(fill yes
			(thermal_gap 0.5)
			(thermal_bridge_width 0.5)
			(island_removal_mode 0)
		)
		(polygon
			(pts
				(arc
					(start 348.741238 -289.171126)
					(mid 348.436438 -289.475926)
					(end 348.741238 -289.780726)
				)
				(arc
					(start 349.681292 -289.780726)
					(mid 349.986092 -289.475926)
					(end 349.681292 -289.171126)
				)
			)
		)
	)
	(zone
		(layers "In1.Cu" "In2.Cu" "In3.Cu" "In4.Cu")
		(hatch none 0.5)
		(connect_pads
			(clearance 0)
		)
		(min_thickness 0.25)
		(keepout
			(tracks not_allowed)
			(vias allowed)
			(pads allowed)
			(copperpour not_allowed)
			(footprints allowed)
		)
		(placement
			(enabled no)
			(sheetname "")
		)
		(fill yes
			(thermal_gap 0.5)
			(thermal_bridge_width 0.5)
			(island_removal_mode 0)
		)
		(polygon
			(pts
				(arc
					(start 108.790994 -289.981386)
					(mid 108.486194 -290.286186)
					(end 108.790994 -290.590986)
				)
				(arc
					(start 109.731048 -290.590986)
					(mid 110.035848 -290.286186)
					(end 109.731048 -289.981386)
				)
			)
		)
	)
	(zone
		(layers "In1.Cu" "In2.Cu" "In3.Cu" "In4.Cu")
		(hatch none 0.5)
		(connect_pads
			(clearance 0)
		)
		(min_thickness 0.25)
		(keepout
			(tracks not_allowed)
			(vias allowed)
			(pads allowed)
			(copperpour not_allowed)
			(footprints allowed)
		)
		(placement
			(enabled no)
			(sheetname "")
		)
		(fill yes
			(thermal_gap 0.5)
			(thermal_bridge_width 0.5)
			(island_removal_mode 0)
		)
		(polygon
			(pts
				(arc
					(start 100.80117 -289.17138)
					(mid 100.49637 -289.47618)
					(end 100.80117 -289.78098)
				)
				(arc
					(start 101.741224 -289.78098)
					(mid 102.046024 -289.47618)
					(end 101.741224 -289.17138)
				)
			)
		)
	)
	(zone
		(layers "In1.Cu" "In2.Cu" "In3.Cu" "In4.Cu")
		(hatch none 0.5)
		(connect_pads
			(clearance 0)
		)
		(min_thickness 0.25)
		(keepout
			(tracks not_allowed)
			(vias allowed)
			(pads allowed)
			(copperpour not_allowed)
			(footprints allowed)
		)
		(placement
			(enabled no)
			(sheetname "")
		)
		(fill yes
			(thermal_gap 0.5)
			(thermal_bridge_width 0.5)
			(island_removal_mode 0)
		)
		(polygon
			(pts
				(arc
					(start 356.731062 -288.36112)
					(mid 356.426262 -288.66592)
					(end 356.731062 -288.97072)
				)
				(arc
					(start 357.671116 -288.97072)
					(mid 357.975916 -288.66592)
					(end 357.671116 -288.36112)
				)
			)
		)
	)
	(zone
		(layers "In1.Cu" "In2.Cu" "In3.Cu" "In4.Cu")
		(hatch none 0.5)
		(connect_pads
			(clearance 0)
		)
		(min_thickness 0.25)
		(keepout
			(tracks not_allowed)
			(vias allowed)
			(pads allowed)
			(copperpour not_allowed)
			(footprints allowed)
		)
		(placement
			(enabled no)
			(sheetname "")
		)
		(fill yes
			(thermal_gap 0.5)
			(thermal_bridge_width 0.5)
			(island_removal_mode 0)
		)
		(polygon
			(pts
				(arc
					(start 348.741238 -290.791138)
					(mid 348.436438 -291.095938)
					(end 348.741238 -291.400738)
				)
				(arc
					(start 349.681292 -291.400738)
					(mid 349.986092 -291.095938)
					(end 349.681292 -290.791138)
				)
			)
		)
	)
	(zone
		(layers "In1.Cu" "In2.Cu" "In3.Cu" "In4.Cu")
		(hatch none 0.5)
		(connect_pads
			(clearance 0)
		)
		(min_thickness 0.25)
		(keepout
			(tracks not_allowed)
			(vias allowed)
			(pads allowed)
			(copperpour not_allowed)
			(footprints allowed)
		)
		(placement
			(enabled no)
			(sheetname "")
		)
		(fill yes
			(thermal_gap 0.5)
			(thermal_bridge_width 0.5)
			(island_removal_mode 0)
		)
		(polygon
			(pts
				(arc
					(start 345.921076 -285.931356)
					(mid 345.616276 -286.236156)
					(end 345.921076 -286.540956)
				)
				(arc
					(start 346.86113 -286.540956)
					(mid 347.16593 -286.236156)
					(end 346.86113 -285.931356)
				)
			)
		)
	)
	(zone
		(layers "In1.Cu" "In2.Cu" "In3.Cu" "In4.Cu")
		(hatch none 0.5)
		(connect_pads
			(clearance 0)
		)
		(min_thickness 0.25)
		(keepout
			(tracks not_allowed)
			(vias allowed)
			(pads allowed)
			(copperpour not_allowed)
			(footprints allowed)
		)
		(placement
			(enabled no)
			(sheetname "")
		)
		(fill yes
			(thermal_gap 0.5)
			(thermal_bridge_width 0.5)
			(island_removal_mode 0)
		)
		(polygon
			(pts
				(arc
					(start 351.561146 -289.171126)
					(mid 351.256346 -289.475926)
					(end 351.561146 -289.780726)
				)
				(arc
					(start 352.5012 -289.780726)
					(mid 352.806 -289.475926)
					(end 352.5012 -289.171126)
				)
			)
		)
	)
	(zone
		(layers "In1.Cu" "In2.Cu" "In3.Cu" "In4.Cu")
		(hatch none 0.5)
		(connect_pads
			(clearance 0)
		)
		(min_thickness 0.25)
		(keepout
			(tracks not_allowed)
			(vias allowed)
			(pads allowed)
			(copperpour not_allowed)
			(footprints allowed)
		)
		(placement
			(enabled no)
			(sheetname "")
		)
		(fill yes
			(thermal_gap 0.5)
			(thermal_bridge_width 0.5)
			(island_removal_mode 0)
		)
		(polygon
			(pts
				(arc
					(start 106.440986 -289.17138)
					(mid 106.136186 -289.47618)
					(end 106.440986 -289.78098)
				)
				(arc
					(start 107.38104 -289.78098)
					(mid 107.68584 -289.47618)
					(end 107.38104 -289.17138)
				)
			)
		)
	)
	(zone
		(layers "In1.Cu" "In2.Cu" "In3.Cu" "In4.Cu")
		(hatch none 0.5)
		(connect_pads
			(clearance 0)
		)
		(min_thickness 0.25)
		(keepout
			(tracks not_allowed)
			(vias allowed)
			(pads allowed)
			(copperpour not_allowed)
			(footprints allowed)
		)
		(placement
			(enabled no)
			(sheetname "")
		)
		(fill yes
			(thermal_gap 0.5)
			(thermal_bridge_width 0.5)
			(island_removal_mode 0)
		)
		(polygon
			(pts
				(arc
					(start 351.561146 -290.791138)
					(mid 351.256346 -291.095938)
					(end 351.561146 -291.400738)
				)
				(arc
					(start 352.5012 -291.400738)
					(mid 352.806 -291.095938)
					(end 352.5012 -290.791138)
				)
			)
		)
	)
	(zone
		(layers "In1.Cu" "In2.Cu" "In3.Cu" "In4.Cu")
		(hatch none 0.5)
		(connect_pads
			(clearance 0)
		)
		(min_thickness 0.25)
		(keepout
			(tracks not_allowed)
			(vias allowed)
			(pads allowed)
			(copperpour not_allowed)
			(footprints allowed)
		)
		(placement
			(enabled no)
			(sheetname "")
		)
		(fill yes
			(thermal_gap 0.5)
			(thermal_bridge_width 0.5)
			(island_removal_mode 0)
		)
		(polygon
			(pts
				(arc
					(start 100.80117 -287.551622)
					(mid 100.49637 -287.856422)
					(end 100.80117 -288.161222)
				)
				(arc
					(start 101.741224 -288.161222)
					(mid 102.046024 -287.856422)
					(end 101.741224 -287.551622)
				)
			)
		)
	)
	(zone
		(layers "In1.Cu" "In2.Cu" "In3.Cu" "In4.Cu")
		(hatch none 0.5)
		(connect_pads
			(clearance 0)
		)
		(min_thickness 0.25)
		(keepout
			(tracks not_allowed)
			(vias allowed)
			(pads allowed)
			(copperpour not_allowed)
			(footprints allowed)
		)
		(placement
			(enabled no)
			(sheetname "")
		)
		(fill yes
			(thermal_gap 0.5)
			(thermal_bridge_width 0.5)
			(island_removal_mode 0)
		)
		(polygon
			(pts
				(arc
					(start 108.790994 -288.361374)
					(mid 108.486194 -288.666174)
					(end 108.790994 -288.970974)
				)
				(arc
					(start 109.731048 -288.970974)
					(mid 110.035848 -288.666174)
					(end 109.731048 -288.361374)
				)
			)
		)
	)
	(zone
		(layers "In1.Cu" "In2.Cu" "In3.Cu" "In4.Cu")
		(hatch none 0.5)
		(connect_pads
			(clearance 0)
		)
		(min_thickness 0.25)
		(keepout
			(tracks not_allowed)
			(vias allowed)
			(pads allowed)
			(copperpour not_allowed)
			(footprints allowed)
		)
		(placement
			(enabled no)
			(sheetname "")
		)
		(fill yes
			(thermal_gap 0.5)
			(thermal_bridge_width 0.5)
			(island_removal_mode 0)
		)
		(polygon
			(pts
				(arc
					(start 345.921076 -290.791138)
					(mid 345.616276 -291.095938)
					(end 345.921076 -291.400738)
				)
				(arc
					(start 346.86113 -291.400738)
					(mid 347.16593 -291.095938)
					(end 346.86113 -290.791138)
				)
			)
		)
	)
	(zone
		(layers "In1.Cu" "In2.Cu" "In3.Cu" "In4.Cu")
		(hatch none 0.5)
		(connect_pads
			(clearance 0)
		)
		(min_thickness 0.25)
		(keepout
			(tracks not_allowed)
			(vias allowed)
			(pads allowed)
			(copperpour not_allowed)
			(footprints allowed)
		)
		(placement
			(enabled no)
			(sheetname "")
		)
		(fill yes
			(thermal_gap 0.5)
			(thermal_bridge_width 0.5)
			(island_removal_mode 0)
		)
		(polygon
			(pts
				(arc
					(start 97.981008 -290.791392)
					(mid 97.676208 -291.096192)
					(end 97.981008 -291.400992)
				)
				(arc
					(start 98.921062 -291.400992)
					(mid 99.225862 -291.096192)
					(end 98.921062 -290.791392)
				)
			)
		)
	)
	(zone
		(layers "In1.Cu" "In2.Cu" "In3.Cu" "In4.Cu")
		(hatch none 0.5)
		(connect_pads
			(clearance 0)
		)
		(min_thickness 0.25)
		(keepout
			(tracks not_allowed)
			(vias allowed)
			(pads allowed)
			(copperpour not_allowed)
			(footprints allowed)
		)
		(placement
			(enabled no)
			(sheetname "")
		)
		(fill yes
			(thermal_gap 0.5)
			(thermal_bridge_width 0.5)
			(island_removal_mode 0)
		)
		(polygon
			(pts
				(arc
					(start 103.621078 -287.551622)
					(mid 103.316278 -287.856422)
					(end 103.621078 -288.161222)
				)
				(arc
					(start 104.561132 -288.161222)
					(mid 104.865932 -287.856422)
					(end 104.561132 -287.551622)
				)
			)
		)
	)
	(zone
		(layers "In1.Cu" "In2.Cu" "In3.Cu" "In4.Cu")
		(hatch none 0.5)
		(connect_pads
			(clearance 0)
		)
		(min_thickness 0.25)
		(keepout
			(tracks not_allowed)
			(vias allowed)
			(pads allowed)
			(copperpour not_allowed)
			(footprints allowed)
		)
		(placement
			(enabled no)
			(sheetname "")
		)
		(fill yes
			(thermal_gap 0.5)
			(thermal_bridge_width 0.5)
			(island_removal_mode 0)
		)
		(polygon
			(pts
				(arc
					(start 103.621078 -289.17138)
					(mid 103.316278 -289.47618)
					(end 103.621078 -289.78098)
				)
				(arc
					(start 104.561132 -289.78098)
					(mid 104.865932 -289.47618)
					(end 104.561132 -289.17138)
				)
			)
		)
	)
	(zone
		(layers "In1.Cu" "In2.Cu" "In3.Cu" "In4.Cu" "In5.Cu" "In7.Cu" "In8.Cu"
			"In9.Cu"
		)
		(hatch none 0.5)
		(connect_pads
			(clearance 0)
		)
		(min_thickness 0.25)
		(keepout
			(tracks not_allowed)
			(vias allowed)
			(pads allowed)
			(copperpour not_allowed)
			(footprints allowed)
		)
		(placement
			(enabled no)
			(sheetname "")
		)
		(fill yes
			(thermal_gap 0.5)
			(thermal_bridge_width 0.5)
			(island_removal_mode 0)
		)
		(polygon
			(pts
				(arc
					(start 114.424714 -281.88158)
					(mid 114.119914 -282.18638)
					(end 114.424714 -282.49118)
				)
				(arc
					(start 115.364768 -282.49118)
					(mid 115.669568 -282.18638)
					(end 115.364768 -281.88158)
				)
			)
		)
	)
	(zone
		(layers "In1.Cu" "In2.Cu" "In3.Cu" "In4.Cu" "In5.Cu" "In7.Cu" "In8.Cu"
			"In9.Cu"
		)
		(hatch none 0.5)
		(connect_pads
			(clearance 0)
		)
		(min_thickness 0.25)
		(keepout
			(tracks not_allowed)
			(vias allowed)
			(pads allowed)
			(copperpour not_allowed)
			(footprints allowed)
		)
		(placement
			(enabled no)
			(sheetname "")
		)
		(fill yes
			(thermal_gap 0.5)
			(thermal_bridge_width 0.5)
			(island_removal_mode 0)
		)
		(polygon
			(pts
				(arc
					(start 122.414792 -284.311598)
					(mid 122.109992 -284.616398)
					(end 122.414792 -284.921198)
				)
				(arc
					(start 123.354846 -284.921198)
					(mid 123.659646 -284.616398)
					(end 123.354846 -284.311598)
				)
			)
		)
	)
	(zone
		(layers "In1.Cu" "In2.Cu" "In3.Cu" "In4.Cu" "In5.Cu" "In7.Cu" "In8.Cu"
			"In9.Cu"
		)
		(hatch none 0.5)
		(connect_pads
			(clearance 0)
		)
		(min_thickness 0.25)
		(keepout
			(tracks not_allowed)
			(vias allowed)
			(pads allowed)
			(copperpour not_allowed)
			(footprints allowed)
		)
		(placement
			(enabled no)
			(sheetname "")
		)
		(fill yes
			(thermal_gap 0.5)
			(thermal_bridge_width 0.5)
			(island_removal_mode 0)
		)
		(polygon
			(pts
				(arc
					(start 364.71479 -282.691332)
					(mid 364.40999 -282.996132)
					(end 364.71479 -283.300932)
				)
				(arc
					(start 365.654844 -283.300932)
					(mid 365.959644 -282.996132)
					(end 365.654844 -282.691332)
				)
			)
		)
	)
	(zone
		(layers "In1.Cu" "In2.Cu" "In3.Cu" "In4.Cu" "In5.Cu" "In7.Cu" "In8.Cu"
			"In9.Cu"
		)
		(hatch none 0.5)
		(connect_pads
			(clearance 0)
		)
		(min_thickness 0.25)
		(keepout
			(tracks not_allowed)
			(vias allowed)
			(pads allowed)
			(copperpour not_allowed)
			(footprints allowed)
		)
		(placement
			(enabled no)
			(sheetname "")
		)
		(fill yes
			(thermal_gap 0.5)
			(thermal_bridge_width 0.5)
			(island_removal_mode 0)
		)
		(polygon
			(pts
				(arc
					(start 116.774722 -282.691586)
					(mid 116.469922 -282.996386)
					(end 116.774722 -283.301186)
				)
				(arc
					(start 117.714776 -283.301186)
					(mid 118.019576 -282.996386)
					(end 117.714776 -282.691586)
				)
			)
		)
	)
	(zone
		(layers "In1.Cu" "In2.Cu" "In3.Cu" "In4.Cu" "In5.Cu" "In7.Cu" "In8.Cu"
			"In9.Cu"
		)
		(hatch none 0.5)
		(connect_pads
			(clearance 0)
		)
		(min_thickness 0.25)
		(keepout
			(tracks not_allowed)
			(vias allowed)
			(pads allowed)
			(copperpour not_allowed)
			(footprints allowed)
		)
		(placement
			(enabled no)
			(sheetname "")
		)
		(fill yes
			(thermal_gap 0.5)
			(thermal_bridge_width 0.5)
			(island_removal_mode 0)
		)
		(polygon
			(pts
				(arc
					(start 367.534698 -284.311344)
					(mid 367.229898 -284.616144)
					(end 367.534698 -284.920944)
				)
				(arc
					(start 368.474752 -284.920944)
					(mid 368.779552 -284.616144)
					(end 368.474752 -284.311344)
				)
			)
		)
	)
	(zone
		(layers "In1.Cu" "In2.Cu" "In3.Cu" "In4.Cu" "In5.Cu" "In7.Cu" "In8.Cu"
			"In9.Cu"
		)
		(hatch none 0.5)
		(connect_pads
			(clearance 0)
		)
		(min_thickness 0.25)
		(keepout
			(tracks not_allowed)
			(vias allowed)
			(pads allowed)
			(copperpour not_allowed)
			(footprints allowed)
		)
		(placement
			(enabled no)
			(sheetname "")
		)
		(fill yes
			(thermal_gap 0.5)
			(thermal_bridge_width 0.5)
			(island_removal_mode 0)
		)
		(polygon
			(pts
				(arc
					(start 370.35486 -282.691332)
					(mid 370.05006 -282.996132)
					(end 370.35486 -283.300932)
				)
				(arc
					(start 371.294914 -283.300932)
					(mid 371.599714 -282.996132)
					(end 371.294914 -282.691332)
				)
			)
		)
	)
	(zone
		(layers "In1.Cu" "In2.Cu" "In3.Cu" "In4.Cu" "In5.Cu" "In7.Cu" "In8.Cu"
			"In9.Cu"
		)
		(hatch none 0.5)
		(connect_pads
			(clearance 0)
		)
		(min_thickness 0.25)
		(keepout
			(tracks not_allowed)
			(vias allowed)
			(pads allowed)
			(copperpour not_allowed)
			(footprints allowed)
		)
		(placement
			(enabled no)
			(sheetname "")
		)
		(fill yes
			(thermal_gap 0.5)
			(thermal_bridge_width 0.5)
			(island_removal_mode 0)
		)
		(polygon
			(pts
				(arc
					(start 125.2347 -282.691586)
					(mid 124.9299 -282.996386)
					(end 125.2347 -283.301186)
				)
				(arc
					(start 126.174754 -283.301186)
					(mid 126.479554 -282.996386)
					(end 126.174754 -282.691586)
				)
			)
		)
	)
	(zone
		(layers "In1.Cu" "In2.Cu" "In3.Cu" "In4.Cu" "In5.Cu" "In7.Cu" "In8.Cu"
			"In9.Cu"
		)
		(hatch none 0.5)
		(connect_pads
			(clearance 0)
		)
		(min_thickness 0.25)
		(keepout
			(tracks not_allowed)
			(vias allowed)
			(pads allowed)
			(copperpour not_allowed)
			(footprints allowed)
		)
		(placement
			(enabled no)
			(sheetname "")
		)
		(fill yes
			(thermal_gap 0.5)
			(thermal_bridge_width 0.5)
			(island_removal_mode 0)
		)
		(polygon
			(pts
				(arc
					(start 364.71479 -285.931356)
					(mid 364.40999 -286.236156)
					(end 364.71479 -286.540956)
				)
				(arc
					(start 365.654844 -286.540956)
					(mid 365.959644 -286.236156)
					(end 365.654844 -285.931356)
				)
			)
		)
	)
	(zone
		(layers "In1.Cu" "In2.Cu" "In3.Cu" "In4.Cu" "In5.Cu" "In7.Cu" "In8.Cu"
			"In9.Cu"
		)
		(hatch none 0.5)
		(connect_pads
			(clearance 0)
		)
		(min_thickness 0.25)
		(keepout
			(tracks not_allowed)
			(vias allowed)
			(pads allowed)
			(copperpour not_allowed)
			(footprints allowed)
		)
		(placement
			(enabled no)
			(sheetname "")
		)
		(fill yes
			(thermal_gap 0.5)
			(thermal_bridge_width 0.5)
			(island_removal_mode 0)
		)
		(polygon
			(pts
				(arc
					(start 119.59463 -282.691586)
					(mid 119.28983 -282.996386)
					(end 119.59463 -283.301186)
				)
				(arc
					(start 120.534684 -283.301186)
					(mid 120.839484 -282.996386)
					(end 120.534684 -282.691586)
				)
			)
		)
	)
	(zone
		(layers "In1.Cu" "In2.Cu" "In3.Cu" "In4.Cu" "In5.Cu" "In7.Cu" "In8.Cu"
			"In9.Cu"
		)
		(hatch none 0.5)
		(connect_pads
			(clearance 0)
		)
		(min_thickness 0.25)
		(keepout
			(tracks not_allowed)
			(vias allowed)
			(pads allowed)
			(copperpour not_allowed)
			(footprints allowed)
		)
		(placement
			(enabled no)
			(sheetname "")
		)
		(fill yes
			(thermal_gap 0.5)
			(thermal_bridge_width 0.5)
			(island_removal_mode 0)
		)
		(polygon
			(pts
				(arc
					(start 125.2347 -281.071574)
					(mid 124.9299 -281.376374)
					(end 125.2347 -281.681174)
				)
				(arc
					(start 126.174754 -281.681174)
					(mid 126.479554 -281.376374)
					(end 126.174754 -281.071574)
				)
			)
		)
	)
	(zone
		(layers "In1.Cu" "In2.Cu" "In3.Cu" "In4.Cu" "In5.Cu" "In7.Cu" "In8.Cu"
			"In9.Cu"
		)
		(hatch none 0.5)
		(connect_pads
			(clearance 0)
		)
		(min_thickness 0.25)
		(keepout
			(tracks not_allowed)
			(vias allowed)
			(pads allowed)
			(copperpour not_allowed)
			(footprints allowed)
		)
		(placement
			(enabled no)
			(sheetname "")
		)
		(fill yes
			(thermal_gap 0.5)
			(thermal_bridge_width 0.5)
			(island_removal_mode 0)
		)
		(polygon
			(pts
				(arc
					(start 367.534698 -282.691332)
					(mid 367.229898 -282.996132)
					(end 367.534698 -283.300932)
				)
				(arc
					(start 368.474752 -283.300932)
					(mid 368.779552 -282.996132)
					(end 368.474752 -282.691332)
				)
			)
		)
	)
	(zone
		(layers "In1.Cu" "In2.Cu" "In3.Cu" "In4.Cu" "In5.Cu" "In7.Cu" "In8.Cu"
			"In9.Cu"
		)
		(hatch none 0.5)
		(connect_pads
			(clearance 0)
		)
		(min_thickness 0.25)
		(keepout
			(tracks not_allowed)
			(vias allowed)
			(pads allowed)
			(copperpour not_allowed)
			(footprints allowed)
		)
		(placement
			(enabled no)
			(sheetname "")
		)
		(fill yes
			(thermal_gap 0.5)
			(thermal_bridge_width 0.5)
			(island_removal_mode 0)
		)
		(polygon
			(pts
				(arc
					(start 373.174768 -284.311344)
					(mid 372.869968 -284.616144)
					(end 373.174768 -284.920944)
				)
				(arc
					(start 374.114822 -284.920944)
					(mid 374.419622 -284.616144)
					(end 374.114822 -284.311344)
				)
			)
		)
	)
	(zone
		(layers "In1.Cu" "In2.Cu" "In3.Cu" "In4.Cu" "In5.Cu" "In7.Cu" "In8.Cu"
			"In9.Cu"
		)
		(hatch none 0.5)
		(connect_pads
			(clearance 0)
		)
		(min_thickness 0.25)
		(keepout
			(tracks not_allowed)
			(vias allowed)
			(pads allowed)
			(copperpour not_allowed)
			(footprints allowed)
		)
		(placement
			(enabled no)
			(sheetname "")
		)
		(fill yes
			(thermal_gap 0.5)
			(thermal_bridge_width 0.5)
			(island_removal_mode 0)
		)
		(polygon
			(pts
				(arc
					(start 367.534698 -285.931356)
					(mid 367.229898 -286.236156)
					(end 367.534698 -286.540956)
				)
				(arc
					(start 368.474752 -286.540956)
					(mid 368.779552 -286.236156)
					(end 368.474752 -285.931356)
				)
			)
		)
	)
	(zone
		(layers "In1.Cu" "In2.Cu" "In3.Cu" "In4.Cu" "In5.Cu" "In7.Cu" "In8.Cu"
			"In9.Cu"
		)
		(hatch none 0.5)
		(connect_pads
			(clearance 0)
		)
		(min_thickness 0.25)
		(keepout
			(tracks not_allowed)
			(vias allowed)
			(pads allowed)
			(copperpour not_allowed)
			(footprints allowed)
		)
		(placement
			(enabled no)
			(sheetname "")
		)
		(fill yes
			(thermal_gap 0.5)
			(thermal_bridge_width 0.5)
			(island_removal_mode 0)
		)
		(polygon
			(pts
				(arc
					(start 119.59463 -284.311598)
					(mid 119.28983 -284.616398)
					(end 119.59463 -284.921198)
				)
				(arc
					(start 120.534684 -284.921198)
					(mid 120.839484 -284.616398)
					(end 120.534684 -284.311598)
				)
			)
		)
	)
	(zone
		(layers "In1.Cu" "In2.Cu" "In3.Cu" "In4.Cu" "In5.Cu" "In7.Cu" "In8.Cu"
			"In9.Cu"
		)
		(hatch none 0.5)
		(connect_pads
			(clearance 0)
		)
		(min_thickness 0.25)
		(keepout
			(tracks not_allowed)
			(vias allowed)
			(pads allowed)
			(copperpour not_allowed)
			(footprints allowed)
		)
		(placement
			(enabled no)
			(sheetname "")
		)
		(fill yes
			(thermal_gap 0.5)
			(thermal_bridge_width 0.5)
			(island_removal_mode 0)
		)
		(polygon
			(pts
				(arc
					(start 125.2347 -284.311598)
					(mid 124.9299 -284.616398)
					(end 125.2347 -284.921198)
				)
				(arc
					(start 126.174754 -284.921198)
					(mid 126.479554 -284.616398)
					(end 126.174754 -284.311598)
				)
			)
		)
	)
	(zone
		(layers "In1.Cu" "In2.Cu" "In3.Cu" "In4.Cu" "In5.Cu" "In7.Cu" "In8.Cu"
			"In9.Cu"
		)
		(hatch none 0.5)
		(connect_pads
			(clearance 0)
		)
		(min_thickness 0.25)
		(keepout
			(tracks not_allowed)
			(vias allowed)
			(pads allowed)
			(copperpour not_allowed)
			(footprints allowed)
		)
		(placement
			(enabled no)
			(sheetname "")
		)
		(fill yes
			(thermal_gap 0.5)
			(thermal_bridge_width 0.5)
			(island_removal_mode 0)
		)
		(polygon
			(pts
				(arc
					(start 114.424714 -285.121604)
					(mid 114.119914 -285.426404)
					(end 114.424714 -285.731204)
				)
				(arc
					(start 115.364768 -285.731204)
					(mid 115.669568 -285.426404)
					(end 115.364768 -285.121604)
				)
			)
		)
	)
	(zone
		(layers "In1.Cu" "In2.Cu" "In3.Cu" "In4.Cu" "In5.Cu" "In7.Cu" "In8.Cu"
			"In9.Cu"
		)
		(hatch none 0.5)
		(connect_pads
			(clearance 0)
		)
		(min_thickness 0.25)
		(keepout
			(tracks not_allowed)
			(vias allowed)
			(pads allowed)
			(copperpour not_allowed)
			(footprints allowed)
		)
		(placement
			(enabled no)
			(sheetname "")
		)
		(fill yes
			(thermal_gap 0.5)
			(thermal_bridge_width 0.5)
			(island_removal_mode 0)
		)
		(polygon
			(pts
				(arc
					(start 114.424714 -283.501592)
					(mid 114.119914 -283.806392)
					(end 114.424714 -284.111192)
				)
				(arc
					(start 115.364768 -284.111192)
					(mid 115.669568 -283.806392)
					(end 115.364768 -283.501592)
				)
			)
		)
	)
	(zone
		(layers "In1.Cu" "In2.Cu" "In3.Cu" "In4.Cu" "In5.Cu" "In7.Cu" "In8.Cu"
			"In9.Cu"
		)
		(hatch none 0.5)
		(connect_pads
			(clearance 0)
		)
		(min_thickness 0.25)
		(keepout
			(tracks not_allowed)
			(vias allowed)
			(pads allowed)
			(copperpour not_allowed)
			(footprints allowed)
		)
		(placement
			(enabled no)
			(sheetname "")
		)
		(fill yes
			(thermal_gap 0.5)
			(thermal_bridge_width 0.5)
			(island_removal_mode 0)
		)
		(polygon
			(pts
				(arc
					(start 362.364782 -283.501338)
					(mid 362.059982 -283.806138)
					(end 362.364782 -284.110938)
				)
				(arc
					(start 363.304836 -284.110938)
					(mid 363.609636 -283.806138)
					(end 363.304836 -283.501338)
				)
			)
		)
	)
	(zone
		(layers "In1.Cu" "In2.Cu" "In3.Cu" "In4.Cu" "In5.Cu" "In7.Cu" "In8.Cu"
			"In9.Cu"
		)
		(hatch none 0.5)
		(connect_pads
			(clearance 0)
		)
		(min_thickness 0.25)
		(keepout
			(tracks not_allowed)
			(vias allowed)
			(pads allowed)
			(copperpour not_allowed)
			(footprints allowed)
		)
		(placement
			(enabled no)
			(sheetname "")
		)
		(fill yes
			(thermal_gap 0.5)
			(thermal_bridge_width 0.5)
			(island_removal_mode 0)
		)
		(polygon
			(pts
				(arc
					(start 116.774722 -284.311598)
					(mid 116.469922 -284.616398)
					(end 116.774722 -284.921198)
				)
				(arc
					(start 117.714776 -284.921198)
					(mid 118.019576 -284.616398)
					(end 117.714776 -284.311598)
				)
			)
		)
	)
	(zone
		(layers "In1.Cu" "In2.Cu" "In3.Cu" "In4.Cu" "In5.Cu" "In7.Cu" "In8.Cu"
			"In9.Cu"
		)
		(hatch none 0.5)
		(connect_pads
			(clearance 0)
		)
		(min_thickness 0.25)
		(keepout
			(tracks not_allowed)
			(vias allowed)
			(pads allowed)
			(copperpour not_allowed)
			(footprints allowed)
		)
		(placement
			(enabled no)
			(sheetname "")
		)
		(fill yes
			(thermal_gap 0.5)
			(thermal_bridge_width 0.5)
			(island_removal_mode 0)
		)
		(polygon
			(pts
				(arc
					(start 373.174768 -281.07132)
					(mid 372.869968 -281.37612)
					(end 373.174768 -281.68092)
				)
				(arc
					(start 374.114822 -281.68092)
					(mid 374.419622 -281.37612)
					(end 374.114822 -281.07132)
				)
			)
		)
	)
	(zone
		(layers "In1.Cu" "In2.Cu" "In3.Cu" "In4.Cu" "In5.Cu" "In7.Cu" "In8.Cu"
			"In9.Cu"
		)
		(hatch none 0.5)
		(connect_pads
			(clearance 0)
		)
		(min_thickness 0.25)
		(keepout
			(tracks not_allowed)
			(vias allowed)
			(pads allowed)
			(copperpour not_allowed)
			(footprints allowed)
		)
		(placement
			(enabled no)
			(sheetname "")
		)
		(fill yes
			(thermal_gap 0.5)
			(thermal_bridge_width 0.5)
			(island_removal_mode 0)
		)
		(polygon
			(pts
				(arc
					(start 364.71479 -284.311344)
					(mid 364.40999 -284.616144)
					(end 364.71479 -284.920944)
				)
				(arc
					(start 365.654844 -284.920944)
					(mid 365.959644 -284.616144)
					(end 365.654844 -284.311344)
				)
			)
		)
	)
	(zone
		(layers "In1.Cu" "In2.Cu" "In3.Cu" "In4.Cu" "In5.Cu" "In7.Cu" "In8.Cu"
			"In9.Cu"
		)
		(hatch none 0.5)
		(connect_pads
			(clearance 0)
		)
		(min_thickness 0.25)
		(keepout
			(tracks not_allowed)
			(vias allowed)
			(pads allowed)
			(copperpour not_allowed)
			(footprints allowed)
		)
		(placement
			(enabled no)
			(sheetname "")
		)
		(fill yes
			(thermal_gap 0.5)
			(thermal_bridge_width 0.5)
			(island_removal_mode 0)
		)
		(polygon
			(pts
				(arc
					(start 122.414792 -285.93161)
					(mid 122.109992 -286.23641)
					(end 122.414792 -286.54121)
				)
				(arc
					(start 123.354846 -286.54121)
					(mid 123.659646 -286.23641)
					(end 123.354846 -285.93161)
				)
			)
		)
	)
	(zone
		(layers "In1.Cu" "In2.Cu" "In3.Cu" "In4.Cu" "In5.Cu" "In7.Cu" "In8.Cu"
			"In9.Cu"
		)
		(hatch none 0.5)
		(connect_pads
			(clearance 0)
		)
		(min_thickness 0.25)
		(keepout
			(tracks not_allowed)
			(vias allowed)
			(pads allowed)
			(copperpour not_allowed)
			(footprints allowed)
		)
		(placement
			(enabled no)
			(sheetname "")
		)
		(fill yes
			(thermal_gap 0.5)
			(thermal_bridge_width 0.5)
			(island_removal_mode 0)
		)
		(polygon
			(pts
				(arc
					(start 370.35486 -285.931356)
					(mid 370.05006 -286.236156)
					(end 370.35486 -286.540956)
				)
				(arc
					(start 371.294914 -286.540956)
					(mid 371.599714 -286.236156)
					(end 371.294914 -285.931356)
				)
			)
		)
	)
	(zone
		(layers "In1.Cu" "In2.Cu" "In3.Cu" "In4.Cu" "In5.Cu" "In7.Cu" "In8.Cu"
			"In9.Cu"
		)
		(hatch none 0.5)
		(connect_pads
			(clearance 0)
		)
		(min_thickness 0.25)
		(keepout
			(tracks not_allowed)
			(vias allowed)
			(pads allowed)
			(copperpour not_allowed)
			(footprints allowed)
		)
		(placement
			(enabled no)
			(sheetname "")
		)
		(fill yes
			(thermal_gap 0.5)
			(thermal_bridge_width 0.5)
			(island_removal_mode 0)
		)
		(polygon
			(pts
				(arc
					(start 370.35486 -281.07132)
					(mid 370.05006 -281.37612)
					(end 370.35486 -281.68092)
				)
				(arc
					(start 371.294914 -281.68092)
					(mid 371.599714 -281.37612)
					(end 371.294914 -281.07132)
				)
			)
		)
	)
	(zone
		(layers "In1.Cu" "In2.Cu" "In3.Cu" "In4.Cu" "In5.Cu" "In7.Cu" "In8.Cu"
			"In9.Cu"
		)
		(hatch none 0.5)
		(connect_pads
			(clearance 0)
		)
		(min_thickness 0.25)
		(keepout
			(tracks not_allowed)
			(vias allowed)
			(pads allowed)
			(copperpour not_allowed)
			(footprints allowed)
		)
		(placement
			(enabled no)
			(sheetname "")
		)
		(fill yes
			(thermal_gap 0.5)
			(thermal_bridge_width 0.5)
			(island_removal_mode 0)
		)
		(polygon
			(pts
				(arc
					(start 373.174768 -282.691332)
					(mid 372.869968 -282.996132)
					(end 373.174768 -283.300932)
				)
				(arc
					(start 374.114822 -283.300932)
					(mid 374.419622 -282.996132)
					(end 374.114822 -282.691332)
				)
			)
		)
	)
	(zone
		(layers "In1.Cu" "In2.Cu" "In3.Cu" "In4.Cu" "In5.Cu" "In7.Cu" "In8.Cu"
			"In9.Cu"
		)
		(hatch none 0.5)
		(connect_pads
			(clearance 0)
		)
		(min_thickness 0.25)
		(keepout
			(tracks not_allowed)
			(vias allowed)
			(pads allowed)
			(copperpour not_allowed)
			(footprints allowed)
		)
		(placement
			(enabled no)
			(sheetname "")
		)
		(fill yes
			(thermal_gap 0.5)
			(thermal_bridge_width 0.5)
			(island_removal_mode 0)
		)
		(polygon
			(pts
				(arc
					(start 122.414792 -281.071574)
					(mid 122.109992 -281.376374)
					(end 122.414792 -281.681174)
				)
				(arc
					(start 123.354846 -281.681174)
					(mid 123.659646 -281.376374)
					(end 123.354846 -281.071574)
				)
			)
		)
	)
	(zone
		(layers "In1.Cu" "In2.Cu" "In3.Cu" "In4.Cu" "In5.Cu" "In7.Cu" "In8.Cu"
			"In9.Cu"
		)
		(hatch none 0.5)
		(connect_pads
			(clearance 0)
		)
		(min_thickness 0.25)
		(keepout
			(tracks not_allowed)
			(vias allowed)
			(pads allowed)
			(copperpour not_allowed)
			(footprints allowed)
		)
		(placement
			(enabled no)
			(sheetname "")
		)
		(fill yes
			(thermal_gap 0.5)
			(thermal_bridge_width 0.5)
			(island_removal_mode 0)
		)
		(polygon
			(pts
				(arc
					(start 116.774722 -285.93161)
					(mid 116.469922 -286.23641)
					(end 116.774722 -286.54121)
				)
				(arc
					(start 117.714776 -286.54121)
					(mid 118.019576 -286.23641)
					(end 117.714776 -285.93161)
				)
			)
		)
	)
	(zone
		(layers "In1.Cu" "In2.Cu" "In3.Cu" "In4.Cu" "In5.Cu" "In7.Cu" "In8.Cu"
			"In9.Cu"
		)
		(hatch none 0.5)
		(connect_pads
			(clearance 0)
		)
		(min_thickness 0.25)
		(keepout
			(tracks not_allowed)
			(vias allowed)
			(pads allowed)
			(copperpour not_allowed)
			(footprints allowed)
		)
		(placement
			(enabled no)
			(sheetname "")
		)
		(fill yes
			(thermal_gap 0.5)
			(thermal_bridge_width 0.5)
			(island_removal_mode 0)
		)
		(polygon
			(pts
				(arc
					(start 362.364782 -285.12135)
					(mid 362.059982 -285.42615)
					(end 362.364782 -285.73095)
				)
				(arc
					(start 363.304836 -285.73095)
					(mid 363.609636 -285.42615)
					(end 363.304836 -285.12135)
				)
			)
		)
	)
	(zone
		(layers "In1.Cu" "In2.Cu" "In3.Cu" "In4.Cu" "In5.Cu" "In7.Cu" "In8.Cu"
			"In9.Cu"
		)
		(hatch none 0.5)
		(connect_pads
			(clearance 0)
		)
		(min_thickness 0.25)
		(keepout
			(tracks not_allowed)
			(vias allowed)
			(pads allowed)
			(copperpour not_allowed)
			(footprints allowed)
		)
		(placement
			(enabled no)
			(sheetname "")
		)
		(fill yes
			(thermal_gap 0.5)
			(thermal_bridge_width 0.5)
			(island_removal_mode 0)
		)
		(polygon
			(pts
				(arc
					(start 370.35486 -284.311344)
					(mid 370.05006 -284.616144)
					(end 370.35486 -284.920944)
				)
				(arc
					(start 371.294914 -284.920944)
					(mid 371.599714 -284.616144)
					(end 371.294914 -284.311344)
				)
			)
		)
	)
	(zone
		(layers "In1.Cu" "In2.Cu" "In3.Cu" "In4.Cu" "In5.Cu" "In7.Cu" "In8.Cu"
			"In9.Cu"
		)
		(hatch none 0.5)
		(connect_pads
			(clearance 0)
		)
		(min_thickness 0.25)
		(keepout
			(tracks not_allowed)
			(vias allowed)
			(pads allowed)
			(copperpour not_allowed)
			(footprints allowed)
		)
		(placement
			(enabled no)
			(sheetname "")
		)
		(fill yes
			(thermal_gap 0.5)
			(thermal_bridge_width 0.5)
			(island_removal_mode 0)
		)
		(polygon
			(pts
				(arc
					(start 122.414792 -282.691586)
					(mid 122.109992 -282.996386)
					(end 122.414792 -283.301186)
				)
				(arc
					(start 123.354846 -283.301186)
					(mid 123.659646 -282.996386)
					(end 123.354846 -282.691586)
				)
			)
		)
	)
	(zone
		(layers "In1.Cu" "In2.Cu" "In3.Cu" "In4.Cu" "In5.Cu" "In7.Cu" "In8.Cu"
			"In9.Cu"
		)
		(hatch none 0.5)
		(connect_pads
			(clearance 0)
		)
		(min_thickness 0.25)
		(keepout
			(tracks not_allowed)
			(vias allowed)
			(pads allowed)
			(copperpour not_allowed)
			(footprints allowed)
		)
		(placement
			(enabled no)
			(sheetname "")
		)
		(fill yes
			(thermal_gap 0.5)
			(thermal_bridge_width 0.5)
			(island_removal_mode 0)
		)
		(polygon
			(pts
				(arc
					(start 119.59463 -285.93161)
					(mid 119.28983 -286.23641)
					(end 119.59463 -286.54121)
				)
				(arc
					(start 120.534684 -286.54121)
					(mid 120.839484 -286.23641)
					(end 120.534684 -285.93161)
				)
			)
		)
	)
	(zone
		(layers "In1.Cu" "In2.Cu" "In3.Cu" "In4.Cu" "In5.Cu" "In7.Cu" "In8.Cu"
			"In9.Cu"
		)
		(hatch none 0.5)
		(connect_pads
			(clearance 0)
		)
		(min_thickness 0.25)
		(keepout
			(tracks not_allowed)
			(vias allowed)
			(pads allowed)
			(copperpour not_allowed)
			(footprints allowed)
		)
		(placement
			(enabled no)
			(sheetname "")
		)
		(fill yes
			(thermal_gap 0.5)
			(thermal_bridge_width 0.5)
			(island_removal_mode 0)
		)
		(polygon
			(pts
				(arc
					(start 362.364782 -281.881326)
					(mid 362.059982 -282.186126)
					(end 362.364782 -282.490926)
				)
				(arc
					(start 363.304836 -282.490926)
					(mid 363.609636 -282.186126)
					(end 363.304836 -281.881326)
				)
			)
		)
	)
	(zone
		(layers "In1.Cu" "In2.Cu" "In3.Cu" "In5.Cu" "In7.Cu" "In8.Cu" "In9.Cu"
			"In14.Cu" "In16.Cu"
		)
		(hatch none 0.5)
		(connect_pads
			(clearance 0)
		)
		(min_thickness 0.25)
		(keepout
			(tracks not_allowed)
			(vias allowed)
			(pads allowed)
			(copperpour not_allowed)
			(footprints allowed)
		)
		(placement
			(enabled no)
			(sheetname "")
		)
		(fill yes
			(thermal_gap 0.5)
			(thermal_bridge_width 0.5)
			(island_removal_mode 0)
		)
		(polygon
			(pts
				(arc
					(start 72.141842 -432.560476)
					(mid 72.16416 -432.614358)
					(end 72.218042 -432.636676)
				)
				(arc
					(start 73.157842 -432.636676)
					(mid 73.211724 -432.614358)
					(end 73.234042 -432.560476)
				)
				(arc
					(start 73.234042 -430.018952)
					(mid 73.211724 -429.96507)
					(end 73.157842 -429.942752)
				)
				(arc
					(start 72.218042 -429.942752)
					(mid 72.16416 -429.96507)
					(end 72.141842 -430.018952)
				)
			)
		)
	)
	(zone
		(layers "In1.Cu" "In2.Cu" "In3.Cu" "In5.Cu" "In7.Cu" "In8.Cu" "In9.Cu"
			"In14.Cu" "In16.Cu"
		)
		(hatch none 0.5)
		(connect_pads
			(clearance 0)
		)
		(min_thickness 0.25)
		(keepout
			(tracks not_allowed)
			(vias allowed)
			(pads allowed)
			(copperpour not_allowed)
			(footprints allowed)
		)
		(placement
			(enabled no)
			(sheetname "")
		)
		(fill yes
			(thermal_gap 0.5)
			(thermal_bridge_width 0.5)
			(island_removal_mode 0)
		)
		(polygon
			(pts
				(arc
					(start 77.141832 -432.560476)
					(mid 77.16415 -432.614358)
					(end 77.218032 -432.636676)
				)
				(arc
					(start 78.157832 -432.636676)
					(mid 78.211714 -432.614358)
					(end 78.234032 -432.560476)
				)
				(arc
					(start 78.234032 -430.018952)
					(mid 78.211714 -429.96507)
					(end 78.157832 -429.942752)
				)
				(arc
					(start 77.218032 -429.942752)
					(mid 77.16415 -429.96507)
					(end 77.141832 -430.018952)
				)
			)
		)
	)
	(zone
		(layers "In1.Cu" "In2.Cu" "In3.Cu" "In5.Cu" "In7.Cu" "In8.Cu" "In9.Cu"
			"In14.Cu" "In16.Cu"
		)
		(hatch none 0.5)
		(connect_pads
			(clearance 0)
		)
		(min_thickness 0.25)
		(keepout
			(tracks not_allowed)
			(vias allowed)
			(pads allowed)
			(copperpour not_allowed)
			(footprints allowed)
		)
		(placement
			(enabled no)
			(sheetname "")
		)
		(fill yes
			(thermal_gap 0.5)
			(thermal_bridge_width 0.5)
			(island_removal_mode 0)
		)
		(polygon
			(pts
				(arc
					(start 68.14185 -432.560476)
					(mid 68.164168 -432.614358)
					(end 68.21805 -432.636676)
				)
				(arc
					(start 69.15785 -432.636676)
					(mid 69.211732 -432.614358)
					(end 69.23405 -432.560476)
				)
				(arc
					(start 69.23405 -430.018952)
					(mid 69.211732 -429.96507)
					(end 69.15785 -429.942752)
				)
				(arc
					(start 68.21805 -429.942752)
					(mid 68.164168 -429.96507)
					(end 68.14185 -430.018952)
				)
			)
		)
	)
	(zone
		(layers "In1.Cu" "In2.Cu" "In3.Cu" "In5.Cu" "In7.Cu" "In8.Cu" "In9.Cu"
			"In14.Cu" "In16.Cu"
		)
		(hatch none 0.5)
		(connect_pads
			(clearance 0)
		)
		(min_thickness 0.25)
		(keepout
			(tracks not_allowed)
			(vias allowed)
			(pads allowed)
			(copperpour not_allowed)
			(footprints allowed)
		)
		(placement
			(enabled no)
			(sheetname "")
		)
		(fill yes
			(thermal_gap 0.5)
			(thermal_bridge_width 0.5)
			(island_removal_mode 0)
		)
		(polygon
			(pts
				(arc
					(start 60.141866 -432.560476)
					(mid 60.164184 -432.614358)
					(end 60.218066 -432.636676)
				)
				(arc
					(start 61.157866 -432.636676)
					(mid 61.211748 -432.614358)
					(end 61.234066 -432.560476)
				)
				(arc
					(start 61.234066 -430.018952)
					(mid 61.211748 -429.96507)
					(end 61.157866 -429.942752)
				)
				(arc
					(start 60.218066 -429.942752)
					(mid 60.164184 -429.96507)
					(end 60.141866 -430.018952)
				)
			)
		)
	)
	(zone
		(layers "In1.Cu" "In2.Cu" "In3.Cu" "In5.Cu" "In7.Cu" "In8.Cu" "In9.Cu"
			"In14.Cu" "In16.Cu"
		)
		(hatch none 0.5)
		(connect_pads
			(clearance 0)
		)
		(min_thickness 0.25)
		(keepout
			(tracks not_allowed)
			(vias allowed)
			(pads allowed)
			(copperpour not_allowed)
			(footprints allowed)
		)
		(placement
			(enabled no)
			(sheetname "")
		)
		(fill yes
			(thermal_gap 0.5)
			(thermal_bridge_width 0.5)
			(island_removal_mode 0)
		)
		(polygon
			(pts
				(arc
					(start 81.141824 -432.560476)
					(mid 81.164142 -432.614358)
					(end 81.218024 -432.636676)
				)
				(arc
					(start 82.157824 -432.636676)
					(mid 82.211706 -432.614358)
					(end 82.234024 -432.560476)
				)
				(arc
					(start 82.234024 -430.018952)
					(mid 82.211706 -429.96507)
					(end 82.157824 -429.942752)
				)
				(arc
					(start 81.218024 -429.942752)
					(mid 81.164142 -429.96507)
					(end 81.141824 -430.018952)
				)
			)
		)
	)
	(zone
		(layers "In1.Cu" "In2.Cu" "In3.Cu" "In5.Cu" "In7.Cu" "In8.Cu" "In9.Cu"
			"In14.Cu" "In16.Cu"
		)
		(hatch none 0.5)
		(connect_pads
			(clearance 0)
		)
		(min_thickness 0.25)
		(keepout
			(tracks not_allowed)
			(vias allowed)
			(pads allowed)
			(copperpour not_allowed)
			(footprints allowed)
		)
		(placement
			(enabled no)
			(sheetname "")
		)
		(fill yes
			(thermal_gap 0.5)
			(thermal_bridge_width 0.5)
			(island_removal_mode 0)
		)
		(polygon
			(pts
				(arc
					(start 75.141836 -431.560478)
					(mid 75.164154 -431.61436)
					(end 75.218036 -431.636678)
				)
				(arc
					(start 76.157836 -431.636678)
					(mid 76.211718 -431.61436)
					(end 76.234036 -431.560478)
				)
				(arc
					(start 76.234036 -429.018954)
					(mid 76.211718 -428.965072)
					(end 76.157836 -428.942754)
				)
				(arc
					(start 75.218036 -428.942754)
					(mid 75.164154 -428.965072)
					(end 75.141836 -429.018954)
				)
			)
		)
	)
	(zone
		(layers "In1.Cu" "In2.Cu" "In3.Cu" "In5.Cu" "In7.Cu" "In8.Cu" "In9.Cu"
			"In14.Cu" "In16.Cu"
		)
		(hatch none 0.5)
		(connect_pads
			(clearance 0)
		)
		(min_thickness 0.25)
		(keepout
			(tracks not_allowed)
			(vias allowed)
			(pads allowed)
			(copperpour not_allowed)
			(footprints allowed)
		)
		(placement
			(enabled no)
			(sheetname "")
		)
		(fill yes
			(thermal_gap 0.5)
			(thermal_bridge_width 0.5)
			(island_removal_mode 0)
		)
		(polygon
			(pts
				(arc
					(start 79.141828 -431.560478)
					(mid 79.164146 -431.61436)
					(end 79.218028 -431.636678)
				)
				(arc
					(start 80.157828 -431.636678)
					(mid 80.21171 -431.61436)
					(end 80.234028 -431.560478)
				)
				(arc
					(start 80.234028 -429.018954)
					(mid 80.21171 -428.965072)
					(end 80.157828 -428.942754)
				)
				(arc
					(start 79.218028 -428.942754)
					(mid 79.164146 -428.965072)
					(end 79.141828 -429.018954)
				)
			)
		)
	)
	(zone
		(layers "In1.Cu" "In2.Cu" "In3.Cu" "In5.Cu" "In7.Cu" "In8.Cu" "In9.Cu"
			"In14.Cu" "In16.Cu"
		)
		(hatch none 0.5)
		(connect_pads
			(clearance 0)
		)
		(min_thickness 0.25)
		(keepout
			(tracks not_allowed)
			(vias allowed)
			(pads allowed)
			(copperpour not_allowed)
			(footprints allowed)
		)
		(placement
			(enabled no)
			(sheetname "")
		)
		(fill yes
			(thermal_gap 0.5)
			(thermal_bridge_width 0.5)
			(island_removal_mode 0)
		)
		(polygon
			(pts
				(arc
					(start 58.14187 -431.560478)
					(mid 58.164188 -431.61436)
					(end 58.21807 -431.636678)
				)
				(arc
					(start 59.15787 -431.636678)
					(mid 59.211752 -431.61436)
					(end 59.23407 -431.560478)
				)
				(arc
					(start 59.23407 -429.018954)
					(mid 59.211752 -428.965072)
					(end 59.15787 -428.942754)
				)
				(arc
					(start 58.21807 -428.942754)
					(mid 58.164188 -428.965072)
					(end 58.14187 -429.018954)
				)
			)
		)
	)
	(zone
		(layers "In1.Cu" "In2.Cu" "In3.Cu" "In5.Cu" "In7.Cu" "In8.Cu" "In9.Cu"
			"In14.Cu" "In16.Cu"
		)
		(hatch none 0.5)
		(connect_pads
			(clearance 0)
		)
		(min_thickness 0.25)
		(keepout
			(tracks not_allowed)
			(vias allowed)
			(pads allowed)
			(copperpour not_allowed)
			(footprints allowed)
		)
		(placement
			(enabled no)
			(sheetname "")
		)
		(fill yes
			(thermal_gap 0.5)
			(thermal_bridge_width 0.5)
			(island_removal_mode 0)
		)
		(polygon
			(pts
				(arc
					(start 87.141812 -431.560478)
					(mid 87.16413 -431.61436)
					(end 87.218012 -431.636678)
				)
				(arc
					(start 88.157812 -431.636678)
					(mid 88.211694 -431.61436)
					(end 88.234012 -431.560478)
				)
				(arc
					(start 88.234012 -429.018954)
					(mid 88.211694 -428.965072)
					(end 88.157812 -428.942754)
				)
				(arc
					(start 87.218012 -428.942754)
					(mid 87.16413 -428.965072)
					(end 87.141812 -429.018954)
				)
			)
		)
	)
	(zone
		(layers "In1.Cu" "In2.Cu" "In3.Cu" "In5.Cu" "In7.Cu" "In8.Cu" "In9.Cu"
			"In14.Cu" "In16.Cu"
		)
		(hatch none 0.5)
		(connect_pads
			(clearance 0)
		)
		(min_thickness 0.25)
		(keepout
			(tracks not_allowed)
			(vias allowed)
			(pads allowed)
			(copperpour not_allowed)
			(footprints allowed)
		)
		(placement
			(enabled no)
			(sheetname "")
		)
		(fill yes
			(thermal_gap 0.5)
			(thermal_bridge_width 0.5)
			(island_removal_mode 0)
		)
		(polygon
			(pts
				(arc
					(start 62.141862 -431.560478)
					(mid 62.16418 -431.61436)
					(end 62.218062 -431.636678)
				)
				(arc
					(start 63.157862 -431.636678)
					(mid 63.211744 -431.61436)
					(end 63.234062 -431.560478)
				)
				(arc
					(start 63.234062 -429.018954)
					(mid 63.211744 -428.965072)
					(end 63.157862 -428.942754)
				)
				(arc
					(start 62.218062 -428.942754)
					(mid 62.16418 -428.965072)
					(end 62.141862 -429.018954)
				)
			)
		)
	)
	(zone
		(layers "In1.Cu" "In2.Cu" "In3.Cu" "In5.Cu" "In7.Cu" "In8.Cu" "In9.Cu"
			"In14.Cu" "In16.Cu"
		)
		(hatch none 0.5)
		(connect_pads
			(clearance 0)
		)
		(min_thickness 0.25)
		(keepout
			(tracks not_allowed)
			(vias allowed)
			(pads allowed)
			(copperpour not_allowed)
			(footprints allowed)
		)
		(placement
			(enabled no)
			(sheetname "")
		)
		(fill yes
			(thermal_gap 0.5)
			(thermal_bridge_width 0.5)
			(island_removal_mode 0)
		)
		(polygon
			(pts
				(arc
					(start 64.141858 -432.560476)
					(mid 64.164176 -432.614358)
					(end 64.218058 -432.636676)
				)
				(arc
					(start 65.157858 -432.636676)
					(mid 65.21174 -432.614358)
					(end 65.234058 -432.560476)
				)
				(arc
					(start 65.234058 -430.018952)
					(mid 65.21174 -429.96507)
					(end 65.157858 -429.942752)
				)
				(arc
					(start 64.218058 -429.942752)
					(mid 64.164176 -429.96507)
					(end 64.141858 -430.018952)
				)
			)
		)
	)
	(zone
		(layers "In1.Cu" "In2.Cu" "In3.Cu" "In5.Cu" "In7.Cu" "In8.Cu" "In9.Cu"
			"In14.Cu" "In16.Cu"
		)
		(hatch none 0.5)
		(connect_pads
			(clearance 0)
		)
		(min_thickness 0.25)
		(keepout
			(tracks not_allowed)
			(vias allowed)
			(pads allowed)
			(copperpour not_allowed)
			(footprints allowed)
		)
		(placement
			(enabled no)
			(sheetname "")
		)
		(fill yes
			(thermal_gap 0.5)
			(thermal_bridge_width 0.5)
			(island_removal_mode 0)
		)
		(polygon
			(pts
				(arc
					(start 89.141808 -432.560476)
					(mid 89.164126 -432.614358)
					(end 89.218008 -432.636676)
				)
				(arc
					(start 90.157808 -432.636676)
					(mid 90.21169 -432.614358)
					(end 90.234008 -432.560476)
				)
				(arc
					(start 90.234008 -430.018952)
					(mid 90.21169 -429.96507)
					(end 90.157808 -429.942752)
				)
				(arc
					(start 89.218008 -429.942752)
					(mid 89.164126 -429.96507)
					(end 89.141808 -430.018952)
				)
			)
		)
	)
	(zone
		(layers "In1.Cu" "In2.Cu" "In3.Cu" "In5.Cu" "In7.Cu" "In8.Cu" "In9.Cu"
			"In14.Cu" "In16.Cu"
		)
		(hatch none 0.5)
		(connect_pads
			(clearance 0)
		)
		(min_thickness 0.25)
		(keepout
			(tracks not_allowed)
			(vias allowed)
			(pads allowed)
			(copperpour not_allowed)
			(footprints allowed)
		)
		(placement
			(enabled no)
			(sheetname "")
		)
		(fill yes
			(thermal_gap 0.5)
			(thermal_bridge_width 0.5)
			(island_removal_mode 0)
		)
		(polygon
			(pts
				(arc
					(start 85.141816 -432.560476)
					(mid 85.164134 -432.614358)
					(end 85.218016 -432.636676)
				)
				(arc
					(start 86.157816 -432.636676)
					(mid 86.211698 -432.614358)
					(end 86.234016 -432.560476)
				)
				(arc
					(start 86.234016 -430.018952)
					(mid 86.211698 -429.96507)
					(end 86.157816 -429.942752)
				)
				(arc
					(start 85.218016 -429.942752)
					(mid 85.164134 -429.96507)
					(end 85.141816 -430.018952)
				)
			)
		)
	)
	(zone
		(layers "In1.Cu" "In2.Cu" "In3.Cu" "In5.Cu" "In7.Cu" "In8.Cu" "In9.Cu"
			"In14.Cu" "In16.Cu"
		)
		(hatch none 0.5)
		(connect_pads
			(clearance 0)
		)
		(min_thickness 0.25)
		(keepout
			(tracks not_allowed)
			(vias allowed)
			(pads allowed)
			(copperpour not_allowed)
			(footprints allowed)
		)
		(placement
			(enabled no)
			(sheetname "")
		)
		(fill yes
			(thermal_gap 0.5)
			(thermal_bridge_width 0.5)
			(island_removal_mode 0)
		)
		(polygon
			(pts
				(arc
					(start 70.141846 -431.560478)
					(mid 70.164164 -431.61436)
					(end 70.218046 -431.636678)
				)
				(arc
					(start 71.157846 -431.636678)
					(mid 71.211728 -431.61436)
					(end 71.234046 -431.560478)
				)
				(arc
					(start 71.234046 -429.018954)
					(mid 71.211728 -428.965072)
					(end 71.157846 -428.942754)
				)
				(arc
					(start 70.218046 -428.942754)
					(mid 70.164164 -428.965072)
					(end 70.141846 -429.018954)
				)
			)
		)
	)
	(zone
		(layers "In1.Cu" "In2.Cu" "In3.Cu" "In5.Cu" "In7.Cu" "In8.Cu" "In9.Cu"
			"In14.Cu" "In16.Cu"
		)
		(hatch none 0.5)
		(connect_pads
			(clearance 0)
		)
		(min_thickness 0.25)
		(keepout
			(tracks not_allowed)
			(vias allowed)
			(pads allowed)
			(copperpour not_allowed)
			(footprints allowed)
		)
		(placement
			(enabled no)
			(sheetname "")
		)
		(fill yes
			(thermal_gap 0.5)
			(thermal_bridge_width 0.5)
			(island_removal_mode 0)
		)
		(polygon
			(pts
				(arc
					(start 83.14182 -431.560478)
					(mid 83.164138 -431.61436)
					(end 83.21802 -431.636678)
				)
				(arc
					(start 84.15782 -431.636678)
					(mid 84.211702 -431.61436)
					(end 84.23402 -431.560478)
				)
				(arc
					(start 84.23402 -429.018954)
					(mid 84.211702 -428.965072)
					(end 84.15782 -428.942754)
				)
				(arc
					(start 83.21802 -428.942754)
					(mid 83.164138 -428.965072)
					(end 83.14182 -429.018954)
				)
			)
		)
	)
	(zone
		(layers "In1.Cu" "In2.Cu" "In3.Cu" "In5.Cu" "In7.Cu" "In8.Cu" "In9.Cu"
			"In14.Cu" "In16.Cu"
		)
		(hatch none 0.5)
		(connect_pads
			(clearance 0)
		)
		(min_thickness 0.25)
		(keepout
			(tracks not_allowed)
			(vias allowed)
			(pads allowed)
			(copperpour not_allowed)
			(footprints allowed)
		)
		(placement
			(enabled no)
			(sheetname "")
		)
		(fill yes
			(thermal_gap 0.5)
			(thermal_bridge_width 0.5)
			(island_removal_mode 0)
		)
		(polygon
			(pts
				(arc
					(start 66.141854 -431.560478)
					(mid 66.164172 -431.61436)
					(end 66.218054 -431.636678)
				)
				(arc
					(start 67.157854 -431.636678)
					(mid 67.211736 -431.61436)
					(end 67.234054 -431.560478)
				)
				(arc
					(start 67.234054 -429.018954)
					(mid 67.211736 -428.965072)
					(end 67.157854 -428.942754)
				)
				(arc
					(start 66.218054 -428.942754)
					(mid 66.164172 -428.965072)
					(end 66.141854 -429.018954)
				)
			)
		)
	)
	(zone
		(layers "In1.Cu" "In2.Cu" "In3.Cu" "In5.Cu" "In7.Cu" "In8.Cu" "In9.Cu"
			"In16.Cu"
		)
		(hatch none 0.5)
		(connect_pads
			(clearance 0)
		)
		(min_thickness 0.25)
		(keepout
			(tracks not_allowed)
			(vias allowed)
			(pads allowed)
			(copperpour not_allowed)
			(footprints allowed)
		)
		(placement
			(enabled no)
			(sheetname "")
		)
		(fill yes
			(thermal_gap 0.5)
			(thermal_bridge_width 0.5)
			(island_removal_mode 0)
		)
		(polygon
			(pts
				(arc
					(start 148.241766 -436.160418)
					(mid 148.264084 -436.2143)
					(end 148.317966 -436.236618)
				)
				(arc
					(start 149.257766 -436.236618)
					(mid 149.311648 -436.2143)
					(end 149.333966 -436.160418)
				)
				(arc
					(start 149.333966 -433.618894)
					(mid 149.311648 -433.565012)
					(end 149.257766 -433.542694)
				)
				(arc
					(start 148.317966 -433.542694)
					(mid 148.264084 -433.565012)
					(end 148.241766 -433.618894)
				)
			)
		)
	)
	(zone
		(layers "In1.Cu" "In2.Cu" "In3.Cu" "In5.Cu" "In7.Cu" "In8.Cu" "In9.Cu"
			"In16.Cu"
		)
		(hatch none 0.5)
		(connect_pads
			(clearance 0)
		)
		(min_thickness 0.25)
		(keepout
			(tracks not_allowed)
			(vias allowed)
			(pads allowed)
			(copperpour not_allowed)
			(footprints allowed)
		)
		(placement
			(enabled no)
			(sheetname "")
		)
		(fill yes
			(thermal_gap 0.5)
			(thermal_bridge_width 0.5)
			(island_removal_mode 0)
		)
		(polygon
			(pts
				(arc
					(start 144.241774 -436.160418)
					(mid 144.264092 -436.2143)
					(end 144.317974 -436.236618)
				)
				(arc
					(start 145.257774 -436.236618)
					(mid 145.311656 -436.2143)
					(end 145.333974 -436.160418)
				)
				(arc
					(start 145.333974 -433.618894)
					(mid 145.311656 -433.565012)
					(end 145.257774 -433.542694)
				)
				(arc
					(start 144.317974 -433.542694)
					(mid 144.264092 -433.565012)
					(end 144.241774 -433.618894)
				)
			)
		)
	)
	(zone
		(layers "In1.Cu" "In2.Cu" "In3.Cu" "In5.Cu" "In7.Cu" "In8.Cu" "In9.Cu"
			"In16.Cu"
		)
		(hatch none 0.5)
		(connect_pads
			(clearance 0)
		)
		(min_thickness 0.25)
		(keepout
			(tracks not_allowed)
			(vias allowed)
			(pads allowed)
			(copperpour not_allowed)
			(footprints allowed)
		)
		(placement
			(enabled no)
			(sheetname "")
		)
		(fill yes
			(thermal_gap 0.5)
			(thermal_bridge_width 0.5)
			(island_removal_mode 0)
		)
		(polygon
			(pts
				(arc
					(start 127.241808 -436.160418)
					(mid 127.264126 -436.2143)
					(end 127.318008 -436.236618)
				)
				(arc
					(start 128.257808 -436.236618)
					(mid 128.31169 -436.2143)
					(end 128.334008 -436.160418)
				)
				(arc
					(start 128.334008 -433.618894)
					(mid 128.31169 -433.565012)
					(end 128.257808 -433.542694)
				)
				(arc
					(start 127.318008 -433.542694)
					(mid 127.264126 -433.565012)
					(end 127.241808 -433.618894)
				)
			)
		)
	)
	(zone
		(layers "In1.Cu" "In2.Cu" "In3.Cu" "In5.Cu" "In7.Cu" "In8.Cu" "In9.Cu"
			"In16.Cu"
		)
		(hatch none 0.5)
		(connect_pads
			(clearance 0)
		)
		(min_thickness 0.25)
		(keepout
			(tracks not_allowed)
			(vias allowed)
			(pads allowed)
			(copperpour not_allowed)
			(footprints allowed)
		)
		(placement
			(enabled no)
			(sheetname "")
		)
		(fill yes
			(thermal_gap 0.5)
			(thermal_bridge_width 0.5)
			(island_removal_mode 0)
		)
		(polygon
			(pts
				(arc
					(start 133.241796 -431.560478)
					(mid 133.264114 -431.61436)
					(end 133.317996 -431.636678)
				)
				(arc
					(start 134.257796 -431.636678)
					(mid 134.311678 -431.61436)
					(end 134.333996 -431.560478)
				)
				(arc
					(start 134.333996 -429.018954)
					(mid 134.311678 -428.965072)
					(end 134.257796 -428.942754)
				)
				(arc
					(start 133.317996 -428.942754)
					(mid 133.264114 -428.965072)
					(end 133.241796 -429.018954)
				)
			)
		)
	)
	(zone
		(layers "In1.Cu" "In2.Cu" "In3.Cu" "In5.Cu" "In7.Cu" "In8.Cu" "In9.Cu"
			"In16.Cu"
		)
		(hatch none 0.5)
		(connect_pads
			(clearance 0)
		)
		(min_thickness 0.25)
		(keepout
			(tracks not_allowed)
			(vias allowed)
			(pads allowed)
			(copperpour not_allowed)
			(footprints allowed)
		)
		(placement
			(enabled no)
			(sheetname "")
		)
		(fill yes
			(thermal_gap 0.5)
			(thermal_bridge_width 0.5)
			(island_removal_mode 0)
		)
		(polygon
			(pts
				(arc
					(start 137.241788 -431.560478)
					(mid 137.264106 -431.61436)
					(end 137.317988 -431.636678)
				)
				(arc
					(start 138.257788 -431.636678)
					(mid 138.31167 -431.61436)
					(end 138.333988 -431.560478)
				)
				(arc
					(start 138.333988 -429.018954)
					(mid 138.31167 -428.965072)
					(end 138.257788 -428.942754)
				)
				(arc
					(start 137.317988 -428.942754)
					(mid 137.264106 -428.965072)
					(end 137.241788 -429.018954)
				)
			)
		)
	)
	(zone
		(layers "In1.Cu" "In2.Cu" "In3.Cu" "In5.Cu" "In7.Cu" "In8.Cu" "In9.Cu"
			"In16.Cu"
		)
		(hatch none 0.5)
		(connect_pads
			(clearance 0)
		)
		(min_thickness 0.25)
		(keepout
			(tracks not_allowed)
			(vias allowed)
			(pads allowed)
			(copperpour not_allowed)
			(footprints allowed)
		)
		(placement
			(enabled no)
			(sheetname "")
		)
		(fill yes
			(thermal_gap 0.5)
			(thermal_bridge_width 0.5)
			(island_removal_mode 0)
		)
		(polygon
			(pts
				(arc
					(start 139.241784 -432.560476)
					(mid 139.264102 -432.614358)
					(end 139.317984 -432.636676)
				)
				(arc
					(start 140.257784 -432.636676)
					(mid 140.311666 -432.614358)
					(end 140.333984 -432.560476)
				)
				(arc
					(start 140.333984 -430.018952)
					(mid 140.311666 -429.96507)
					(end 140.257784 -429.942752)
				)
				(arc
					(start 139.317984 -429.942752)
					(mid 139.264102 -429.96507)
					(end 139.241784 -430.018952)
				)
			)
		)
	)
	(zone
		(layers "In1.Cu" "In2.Cu" "In3.Cu" "In5.Cu" "In7.Cu" "In8.Cu" "In9.Cu"
			"In16.Cu"
		)
		(hatch none 0.5)
		(connect_pads
			(clearance 0)
		)
		(min_thickness 0.25)
		(keepout
			(tracks not_allowed)
			(vias allowed)
			(pads allowed)
			(copperpour not_allowed)
			(footprints allowed)
		)
		(placement
			(enabled no)
			(sheetname "")
		)
		(fill yes
			(thermal_gap 0.5)
			(thermal_bridge_width 0.5)
			(island_removal_mode 0)
		)
		(polygon
			(pts
				(arc
					(start 139.241784 -436.160418)
					(mid 139.264102 -436.2143)
					(end 139.317984 -436.236618)
				)
				(arc
					(start 140.257784 -436.236618)
					(mid 140.311666 -436.2143)
					(end 140.333984 -436.160418)
				)
				(arc
					(start 140.333984 -433.618894)
					(mid 140.311666 -433.565012)
					(end 140.257784 -433.542694)
				)
				(arc
					(start 139.317984 -433.542694)
					(mid 139.264102 -433.565012)
					(end 139.241784 -433.618894)
				)
			)
		)
	)
	(zone
		(layers "In1.Cu" "In2.Cu" "In3.Cu" "In5.Cu" "In7.Cu" "In8.Cu" "In9.Cu"
			"In16.Cu"
		)
		(hatch none 0.5)
		(connect_pads
			(clearance 0)
		)
		(min_thickness 0.25)
		(keepout
			(tracks not_allowed)
			(vias allowed)
			(pads allowed)
			(copperpour not_allowed)
			(footprints allowed)
		)
		(placement
			(enabled no)
			(sheetname "")
		)
		(fill yes
			(thermal_gap 0.5)
			(thermal_bridge_width 0.5)
			(island_removal_mode 0)
		)
		(polygon
			(pts
				(arc
					(start 129.241804 -431.560478)
					(mid 129.264122 -431.61436)
					(end 129.318004 -431.636678)
				)
				(arc
					(start 130.257804 -431.636678)
					(mid 130.311686 -431.61436)
					(end 130.334004 -431.560478)
				)
				(arc
					(start 130.334004 -429.018954)
					(mid 130.311686 -428.965072)
					(end 130.257804 -428.942754)
				)
				(arc
					(start 129.318004 -428.942754)
					(mid 129.264122 -428.965072)
					(end 129.241804 -429.018954)
				)
			)
		)
	)
	(zone
		(layers "In1.Cu" "In2.Cu" "In3.Cu" "In5.Cu" "In7.Cu" "In8.Cu" "In9.Cu"
			"In16.Cu"
		)
		(hatch none 0.5)
		(connect_pads
			(clearance 0)
		)
		(min_thickness 0.25)
		(keepout
			(tracks not_allowed)
			(vias allowed)
			(pads allowed)
			(copperpour not_allowed)
			(footprints allowed)
		)
		(placement
			(enabled no)
			(sheetname "")
		)
		(fill yes
			(thermal_gap 0.5)
			(thermal_bridge_width 0.5)
			(island_removal_mode 0)
		)
		(polygon
			(pts
				(arc
					(start 127.241808 -432.560476)
					(mid 127.264126 -432.614358)
					(end 127.318008 -432.636676)
				)
				(arc
					(start 128.257808 -432.636676)
					(mid 128.31169 -432.614358)
					(end 128.334008 -432.560476)
				)
				(arc
					(start 128.334008 -430.018952)
					(mid 128.31169 -429.96507)
					(end 128.257808 -429.942752)
				)
				(arc
					(start 127.318008 -429.942752)
					(mid 127.264126 -429.96507)
					(end 127.241808 -430.018952)
				)
			)
		)
	)
	(zone
		(layers "In1.Cu" "In2.Cu" "In3.Cu" "In5.Cu" "In7.Cu" "In8.Cu" "In9.Cu"
			"In16.Cu"
		)
		(hatch none 0.5)
		(connect_pads
			(clearance 0)
		)
		(min_thickness 0.25)
		(keepout
			(tracks not_allowed)
			(vias allowed)
			(pads allowed)
			(copperpour not_allowed)
			(footprints allowed)
		)
		(placement
			(enabled no)
			(sheetname "")
		)
		(fill yes
			(thermal_gap 0.5)
			(thermal_bridge_width 0.5)
			(island_removal_mode 0)
		)
		(polygon
			(pts
				(arc
					(start 131.2418 -432.560476)
					(mid 131.264118 -432.614358)
					(end 131.318 -432.636676)
				)
				(arc
					(start 132.2578 -432.636676)
					(mid 132.311682 -432.614358)
					(end 132.334 -432.560476)
				)
				(arc
					(start 132.334 -430.018952)
					(mid 132.311682 -429.96507)
					(end 132.2578 -429.942752)
				)
				(arc
					(start 131.318 -429.942752)
					(mid 131.264118 -429.96507)
					(end 131.2418 -430.018952)
				)
			)
		)
	)
	(zone
		(layers "In1.Cu" "In2.Cu" "In3.Cu" "In5.Cu" "In7.Cu" "In8.Cu" "In9.Cu"
			"In16.Cu"
		)
		(hatch none 0.5)
		(connect_pads
			(clearance 0)
		)
		(min_thickness 0.25)
		(keepout
			(tracks not_allowed)
			(vias allowed)
			(pads allowed)
			(copperpour not_allowed)
			(footprints allowed)
		)
		(placement
			(enabled no)
			(sheetname "")
		)
		(fill yes
			(thermal_gap 0.5)
			(thermal_bridge_width 0.5)
			(island_removal_mode 0)
		)
		(polygon
			(pts
				(arc
					(start 154.241754 -435.16042)
					(mid 154.264072 -435.214302)
					(end 154.317954 -435.23662)
				)
				(arc
					(start 155.257754 -435.23662)
					(mid 155.311636 -435.214302)
					(end 155.333954 -435.16042)
				)
				(arc
					(start 155.333954 -432.618896)
					(mid 155.311636 -432.565014)
					(end 155.257754 -432.542696)
				)
				(arc
					(start 154.317954 -432.542696)
					(mid 154.264072 -432.565014)
					(end 154.241754 -432.618896)
				)
			)
		)
	)
	(zone
		(layers "In1.Cu" "In2.Cu" "In3.Cu" "In5.Cu" "In7.Cu" "In8.Cu" "In9.Cu"
			"In16.Cu"
		)
		(hatch none 0.5)
		(connect_pads
			(clearance 0)
		)
		(min_thickness 0.25)
		(keepout
			(tracks not_allowed)
			(vias allowed)
			(pads allowed)
			(copperpour not_allowed)
			(footprints allowed)
		)
		(placement
			(enabled no)
			(sheetname "")
		)
		(fill yes
			(thermal_gap 0.5)
			(thermal_bridge_width 0.5)
			(island_removal_mode 0)
		)
		(polygon
			(pts
				(arc
					(start 135.241792 -432.560476)
					(mid 135.26411 -432.614358)
					(end 135.317992 -432.636676)
				)
				(arc
					(start 136.257792 -432.636676)
					(mid 136.311674 -432.614358)
					(end 136.333992 -432.560476)
				)
				(arc
					(start 136.333992 -430.018952)
					(mid 136.311674 -429.96507)
					(end 136.257792 -429.942752)
				)
				(arc
					(start 135.317992 -429.942752)
					(mid 135.26411 -429.96507)
					(end 135.241792 -430.018952)
				)
			)
		)
	)
	(zone
		(layers "In1.Cu" "In2.Cu" "In3.Cu" "In5.Cu" "In7.Cu" "In8.Cu" "In9.Cu"
			"In16.Cu"
		)
		(hatch none 0.5)
		(connect_pads
			(clearance 0)
		)
		(min_thickness 0.25)
		(keepout
			(tracks not_allowed)
			(vias allowed)
			(pads allowed)
			(copperpour not_allowed)
			(footprints allowed)
		)
		(placement
			(enabled no)
			(sheetname "")
		)
		(fill yes
			(thermal_gap 0.5)
			(thermal_bridge_width 0.5)
			(island_removal_mode 0)
		)
		(polygon
			(pts
				(arc
					(start 131.2418 -436.160418)
					(mid 131.264118 -436.2143)
					(end 131.318 -436.236618)
				)
				(arc
					(start 132.2578 -436.236618)
					(mid 132.311682 -436.2143)
					(end 132.334 -436.160418)
				)
				(arc
					(start 132.334 -433.618894)
					(mid 132.311682 -433.565012)
					(end 132.2578 -433.542694)
				)
				(arc
					(start 131.318 -433.542694)
					(mid 131.264118 -433.565012)
					(end 131.2418 -433.618894)
				)
			)
		)
	)
	(zone
		(layers "In1.Cu" "In2.Cu" "In3.Cu" "In5.Cu" "In7.Cu" "In8.Cu" "In9.Cu"
			"In16.Cu"
		)
		(hatch none 0.5)
		(connect_pads
			(clearance 0)
		)
		(min_thickness 0.25)
		(keepout
			(tracks not_allowed)
			(vias allowed)
			(pads allowed)
			(copperpour not_allowed)
			(footprints allowed)
		)
		(placement
			(enabled no)
			(sheetname "")
		)
		(fill yes
			(thermal_gap 0.5)
			(thermal_bridge_width 0.5)
			(island_removal_mode 0)
		)
		(polygon
			(pts
				(arc
					(start 125.241812 -431.560478)
					(mid 125.26413 -431.61436)
					(end 125.318012 -431.636678)
				)
				(arc
					(start 126.257812 -431.636678)
					(mid 126.311694 -431.61436)
					(end 126.334012 -431.560478)
				)
				(arc
					(start 126.334012 -429.018954)
					(mid 126.311694 -428.965072)
					(end 126.257812 -428.942754)
				)
				(arc
					(start 125.318012 -428.942754)
					(mid 125.26413 -428.965072)
					(end 125.241812 -429.018954)
				)
			)
		)
	)
	(zone
		(layers "In1.Cu" "In2.Cu" "In3.Cu" "In5.Cu" "In7.Cu" "In8.Cu" "In9.Cu"
			"In16.Cu"
		)
		(hatch none 0.5)
		(connect_pads
			(clearance 0)
		)
		(min_thickness 0.25)
		(keepout
			(tracks not_allowed)
			(vias allowed)
			(pads allowed)
			(copperpour not_allowed)
			(footprints allowed)
		)
		(placement
			(enabled no)
			(sheetname "")
		)
		(fill yes
			(thermal_gap 0.5)
			(thermal_bridge_width 0.5)
			(island_removal_mode 0)
		)
		(polygon
			(pts
				(arc
					(start 135.241792 -436.160418)
					(mid 135.26411 -436.2143)
					(end 135.317992 -436.236618)
				)
				(arc
					(start 136.257792 -436.236618)
					(mid 136.311674 -436.2143)
					(end 136.333992 -436.160418)
				)
				(arc
					(start 136.333992 -433.618894)
					(mid 136.311674 -433.565012)
					(end 136.257792 -433.542694)
				)
				(arc
					(start 135.317992 -433.542694)
					(mid 135.26411 -433.565012)
					(end 135.241792 -433.618894)
				)
			)
		)
	)
	(zone
		(layers "In1.Cu" "In2.Cu" "In3.Cu" "In5.Cu" "In7.Cu" "In8.Cu" "In9.Cu"
			"In16.Cu"
		)
		(hatch none 0.5)
		(connect_pads
			(clearance 0)
		)
		(min_thickness 0.25)
		(keepout
			(tracks not_allowed)
			(vias allowed)
			(pads allowed)
			(copperpour not_allowed)
			(footprints allowed)
		)
		(placement
			(enabled no)
			(sheetname "")
		)
		(fill yes
			(thermal_gap 0.5)
			(thermal_bridge_width 0.5)
			(island_removal_mode 0)
		)
		(polygon
			(pts
				(arc
					(start 129.241804 -435.16042)
					(mid 129.264122 -435.214302)
					(end 129.318004 -435.23662)
				)
				(arc
					(start 130.257804 -435.23662)
					(mid 130.311686 -435.214302)
					(end 130.334004 -435.16042)
				)
				(arc
					(start 130.334004 -432.618896)
					(mid 130.311686 -432.565014)
					(end 130.257804 -432.542696)
				)
				(arc
					(start 129.318004 -432.542696)
					(mid 129.264122 -432.565014)
					(end 129.241804 -432.618896)
				)
			)
		)
	)
	(zone
		(layers "In1.Cu" "In2.Cu" "In3.Cu" "In5.Cu" "In7.Cu" "In8.Cu" "In9.Cu"
			"In16.Cu"
		)
		(hatch none 0.5)
		(connect_pads
			(clearance 0)
		)
		(min_thickness 0.25)
		(keepout
			(tracks not_allowed)
			(vias allowed)
			(pads allowed)
			(copperpour not_allowed)
			(footprints allowed)
		)
		(placement
			(enabled no)
			(sheetname "")
		)
		(fill yes
			(thermal_gap 0.5)
			(thermal_bridge_width 0.5)
			(island_removal_mode 0)
		)
		(polygon
			(pts
				(arc
					(start 156.24175 -436.160418)
					(mid 156.264068 -436.2143)
					(end 156.31795 -436.236618)
				)
				(arc
					(start 157.25775 -436.236618)
					(mid 157.311632 -436.2143)
					(end 157.33395 -436.160418)
				)
				(arc
					(start 157.33395 -433.618894)
					(mid 157.311632 -433.565012)
					(end 157.25775 -433.542694)
				)
				(arc
					(start 156.31795 -433.542694)
					(mid 156.264068 -433.565012)
					(end 156.24175 -433.618894)
				)
			)
		)
	)
	(zone
		(layers "In1.Cu" "In2.Cu" "In3.Cu" "In5.Cu" "In7.Cu" "In8.Cu" "In9.Cu"
			"In16.Cu"
		)
		(hatch none 0.5)
		(connect_pads
			(clearance 0)
		)
		(min_thickness 0.25)
		(keepout
			(tracks not_allowed)
			(vias allowed)
			(pads allowed)
			(copperpour not_allowed)
			(footprints allowed)
		)
		(placement
			(enabled no)
			(sheetname "")
		)
		(fill yes
			(thermal_gap 0.5)
			(thermal_bridge_width 0.5)
			(island_removal_mode 0)
		)
		(polygon
			(pts
				(arc
					(start 142.241778 -435.16042)
					(mid 142.264096 -435.214302)
					(end 142.317978 -435.23662)
				)
				(arc
					(start 143.257778 -435.23662)
					(mid 143.31166 -435.214302)
					(end 143.333978 -435.16042)
				)
				(arc
					(start 143.333978 -432.618896)
					(mid 143.31166 -432.565014)
					(end 143.257778 -432.542696)
				)
				(arc
					(start 142.317978 -432.542696)
					(mid 142.264096 -432.565014)
					(end 142.241778 -432.618896)
				)
			)
		)
	)
	(zone
		(layers "In1.Cu" "In2.Cu" "In3.Cu" "In5.Cu" "In7.Cu" "In8.Cu" "In9.Cu"
			"In16.Cu"
		)
		(hatch none 0.5)
		(connect_pads
			(clearance 0)
		)
		(min_thickness 0.25)
		(keepout
			(tracks not_allowed)
			(vias allowed)
			(pads allowed)
			(copperpour not_allowed)
			(footprints allowed)
		)
		(placement
			(enabled no)
			(sheetname "")
		)
		(fill yes
			(thermal_gap 0.5)
			(thermal_bridge_width 0.5)
			(island_removal_mode 0)
		)
		(polygon
			(pts
				(arc
					(start 125.241812 -435.16042)
					(mid 125.26413 -435.214302)
					(end 125.318012 -435.23662)
				)
				(arc
					(start 126.257812 -435.23662)
					(mid 126.311694 -435.214302)
					(end 126.334012 -435.16042)
				)
				(arc
					(start 126.334012 -432.618896)
					(mid 126.311694 -432.565014)
					(end 126.257812 -432.542696)
				)
				(arc
					(start 125.318012 -432.542696)
					(mid 125.26413 -432.565014)
					(end 125.241812 -432.618896)
				)
			)
		)
	)
	(zone
		(layers "In1.Cu" "In2.Cu" "In3.Cu" "In5.Cu" "In7.Cu" "In8.Cu" "In9.Cu"
			"In16.Cu"
		)
		(hatch none 0.5)
		(connect_pads
			(clearance 0)
		)
		(min_thickness 0.25)
		(keepout
			(tracks not_allowed)
			(vias allowed)
			(pads allowed)
			(copperpour not_allowed)
			(footprints allowed)
		)
		(placement
			(enabled no)
			(sheetname "")
		)
		(fill yes
			(thermal_gap 0.5)
			(thermal_bridge_width 0.5)
			(island_removal_mode 0)
		)
		(polygon
			(pts
				(arc
					(start 137.241788 -435.16042)
					(mid 137.264106 -435.214302)
					(end 137.317988 -435.23662)
				)
				(arc
					(start 138.257788 -435.23662)
					(mid 138.31167 -435.214302)
					(end 138.333988 -435.16042)
				)
				(arc
					(start 138.333988 -432.618896)
					(mid 138.31167 -432.565014)
					(end 138.257788 -432.542696)
				)
				(arc
					(start 137.317988 -432.542696)
					(mid 137.264106 -432.565014)
					(end 137.241788 -432.618896)
				)
			)
		)
	)
	(zone
		(layers "In1.Cu" "In2.Cu" "In3.Cu" "In5.Cu" "In7.Cu" "In8.Cu" "In9.Cu"
			"In16.Cu"
		)
		(hatch none 0.5)
		(connect_pads
			(clearance 0)
		)
		(min_thickness 0.25)
		(keepout
			(tracks not_allowed)
			(vias allowed)
			(pads allowed)
			(copperpour not_allowed)
			(footprints allowed)
		)
		(placement
			(enabled no)
			(sheetname "")
		)
		(fill yes
			(thermal_gap 0.5)
			(thermal_bridge_width 0.5)
			(island_removal_mode 0)
		)
		(polygon
			(pts
				(arc
					(start 133.241796 -435.16042)
					(mid 133.264114 -435.214302)
					(end 133.317996 -435.23662)
				)
				(arc
					(start 134.257796 -435.23662)
					(mid 134.311678 -435.214302)
					(end 134.333996 -435.16042)
				)
				(arc
					(start 134.333996 -432.618896)
					(mid 134.311678 -432.565014)
					(end 134.257796 -432.542696)
				)
				(arc
					(start 133.317996 -432.542696)
					(mid 133.264114 -432.565014)
					(end 133.241796 -432.618896)
				)
			)
		)
	)
	(zone
		(layers "In1.Cu" "In2.Cu" "In3.Cu" "In5.Cu" "In7.Cu" "In8.Cu" "In9.Cu"
			"In16.Cu"
		)
		(hatch none 0.5)
		(connect_pads
			(clearance 0)
		)
		(min_thickness 0.25)
		(keepout
			(tracks not_allowed)
			(vias allowed)
			(pads allowed)
			(copperpour not_allowed)
			(footprints allowed)
		)
		(placement
			(enabled no)
			(sheetname "")
		)
		(fill yes
			(thermal_gap 0.5)
			(thermal_bridge_width 0.5)
			(island_removal_mode 0)
		)
		(polygon
			(pts
				(arc
					(start 152.241758 -436.160418)
					(mid 152.264076 -436.2143)
					(end 152.317958 -436.236618)
				)
				(arc
					(start 153.257758 -436.236618)
					(mid 153.31164 -436.2143)
					(end 153.333958 -436.160418)
				)
				(arc
					(start 153.333958 -433.618894)
					(mid 153.31164 -433.565012)
					(end 153.257758 -433.542694)
				)
				(arc
					(start 152.317958 -433.542694)
					(mid 152.264076 -433.565012)
					(end 152.241758 -433.618894)
				)
			)
		)
	)
	(zone
		(layers "In1.Cu" "In2.Cu" "In3.Cu" "In5.Cu" "In7.Cu" "In8.Cu" "In9.Cu"
			"In16.Cu"
		)
		(hatch none 0.5)
		(connect_pads
			(clearance 0)
		)
		(min_thickness 0.25)
		(keepout
			(tracks not_allowed)
			(vias allowed)
			(pads allowed)
			(copperpour not_allowed)
			(footprints allowed)
		)
		(placement
			(enabled no)
			(sheetname "")
		)
		(fill yes
			(thermal_gap 0.5)
			(thermal_bridge_width 0.5)
			(island_removal_mode 0)
		)
		(polygon
			(pts
				(arc
					(start 150.241762 -435.16042)
					(mid 150.26408 -435.214302)
					(end 150.317962 -435.23662)
				)
				(arc
					(start 151.257762 -435.23662)
					(mid 151.311644 -435.214302)
					(end 151.333962 -435.16042)
				)
				(arc
					(start 151.333962 -432.618896)
					(mid 151.311644 -432.565014)
					(end 151.257762 -432.542696)
				)
				(arc
					(start 150.317962 -432.542696)
					(mid 150.26408 -432.565014)
					(end 150.241762 -432.618896)
				)
			)
		)
	)
	(zone
		(layers "In1.Cu" "In2.Cu" "In3.Cu" "In5.Cu" "In7.Cu" "In8.Cu" "In9.Cu"
			"In16.Cu"
		)
		(hatch none 0.5)
		(connect_pads
			(clearance 0)
		)
		(min_thickness 0.25)
		(keepout
			(tracks not_allowed)
			(vias allowed)
			(pads allowed)
			(copperpour not_allowed)
			(footprints allowed)
		)
		(placement
			(enabled no)
			(sheetname "")
		)
		(fill yes
			(thermal_gap 0.5)
			(thermal_bridge_width 0.5)
			(island_removal_mode 0)
		)
		(polygon
			(pts
				(arc
					(start 146.24177 -435.16042)
					(mid 146.264088 -435.214302)
					(end 146.31797 -435.23662)
				)
				(arc
					(start 147.25777 -435.23662)
					(mid 147.311652 -435.214302)
					(end 147.33397 -435.16042)
				)
				(arc
					(start 147.33397 -432.618896)
					(mid 147.311652 -432.565014)
					(end 147.25777 -432.542696)
				)
				(arc
					(start 146.31797 -432.542696)
					(mid 146.264088 -432.565014)
					(end 146.24177 -432.618896)
				)
			)
		)
	)
	(zone
		(layers "In1.Cu" "In2.Cu" "In3.Cu" "In7.Cu" "In8.Cu" "In9.Cu" "In10.Cu"
			"In16.Cu"
		)
		(hatch none 0.5)
		(connect_pads
			(clearance 0)
		)
		(min_thickness 0.25)
		(keepout
			(tracks not_allowed)
			(vias allowed)
			(pads allowed)
			(copperpour not_allowed)
			(footprints allowed)
		)
		(placement
			(enabled no)
			(sheetname "")
		)
		(fill yes
			(thermal_gap 0.5)
			(thermal_bridge_width 0.5)
			(island_removal_mode 0)
		)
		(polygon
			(pts
				(arc
					(start 68.14185 -436.160418)
					(mid 68.164168 -436.2143)
					(end 68.21805 -436.236618)
				)
				(arc
					(start 69.15785 -436.236618)
					(mid 69.211732 -436.2143)
					(end 69.23405 -436.160418)
				)
				(arc
					(start 69.23405 -433.618894)
					(mid 69.211732 -433.565012)
					(end 69.15785 -433.542694)
				)
				(arc
					(start 68.21805 -433.542694)
					(mid 68.164168 -433.565012)
					(end 68.14185 -433.618894)
				)
			)
		)
	)
	(zone
		(layers "In1.Cu" "In2.Cu" "In3.Cu" "In7.Cu" "In8.Cu" "In9.Cu" "In10.Cu"
			"In16.Cu"
		)
		(hatch none 0.5)
		(connect_pads
			(clearance 0)
		)
		(min_thickness 0.25)
		(keepout
			(tracks not_allowed)
			(vias allowed)
			(pads allowed)
			(copperpour not_allowed)
			(footprints allowed)
		)
		(placement
			(enabled no)
			(sheetname "")
		)
		(fill yes
			(thermal_gap 0.5)
			(thermal_bridge_width 0.5)
			(island_removal_mode 0)
		)
		(polygon
			(pts
				(arc
					(start 83.14182 -435.16042)
					(mid 83.164138 -435.214302)
					(end 83.21802 -435.23662)
				)
				(arc
					(start 84.15782 -435.23662)
					(mid 84.211702 -435.214302)
					(end 84.23402 -435.16042)
				)
				(arc
					(start 84.23402 -432.618896)
					(mid 84.211702 -432.565014)
					(end 84.15782 -432.542696)
				)
				(arc
					(start 83.21802 -432.542696)
					(mid 83.164138 -432.565014)
					(end 83.14182 -432.618896)
				)
			)
		)
	)
	(zone
		(layers "In1.Cu" "In2.Cu" "In3.Cu" "In7.Cu" "In8.Cu" "In9.Cu" "In10.Cu"
			"In16.Cu"
		)
		(hatch none 0.5)
		(connect_pads
			(clearance 0)
		)
		(min_thickness 0.25)
		(keepout
			(tracks not_allowed)
			(vias allowed)
			(pads allowed)
			(copperpour not_allowed)
			(footprints allowed)
		)
		(placement
			(enabled no)
			(sheetname "")
		)
		(fill yes
			(thermal_gap 0.5)
			(thermal_bridge_width 0.5)
			(island_removal_mode 0)
		)
		(polygon
			(pts
				(arc
					(start 79.141828 -435.16042)
					(mid 79.164146 -435.214302)
					(end 79.218028 -435.23662)
				)
				(arc
					(start 80.157828 -435.23662)
					(mid 80.21171 -435.214302)
					(end 80.234028 -435.16042)
				)
				(arc
					(start 80.234028 -432.618896)
					(mid 80.21171 -432.565014)
					(end 80.157828 -432.542696)
				)
				(arc
					(start 79.218028 -432.542696)
					(mid 79.164146 -432.565014)
					(end 79.141828 -432.618896)
				)
			)
		)
	)
	(zone
		(layers "In1.Cu" "In2.Cu" "In3.Cu" "In7.Cu" "In8.Cu" "In9.Cu" "In10.Cu"
			"In16.Cu"
		)
		(hatch none 0.5)
		(connect_pads
			(clearance 0)
		)
		(min_thickness 0.25)
		(keepout
			(tracks not_allowed)
			(vias allowed)
			(pads allowed)
			(copperpour not_allowed)
			(footprints allowed)
		)
		(placement
			(enabled no)
			(sheetname "")
		)
		(fill yes
			(thermal_gap 0.5)
			(thermal_bridge_width 0.5)
			(island_removal_mode 0)
		)
		(polygon
			(pts
				(arc
					(start 66.141854 -435.16042)
					(mid 66.164172 -435.214302)
					(end 66.218054 -435.23662)
				)
				(arc
					(start 67.157854 -435.23662)
					(mid 67.211736 -435.214302)
					(end 67.234054 -435.16042)
				)
				(arc
					(start 67.234054 -432.618896)
					(mid 67.211736 -432.565014)
					(end 67.157854 -432.542696)
				)
				(arc
					(start 66.218054 -432.542696)
					(mid 66.164172 -432.565014)
					(end 66.141854 -432.618896)
				)
			)
		)
	)
	(zone
		(layers "In1.Cu" "In2.Cu" "In3.Cu" "In7.Cu" "In8.Cu" "In9.Cu" "In10.Cu"
			"In16.Cu"
		)
		(hatch none 0.5)
		(connect_pads
			(clearance 0)
		)
		(min_thickness 0.25)
		(keepout
			(tracks not_allowed)
			(vias allowed)
			(pads allowed)
			(copperpour not_allowed)
			(footprints allowed)
		)
		(placement
			(enabled no)
			(sheetname "")
		)
		(fill yes
			(thermal_gap 0.5)
			(thermal_bridge_width 0.5)
			(island_removal_mode 0)
		)
		(polygon
			(pts
				(arc
					(start 85.141816 -436.160418)
					(mid 85.164134 -436.2143)
					(end 85.218016 -436.236618)
				)
				(arc
					(start 86.157816 -436.236618)
					(mid 86.211698 -436.2143)
					(end 86.234016 -436.160418)
				)
				(arc
					(start 86.234016 -433.618894)
					(mid 86.211698 -433.565012)
					(end 86.157816 -433.542694)
				)
				(arc
					(start 85.218016 -433.542694)
					(mid 85.164134 -433.565012)
					(end 85.141816 -433.618894)
				)
			)
		)
	)
	(zone
		(layers "In1.Cu" "In2.Cu" "In3.Cu" "In7.Cu" "In8.Cu" "In9.Cu" "In10.Cu"
			"In16.Cu"
		)
		(hatch none 0.5)
		(connect_pads
			(clearance 0)
		)
		(min_thickness 0.25)
		(keepout
			(tracks not_allowed)
			(vias allowed)
			(pads allowed)
			(copperpour not_allowed)
			(footprints allowed)
		)
		(placement
			(enabled no)
			(sheetname "")
		)
		(fill yes
			(thermal_gap 0.5)
			(thermal_bridge_width 0.5)
			(island_removal_mode 0)
		)
		(polygon
			(pts
				(arc
					(start 81.141824 -436.160418)
					(mid 81.164142 -436.2143)
					(end 81.218024 -436.236618)
				)
				(arc
					(start 82.157824 -436.236618)
					(mid 82.211706 -436.2143)
					(end 82.234024 -436.160418)
				)
				(arc
					(start 82.234024 -433.618894)
					(mid 82.211706 -433.565012)
					(end 82.157824 -433.542694)
				)
				(arc
					(start 81.218024 -433.542694)
					(mid 81.164142 -433.565012)
					(end 81.141824 -433.618894)
				)
			)
		)
	)
	(zone
		(layers "In1.Cu" "In2.Cu" "In3.Cu" "In7.Cu" "In8.Cu" "In9.Cu" "In10.Cu"
			"In16.Cu"
		)
		(hatch none 0.5)
		(connect_pads
			(clearance 0)
		)
		(min_thickness 0.25)
		(keepout
			(tracks not_allowed)
			(vias allowed)
			(pads allowed)
			(copperpour not_allowed)
			(footprints allowed)
		)
		(placement
			(enabled no)
			(sheetname "")
		)
		(fill yes
			(thermal_gap 0.5)
			(thermal_bridge_width 0.5)
			(island_removal_mode 0)
		)
		(polygon
			(pts
				(arc
					(start 62.141862 -435.16042)
					(mid 62.16418 -435.214302)
					(end 62.218062 -435.23662)
				)
				(arc
					(start 63.157862 -435.23662)
					(mid 63.211744 -435.214302)
					(end 63.234062 -435.16042)
				)
				(arc
					(start 63.234062 -432.618896)
					(mid 63.211744 -432.565014)
					(end 63.157862 -432.542696)
				)
				(arc
					(start 62.218062 -432.542696)
					(mid 62.16418 -432.565014)
					(end 62.141862 -432.618896)
				)
			)
		)
	)
	(zone
		(layers "In1.Cu" "In2.Cu" "In3.Cu" "In7.Cu" "In8.Cu" "In9.Cu" "In10.Cu"
			"In16.Cu"
		)
		(hatch none 0.5)
		(connect_pads
			(clearance 0)
		)
		(min_thickness 0.25)
		(keepout
			(tracks not_allowed)
			(vias allowed)
			(pads allowed)
			(copperpour not_allowed)
			(footprints allowed)
		)
		(placement
			(enabled no)
			(sheetname "")
		)
		(fill yes
			(thermal_gap 0.5)
			(thermal_bridge_width 0.5)
			(island_removal_mode 0)
		)
		(polygon
			(pts
				(arc
					(start 64.141858 -436.160418)
					(mid 64.164176 -436.2143)
					(end 64.218058 -436.236618)
				)
				(arc
					(start 65.157858 -436.236618)
					(mid 65.21174 -436.2143)
					(end 65.234058 -436.160418)
				)
				(arc
					(start 65.234058 -433.618894)
					(mid 65.21174 -433.565012)
					(end 65.157858 -433.542694)
				)
				(arc
					(start 64.218058 -433.542694)
					(mid 64.164176 -433.565012)
					(end 64.141858 -433.618894)
				)
			)
		)
	)
	(zone
		(layers "In1.Cu" "In2.Cu" "In3.Cu" "In7.Cu" "In8.Cu" "In9.Cu" "In10.Cu"
			"In16.Cu"
		)
		(hatch none 0.5)
		(connect_pads
			(clearance 0)
		)
		(min_thickness 0.25)
		(keepout
			(tracks not_allowed)
			(vias allowed)
			(pads allowed)
			(copperpour not_allowed)
			(footprints allowed)
		)
		(placement
			(enabled no)
			(sheetname "")
		)
		(fill yes
			(thermal_gap 0.5)
			(thermal_bridge_width 0.5)
			(island_removal_mode 0)
		)
		(polygon
			(pts
				(arc
					(start 77.141832 -436.160418)
					(mid 77.16415 -436.2143)
					(end 77.218032 -436.236618)
				)
				(arc
					(start 78.157832 -436.236618)
					(mid 78.211714 -436.2143)
					(end 78.234032 -436.160418)
				)
				(arc
					(start 78.234032 -433.618894)
					(mid 78.211714 -433.565012)
					(end 78.157832 -433.542694)
				)
				(arc
					(start 77.218032 -433.542694)
					(mid 77.16415 -433.565012)
					(end 77.141832 -433.618894)
				)
			)
		)
	)
	(zone
		(layers "In1.Cu" "In2.Cu" "In3.Cu" "In7.Cu" "In8.Cu" "In9.Cu" "In10.Cu"
			"In16.Cu"
		)
		(hatch none 0.5)
		(connect_pads
			(clearance 0)
		)
		(min_thickness 0.25)
		(keepout
			(tracks not_allowed)
			(vias allowed)
			(pads allowed)
			(copperpour not_allowed)
			(footprints allowed)
		)
		(placement
			(enabled no)
			(sheetname "")
		)
		(fill yes
			(thermal_gap 0.5)
			(thermal_bridge_width 0.5)
			(island_removal_mode 0)
		)
		(polygon
			(pts
				(arc
					(start 72.141842 -436.160418)
					(mid 72.16416 -436.2143)
					(end 72.218042 -436.236618)
				)
				(arc
					(start 73.157842 -436.236618)
					(mid 73.211724 -436.2143)
					(end 73.234042 -436.160418)
				)
				(arc
					(start 73.234042 -433.618894)
					(mid 73.211724 -433.565012)
					(end 73.157842 -433.542694)
				)
				(arc
					(start 72.218042 -433.542694)
					(mid 72.16416 -433.565012)
					(end 72.141842 -433.618894)
				)
			)
		)
	)
	(zone
		(layers "In1.Cu" "In2.Cu" "In3.Cu" "In7.Cu" "In8.Cu" "In9.Cu" "In10.Cu"
			"In16.Cu"
		)
		(hatch none 0.5)
		(connect_pads
			(clearance 0)
		)
		(min_thickness 0.25)
		(keepout
			(tracks not_allowed)
			(vias allowed)
			(pads allowed)
			(copperpour not_allowed)
			(footprints allowed)
		)
		(placement
			(enabled no)
			(sheetname "")
		)
		(fill yes
			(thermal_gap 0.5)
			(thermal_bridge_width 0.5)
			(island_removal_mode 0)
		)
		(polygon
			(pts
				(arc
					(start 87.141812 -435.16042)
					(mid 87.16413 -435.214302)
					(end 87.218012 -435.23662)
				)
				(arc
					(start 88.157812 -435.23662)
					(mid 88.211694 -435.214302)
					(end 88.234012 -435.16042)
				)
				(arc
					(start 88.234012 -432.618896)
					(mid 88.211694 -432.565014)
					(end 88.157812 -432.542696)
				)
				(arc
					(start 87.218012 -432.542696)
					(mid 87.16413 -432.565014)
					(end 87.141812 -432.618896)
				)
			)
		)
	)
	(zone
		(layers "In1.Cu" "In2.Cu" "In3.Cu" "In7.Cu" "In8.Cu" "In9.Cu" "In10.Cu"
			"In16.Cu"
		)
		(hatch none 0.5)
		(connect_pads
			(clearance 0)
		)
		(min_thickness 0.25)
		(keepout
			(tracks not_allowed)
			(vias allowed)
			(pads allowed)
			(copperpour not_allowed)
			(footprints allowed)
		)
		(placement
			(enabled no)
			(sheetname "")
		)
		(fill yes
			(thermal_gap 0.5)
			(thermal_bridge_width 0.5)
			(island_removal_mode 0)
		)
		(polygon
			(pts
				(arc
					(start 75.141836 -435.16042)
					(mid 75.164154 -435.214302)
					(end 75.218036 -435.23662)
				)
				(arc
					(start 76.157836 -435.23662)
					(mid 76.211718 -435.214302)
					(end 76.234036 -435.16042)
				)
				(arc
					(start 76.234036 -432.618896)
					(mid 76.211718 -432.565014)
					(end 76.157836 -432.542696)
				)
				(arc
					(start 75.218036 -432.542696)
					(mid 75.164154 -432.565014)
					(end 75.141836 -432.618896)
				)
			)
		)
	)
	(zone
		(layers "In1.Cu" "In2.Cu" "In3.Cu" "In7.Cu" "In8.Cu" "In9.Cu" "In10.Cu"
			"In16.Cu"
		)
		(hatch none 0.5)
		(connect_pads
			(clearance 0)
		)
		(min_thickness 0.25)
		(keepout
			(tracks not_allowed)
			(vias allowed)
			(pads allowed)
			(copperpour not_allowed)
			(footprints allowed)
		)
		(placement
			(enabled no)
			(sheetname "")
		)
		(fill yes
			(thermal_gap 0.5)
			(thermal_bridge_width 0.5)
			(island_removal_mode 0)
		)
		(polygon
			(pts
				(arc
					(start 60.141866 -436.160418)
					(mid 60.164184 -436.2143)
					(end 60.218066 -436.236618)
				)
				(arc
					(start 61.157866 -436.236618)
					(mid 61.211748 -436.2143)
					(end 61.234066 -436.160418)
				)
				(arc
					(start 61.234066 -433.618894)
					(mid 61.211748 -433.565012)
					(end 61.157866 -433.542694)
				)
				(arc
					(start 60.218066 -433.542694)
					(mid 60.164184 -433.565012)
					(end 60.141866 -433.618894)
				)
			)
		)
	)
	(zone
		(layers "In1.Cu" "In2.Cu" "In3.Cu" "In7.Cu" "In8.Cu" "In9.Cu" "In10.Cu"
			"In16.Cu"
		)
		(hatch none 0.5)
		(connect_pads
			(clearance 0)
		)
		(min_thickness 0.25)
		(keepout
			(tracks not_allowed)
			(vias allowed)
			(pads allowed)
			(copperpour not_allowed)
			(footprints allowed)
		)
		(placement
			(enabled no)
			(sheetname "")
		)
		(fill yes
			(thermal_gap 0.5)
			(thermal_bridge_width 0.5)
			(island_removal_mode 0)
		)
		(polygon
			(pts
				(arc
					(start 58.14187 -435.16042)
					(mid 58.164188 -435.214302)
					(end 58.21807 -435.23662)
				)
				(arc
					(start 59.15787 -435.23662)
					(mid 59.211752 -435.214302)
					(end 59.23407 -435.16042)
				)
				(arc
					(start 59.23407 -432.618896)
					(mid 59.211752 -432.565014)
					(end 59.15787 -432.542696)
				)
				(arc
					(start 58.21807 -432.542696)
					(mid 58.164188 -432.565014)
					(end 58.14187 -432.618896)
				)
			)
		)
	)
	(zone
		(layers "In1.Cu" "In2.Cu" "In3.Cu" "In7.Cu" "In8.Cu" "In9.Cu" "In10.Cu"
			"In16.Cu"
		)
		(hatch none 0.5)
		(connect_pads
			(clearance 0)
		)
		(min_thickness 0.25)
		(keepout
			(tracks not_allowed)
			(vias allowed)
			(pads allowed)
			(copperpour not_allowed)
			(footprints allowed)
		)
		(placement
			(enabled no)
			(sheetname "")
		)
		(fill yes
			(thermal_gap 0.5)
			(thermal_bridge_width 0.5)
			(island_removal_mode 0)
		)
		(polygon
			(pts
				(arc
					(start 70.141846 -435.16042)
					(mid 70.164164 -435.214302)
					(end 70.218046 -435.23662)
				)
				(arc
					(start 71.157846 -435.23662)
					(mid 71.211728 -435.214302)
					(end 71.234046 -435.16042)
				)
				(arc
					(start 71.234046 -432.618896)
					(mid 71.211728 -432.565014)
					(end 71.157846 -432.542696)
				)
				(arc
					(start 70.218046 -432.542696)
					(mid 70.164164 -432.565014)
					(end 70.141846 -432.618896)
				)
			)
		)
	)
	(zone
		(layers "In1.Cu" "In2.Cu" "In3.Cu" "In7.Cu" "In8.Cu" "In9.Cu" "In10.Cu"
			"In16.Cu"
		)
		(hatch none 0.5)
		(connect_pads
			(clearance 0)
		)
		(min_thickness 0.25)
		(keepout
			(tracks not_allowed)
			(vias allowed)
			(pads allowed)
			(copperpour not_allowed)
			(footprints allowed)
		)
		(placement
			(enabled no)
			(sheetname "")
		)
		(fill yes
			(thermal_gap 0.5)
			(thermal_bridge_width 0.5)
			(island_removal_mode 0)
		)
		(polygon
			(pts
				(arc
					(start 89.141808 -436.160418)
					(mid 89.164126 -436.2143)
					(end 89.218008 -436.236618)
				)
				(arc
					(start 90.157808 -436.236618)
					(mid 90.21169 -436.2143)
					(end 90.234008 -436.160418)
				)
				(arc
					(start 90.234008 -433.618894)
					(mid 90.21169 -433.565012)
					(end 90.157808 -433.542694)
				)
				(arc
					(start 89.218008 -433.542694)
					(mid 89.164126 -433.565012)
					(end 89.141808 -433.618894)
				)
			)
		)
	)
	(zone
		(layers "In1.Cu" "In2.Cu" "In3.Cu" "In7.Cu" "In8.Cu" "In9.Cu" "In14.Cu"
			"In16.Cu"
		)
		(hatch none 0.5)
		(connect_pads
			(clearance 0)
		)
		(min_thickness 0.25)
		(keepout
			(tracks not_allowed)
			(vias allowed)
			(pads allowed)
			(copperpour not_allowed)
			(footprints allowed)
		)
		(placement
			(enabled no)
			(sheetname "")
		)
		(fill yes
			(thermal_gap 0.5)
			(thermal_bridge_width 0.5)
			(island_removal_mode 0)
		)
		(polygon
			(pts
				(arc
					(start 314.141866 -431.560478)
					(mid 314.164184 -431.61436)
					(end 314.218066 -431.636678)
				)
				(arc
					(start 315.157866 -431.636678)
					(mid 315.211748 -431.61436)
					(end 315.234066 -431.560478)
				)
				(arc
					(start 315.234066 -429.018954)
					(mid 315.211748 -428.965072)
					(end 315.157866 -428.942754)
				)
				(arc
					(start 314.218066 -428.942754)
					(mid 314.164184 -428.965072)
					(end 314.141866 -429.018954)
				)
			)
		)
	)
	(zone
		(layers "In1.Cu" "In2.Cu" "In3.Cu" "In7.Cu" "In8.Cu" "In9.Cu" "In14.Cu"
			"In16.Cu"
		)
		(hatch none 0.5)
		(connect_pads
			(clearance 0)
		)
		(min_thickness 0.25)
		(keepout
			(tracks not_allowed)
			(vias allowed)
			(pads allowed)
			(copperpour not_allowed)
			(footprints allowed)
		)
		(placement
			(enabled no)
			(sheetname "")
		)
		(fill yes
			(thermal_gap 0.5)
			(thermal_bridge_width 0.5)
			(island_removal_mode 0)
		)
		(polygon
			(pts
				(arc
					(start 316.141862 -432.560476)
					(mid 316.16418 -432.614358)
					(end 316.218062 -432.636676)
				)
				(arc
					(start 317.157862 -432.636676)
					(mid 317.211744 -432.614358)
					(end 317.234062 -432.560476)
				)
				(arc
					(start 317.234062 -430.018952)
					(mid 317.211744 -429.96507)
					(end 317.157862 -429.942752)
				)
				(arc
					(start 316.218062 -429.942752)
					(mid 316.16418 -429.96507)
					(end 316.141862 -430.018952)
				)
			)
		)
	)
	(zone
		(layers "In1.Cu" "In2.Cu" "In3.Cu" "In7.Cu" "In8.Cu" "In9.Cu" "In14.Cu"
			"In16.Cu"
		)
		(hatch none 0.5)
		(connect_pads
			(clearance 0)
		)
		(min_thickness 0.25)
		(keepout
			(tracks not_allowed)
			(vias allowed)
			(pads allowed)
			(copperpour not_allowed)
			(footprints allowed)
		)
		(placement
			(enabled no)
			(sheetname "")
		)
		(fill yes
			(thermal_gap 0.5)
			(thermal_bridge_width 0.5)
			(island_removal_mode 0)
		)
		(polygon
			(pts
				(arc
					(start 318.141858 -431.560478)
					(mid 318.164176 -431.61436)
					(end 318.218058 -431.636678)
				)
				(arc
					(start 319.157858 -431.636678)
					(mid 319.21174 -431.61436)
					(end 319.234058 -431.560478)
				)
				(arc
					(start 319.234058 -429.018954)
					(mid 319.21174 -428.965072)
					(end 319.157858 -428.942754)
				)
				(arc
					(start 318.218058 -428.942754)
					(mid 318.164176 -428.965072)
					(end 318.141858 -429.018954)
				)
			)
		)
	)
	(zone
		(layers "In1.Cu" "In2.Cu" "In3.Cu" "In7.Cu" "In8.Cu" "In9.Cu" "In14.Cu"
			"In16.Cu"
		)
		(hatch none 0.5)
		(connect_pads
			(clearance 0)
		)
		(min_thickness 0.25)
		(keepout
			(tracks not_allowed)
			(vias allowed)
			(pads allowed)
			(copperpour not_allowed)
			(footprints allowed)
		)
		(placement
			(enabled no)
			(sheetname "")
		)
		(fill yes
			(thermal_gap 0.5)
			(thermal_bridge_width 0.5)
			(island_removal_mode 0)
		)
		(polygon
			(pts
				(arc
					(start 320.141854 -432.560476)
					(mid 320.164172 -432.614358)
					(end 320.218054 -432.636676)
				)
				(arc
					(start 321.157854 -432.636676)
					(mid 321.211736 -432.614358)
					(end 321.234054 -432.560476)
				)
				(arc
					(start 321.234054 -430.018952)
					(mid 321.211736 -429.96507)
					(end 321.157854 -429.942752)
				)
				(arc
					(start 320.218054 -429.942752)
					(mid 320.164172 -429.96507)
					(end 320.141854 -430.018952)
				)
			)
		)
	)
	(zone
		(layers "In1.Cu" "In2.Cu" "In3.Cu" "In7.Cu" "In8.Cu" "In9.Cu" "In14.Cu"
			"In16.Cu"
		)
		(hatch none 0.5)
		(connect_pads
			(clearance 0)
		)
		(min_thickness 0.25)
		(keepout
			(tracks not_allowed)
			(vias allowed)
			(pads allowed)
			(copperpour not_allowed)
			(footprints allowed)
		)
		(placement
			(enabled no)
			(sheetname "")
		)
		(fill yes
			(thermal_gap 0.5)
			(thermal_bridge_width 0.5)
			(island_removal_mode 0)
		)
		(polygon
			(pts
				(arc
					(start 322.14185 -431.560478)
					(mid 322.164168 -431.61436)
					(end 322.21805 -431.636678)
				)
				(arc
					(start 323.15785 -431.636678)
					(mid 323.211732 -431.61436)
					(end 323.23405 -431.560478)
				)
				(arc
					(start 323.23405 -429.018954)
					(mid 323.211732 -428.965072)
					(end 323.15785 -428.942754)
				)
				(arc
					(start 322.21805 -428.942754)
					(mid 322.164168 -428.965072)
					(end 322.14185 -429.018954)
				)
			)
		)
	)
	(zone
		(layers "In1.Cu" "In2.Cu" "In3.Cu" "In7.Cu" "In8.Cu" "In9.Cu" "In14.Cu"
			"In16.Cu"
		)
		(hatch none 0.5)
		(connect_pads
			(clearance 0)
		)
		(min_thickness 0.25)
		(keepout
			(tracks not_allowed)
			(vias allowed)
			(pads allowed)
			(copperpour not_allowed)
			(footprints allowed)
		)
		(placement
			(enabled no)
			(sheetname "")
		)
		(fill yes
			(thermal_gap 0.5)
			(thermal_bridge_width 0.5)
			(island_removal_mode 0)
		)
		(polygon
			(pts
				(arc
					(start 326.141842 -431.560478)
					(mid 326.16416 -431.61436)
					(end 326.218042 -431.636678)
				)
				(arc
					(start 327.157842 -431.636678)
					(mid 327.211724 -431.61436)
					(end 327.234042 -431.560478)
				)
				(arc
					(start 327.234042 -429.018954)
					(mid 327.211724 -428.965072)
					(end 327.157842 -428.942754)
				)
				(arc
					(start 326.218042 -428.942754)
					(mid 326.16416 -428.965072)
					(end 326.141842 -429.018954)
				)
			)
		)
	)
	(zone
		(layers "In1.Cu" "In2.Cu" "In3.Cu" "In7.Cu" "In8.Cu" "In9.Cu" "In14.Cu"
			"In16.Cu"
		)
		(hatch none 0.5)
		(connect_pads
			(clearance 0)
		)
		(min_thickness 0.25)
		(keepout
			(tracks not_allowed)
			(vias allowed)
			(pads allowed)
			(copperpour not_allowed)
			(footprints allowed)
		)
		(placement
			(enabled no)
			(sheetname "")
		)
		(fill yes
			(thermal_gap 0.5)
			(thermal_bridge_width 0.5)
			(island_removal_mode 0)
		)
		(polygon
			(pts
				(arc
					(start 328.141838 -432.560476)
					(mid 328.164156 -432.614358)
					(end 328.218038 -432.636676)
				)
				(arc
					(start 329.157838 -432.636676)
					(mid 329.21172 -432.614358)
					(end 329.234038 -432.560476)
				)
				(arc
					(start 329.234038 -430.018952)
					(mid 329.21172 -429.96507)
					(end 329.157838 -429.942752)
				)
				(arc
					(start 328.218038 -429.942752)
					(mid 328.164156 -429.96507)
					(end 328.141838 -430.018952)
				)
			)
		)
	)
	(zone
		(layers "In1.Cu" "In2.Cu" "In3.Cu" "In7.Cu" "In8.Cu" "In9.Cu" "In14.Cu"
			"In16.Cu"
		)
		(hatch none 0.5)
		(connect_pads
			(clearance 0)
		)
		(min_thickness 0.25)
		(keepout
			(tracks not_allowed)
			(vias allowed)
			(pads allowed)
			(copperpour not_allowed)
			(footprints allowed)
		)
		(placement
			(enabled no)
			(sheetname "")
		)
		(fill yes
			(thermal_gap 0.5)
			(thermal_bridge_width 0.5)
			(island_removal_mode 0)
		)
		(polygon
			(pts
				(arc
					(start 324.141846 -432.560476)
					(mid 324.164164 -432.614358)
					(end 324.218046 -432.636676)
				)
				(arc
					(start 325.157846 -432.636676)
					(mid 325.211728 -432.614358)
					(end 325.234046 -432.560476)
				)
				(arc
					(start 325.234046 -430.018952)
					(mid 325.211728 -429.96507)
					(end 325.157846 -429.942752)
				)
				(arc
					(start 324.218046 -429.942752)
					(mid 324.164164 -429.96507)
					(end 324.141846 -430.018952)
				)
			)
		)
	)
	(zone
		(layers "In1.Cu" "In2.Cu" "In3.Cu" "In7.Cu" "In8.Cu" "In9.Cu" "In16.Cu")
		(hatch none 0.5)
		(connect_pads
			(clearance 0)
		)
		(min_thickness 0.25)
		(keepout
			(tracks not_allowed)
			(vias allowed)
			(pads allowed)
			(copperpour not_allowed)
			(footprints allowed)
		)
		(placement
			(enabled no)
			(sheetname "")
		)
		(fill yes
			(thermal_gap 0.5)
			(thermal_bridge_width 0.5)
			(island_removal_mode 0)
		)
		(polygon
			(pts
				(arc
					(start 381.241808 -435.16042)
					(mid 381.264126 -435.214302)
					(end 381.318008 -435.23662)
				)
				(arc
					(start 382.257808 -435.23662)
					(mid 382.31169 -435.214302)
					(end 382.334008 -435.16042)
				)
				(arc
					(start 382.334008 -432.618896)
					(mid 382.31169 -432.565014)
					(end 382.257808 -432.542696)
				)
				(arc
					(start 381.318008 -432.542696)
					(mid 381.264126 -432.565014)
					(end 381.241808 -432.618896)
				)
			)
		)
	)
	(zone
		(layers "In1.Cu" "In2.Cu" "In3.Cu" "In7.Cu" "In8.Cu" "In9.Cu" "In16.Cu")
		(hatch none 0.5)
		(connect_pads
			(clearance 0)
		)
		(min_thickness 0.25)
		(keepout
			(tracks not_allowed)
			(vias allowed)
			(pads allowed)
			(copperpour not_allowed)
			(footprints allowed)
		)
		(placement
			(enabled no)
			(sheetname "")
		)
		(fill yes
			(thermal_gap 0.5)
			(thermal_bridge_width 0.5)
			(island_removal_mode 0)
		)
		(polygon
			(pts
				(arc
					(start 391.241788 -436.160418)
					(mid 391.264106 -436.2143)
					(end 391.317988 -436.236618)
				)
				(arc
					(start 392.257788 -436.236618)
					(mid 392.31167 -436.2143)
					(end 392.333988 -436.160418)
				)
				(arc
					(start 392.333988 -433.618894)
					(mid 392.31167 -433.565012)
					(end 392.257788 -433.542694)
				)
				(arc
					(start 391.317988 -433.542694)
					(mid 391.264106 -433.565012)
					(end 391.241788 -433.618894)
				)
			)
		)
	)
	(zone
		(layers "In1.Cu" "In2.Cu" "In3.Cu" "In7.Cu" "In8.Cu" "In9.Cu" "In16.Cu")
		(hatch none 0.5)
		(connect_pads
			(clearance 0)
		)
		(min_thickness 0.25)
		(keepout
			(tracks not_allowed)
			(vias allowed)
			(pads allowed)
			(copperpour not_allowed)
			(footprints allowed)
		)
		(placement
			(enabled no)
			(sheetname "")
		)
		(fill yes
			(thermal_gap 0.5)
			(thermal_bridge_width 0.5)
			(island_removal_mode 0)
		)
		(polygon
			(pts
				(arc
					(start 395.24178 -436.160418)
					(mid 395.264098 -436.2143)
					(end 395.31798 -436.236618)
				)
				(arc
					(start 396.25778 -436.236618)
					(mid 396.311662 -436.2143)
					(end 396.33398 -436.160418)
				)
				(arc
					(start 396.33398 -433.618894)
					(mid 396.311662 -433.565012)
					(end 396.25778 -433.542694)
				)
				(arc
					(start 395.31798 -433.542694)
					(mid 395.264098 -433.565012)
					(end 395.24178 -433.618894)
				)
			)
		)
	)
	(zone
		(layers "In1.Cu" "In2.Cu" "In3.Cu" "In7.Cu" "In8.Cu" "In9.Cu" "In16.Cu")
		(hatch none 0.5)
		(connect_pads
			(clearance 0)
		)
		(min_thickness 0.25)
		(keepout
			(tracks not_allowed)
			(vias allowed)
			(pads allowed)
			(copperpour not_allowed)
			(footprints allowed)
		)
		(placement
			(enabled no)
			(sheetname "")
		)
		(fill yes
			(thermal_gap 0.5)
			(thermal_bridge_width 0.5)
			(island_removal_mode 0)
		)
		(polygon
			(pts
				(arc
					(start 408.241754 -436.160418)
					(mid 408.264072 -436.2143)
					(end 408.317954 -436.236618)
				)
				(arc
					(start 409.257754 -436.236618)
					(mid 409.311636 -436.2143)
					(end 409.333954 -436.160418)
				)
				(arc
					(start 409.333954 -433.618894)
					(mid 409.311636 -433.565012)
					(end 409.257754 -433.542694)
				)
				(arc
					(start 408.317954 -433.542694)
					(mid 408.264072 -433.565012)
					(end 408.241754 -433.618894)
				)
			)
		)
	)
	(zone
		(layers "In1.Cu" "In2.Cu" "In3.Cu" "In7.Cu" "In8.Cu" "In9.Cu" "In16.Cu")
		(hatch none 0.5)
		(connect_pads
			(clearance 0)
		)
		(min_thickness 0.25)
		(keepout
			(tracks not_allowed)
			(vias allowed)
			(pads allowed)
			(copperpour not_allowed)
			(footprints allowed)
		)
		(placement
			(enabled no)
			(sheetname "")
		)
		(fill yes
			(thermal_gap 0.5)
			(thermal_bridge_width 0.5)
			(island_removal_mode 0)
		)
		(polygon
			(pts
				(arc
					(start 393.241784 -435.16042)
					(mid 393.264102 -435.214302)
					(end 393.317984 -435.23662)
				)
				(arc
					(start 394.257784 -435.23662)
					(mid 394.311666 -435.214302)
					(end 394.333984 -435.16042)
				)
				(arc
					(start 394.333984 -432.618896)
					(mid 394.311666 -432.565014)
					(end 394.257784 -432.542696)
				)
				(arc
					(start 393.317984 -432.542696)
					(mid 393.264102 -432.565014)
					(end 393.241784 -432.618896)
				)
			)
		)
	)
	(zone
		(layers "In1.Cu" "In2.Cu" "In3.Cu" "In7.Cu" "In8.Cu" "In9.Cu" "In16.Cu")
		(hatch none 0.5)
		(connect_pads
			(clearance 0)
		)
		(min_thickness 0.25)
		(keepout
			(tracks not_allowed)
			(vias allowed)
			(pads allowed)
			(copperpour not_allowed)
			(footprints allowed)
		)
		(placement
			(enabled no)
			(sheetname "")
		)
		(fill yes
			(thermal_gap 0.5)
			(thermal_bridge_width 0.5)
			(island_removal_mode 0)
		)
		(polygon
			(pts
				(arc
					(start 400.24177 -436.160418)
					(mid 400.264088 -436.2143)
					(end 400.31797 -436.236618)
				)
				(arc
					(start 401.25777 -436.236618)
					(mid 401.311652 -436.2143)
					(end 401.33397 -436.160418)
				)
				(arc
					(start 401.33397 -433.618894)
					(mid 401.311652 -433.565012)
					(end 401.25777 -433.542694)
				)
				(arc
					(start 400.31797 -433.542694)
					(mid 400.264088 -433.565012)
					(end 400.24177 -433.618894)
				)
			)
		)
	)
	(zone
		(layers "In1.Cu" "In2.Cu" "In3.Cu" "In7.Cu" "In8.Cu" "In9.Cu" "In16.Cu")
		(hatch none 0.5)
		(connect_pads
			(clearance 0)
		)
		(min_thickness 0.25)
		(keepout
			(tracks not_allowed)
			(vias allowed)
			(pads allowed)
			(copperpour not_allowed)
			(footprints allowed)
		)
		(placement
			(enabled no)
			(sheetname "")
		)
		(fill yes
			(thermal_gap 0.5)
			(thermal_bridge_width 0.5)
			(island_removal_mode 0)
		)
		(polygon
			(pts
				(arc
					(start 410.24175 -435.16042)
					(mid 410.264068 -435.214302)
					(end 410.31795 -435.23662)
				)
				(arc
					(start 411.25775 -435.23662)
					(mid 411.311632 -435.214302)
					(end 411.33395 -435.16042)
				)
				(arc
					(start 411.33395 -432.618896)
					(mid 411.311632 -432.565014)
					(end 411.25775 -432.542696)
				)
				(arc
					(start 410.31795 -432.542696)
					(mid 410.264068 -432.565014)
					(end 410.24175 -432.618896)
				)
			)
		)
	)
	(zone
		(layers "In1.Cu" "In2.Cu" "In3.Cu" "In7.Cu" "In8.Cu" "In9.Cu" "In16.Cu")
		(hatch none 0.5)
		(connect_pads
			(clearance 0)
		)
		(min_thickness 0.25)
		(keepout
			(tracks not_allowed)
			(vias allowed)
			(pads allowed)
			(copperpour not_allowed)
			(footprints allowed)
		)
		(placement
			(enabled no)
			(sheetname "")
		)
		(fill yes
			(thermal_gap 0.5)
			(thermal_bridge_width 0.5)
			(island_removal_mode 0)
		)
		(polygon
			(pts
				(arc
					(start 404.241762 -436.160418)
					(mid 404.26408 -436.2143)
					(end 404.317962 -436.236618)
				)
				(arc
					(start 405.257762 -436.236618)
					(mid 405.311644 -436.2143)
					(end 405.333962 -436.160418)
				)
				(arc
					(start 405.333962 -433.618894)
					(mid 405.311644 -433.565012)
					(end 405.257762 -433.542694)
				)
				(arc
					(start 404.317962 -433.542694)
					(mid 404.26408 -433.565012)
					(end 404.241762 -433.618894)
				)
			)
		)
	)
	(zone
		(layers "In1.Cu" "In2.Cu" "In3.Cu" "In7.Cu" "In8.Cu" "In9.Cu" "In16.Cu")
		(hatch none 0.5)
		(connect_pads
			(clearance 0)
		)
		(min_thickness 0.25)
		(keepout
			(tracks not_allowed)
			(vias allowed)
			(pads allowed)
			(copperpour not_allowed)
			(footprints allowed)
		)
		(placement
			(enabled no)
			(sheetname "")
		)
		(fill yes
			(thermal_gap 0.5)
			(thermal_bridge_width 0.5)
			(island_removal_mode 0)
		)
		(polygon
			(pts
				(arc
					(start 383.241804 -436.160418)
					(mid 383.264122 -436.2143)
					(end 383.318004 -436.236618)
				)
				(arc
					(start 384.257804 -436.236618)
					(mid 384.311686 -436.2143)
					(end 384.334004 -436.160418)
				)
				(arc
					(start 384.334004 -433.618894)
					(mid 384.311686 -433.565012)
					(end 384.257804 -433.542694)
				)
				(arc
					(start 383.318004 -433.542694)
					(mid 383.264122 -433.565012)
					(end 383.241804 -433.618894)
				)
			)
		)
	)
	(zone
		(layers "In1.Cu" "In2.Cu" "In3.Cu" "In7.Cu" "In8.Cu" "In9.Cu" "In16.Cu")
		(hatch none 0.5)
		(connect_pads
			(clearance 0)
		)
		(min_thickness 0.25)
		(keepout
			(tracks not_allowed)
			(vias allowed)
			(pads allowed)
			(copperpour not_allowed)
			(footprints allowed)
		)
		(placement
			(enabled no)
			(sheetname "")
		)
		(fill yes
			(thermal_gap 0.5)
			(thermal_bridge_width 0.5)
			(island_removal_mode 0)
		)
		(polygon
			(pts
				(arc
					(start 402.241766 -435.16042)
					(mid 402.264084 -435.214302)
					(end 402.317966 -435.23662)
				)
				(arc
					(start 403.257766 -435.23662)
					(mid 403.311648 -435.214302)
					(end 403.333966 -435.16042)
				)
				(arc
					(start 403.333966 -432.618896)
					(mid 403.311648 -432.565014)
					(end 403.257766 -432.542696)
				)
				(arc
					(start 402.317966 -432.542696)
					(mid 402.264084 -432.565014)
					(end 402.241766 -432.618896)
				)
			)
		)
	)
	(zone
		(layers "In1.Cu" "In2.Cu" "In3.Cu" "In7.Cu" "In8.Cu" "In9.Cu" "In16.Cu")
		(hatch none 0.5)
		(connect_pads
			(clearance 0)
		)
		(min_thickness 0.25)
		(keepout
			(tracks not_allowed)
			(vias allowed)
			(pads allowed)
			(copperpour not_allowed)
			(footprints allowed)
		)
		(placement
			(enabled no)
			(sheetname "")
		)
		(fill yes
			(thermal_gap 0.5)
			(thermal_bridge_width 0.5)
			(island_removal_mode 0)
		)
		(polygon
			(pts
				(arc
					(start 389.241792 -435.16042)
					(mid 389.26411 -435.214302)
					(end 389.317992 -435.23662)
				)
				(arc
					(start 390.257792 -435.23662)
					(mid 390.311674 -435.214302)
					(end 390.333992 -435.16042)
				)
				(arc
					(start 390.333992 -432.618896)
					(mid 390.311674 -432.565014)
					(end 390.257792 -432.542696)
				)
				(arc
					(start 389.317992 -432.542696)
					(mid 389.26411 -432.565014)
					(end 389.241792 -432.618896)
				)
			)
		)
	)
	(zone
		(layers "In1.Cu" "In2.Cu" "In3.Cu" "In7.Cu" "In8.Cu" "In9.Cu" "In16.Cu")
		(hatch none 0.5)
		(connect_pads
			(clearance 0)
		)
		(min_thickness 0.25)
		(keepout
			(tracks not_allowed)
			(vias allowed)
			(pads allowed)
			(copperpour not_allowed)
			(footprints allowed)
		)
		(placement
			(enabled no)
			(sheetname "")
		)
		(fill yes
			(thermal_gap 0.5)
			(thermal_bridge_width 0.5)
			(island_removal_mode 0)
		)
		(polygon
			(pts
				(arc
					(start 385.2418 -435.16042)
					(mid 385.264118 -435.214302)
					(end 385.318 -435.23662)
				)
				(arc
					(start 386.2578 -435.23662)
					(mid 386.311682 -435.214302)
					(end 386.334 -435.16042)
				)
				(arc
					(start 386.334 -432.618896)
					(mid 386.311682 -432.565014)
					(end 386.2578 -432.542696)
				)
				(arc
					(start 385.318 -432.542696)
					(mid 385.264118 -432.565014)
					(end 385.2418 -432.618896)
				)
			)
		)
	)
	(zone
		(layers "In1.Cu" "In2.Cu" "In3.Cu" "In7.Cu" "In8.Cu" "In9.Cu" "In16.Cu")
		(hatch none 0.5)
		(connect_pads
			(clearance 0)
		)
		(min_thickness 0.25)
		(keepout
			(tracks not_allowed)
			(vias allowed)
			(pads allowed)
			(copperpour not_allowed)
			(footprints allowed)
		)
		(placement
			(enabled no)
			(sheetname "")
		)
		(fill yes
			(thermal_gap 0.5)
			(thermal_bridge_width 0.5)
			(island_removal_mode 0)
		)
		(polygon
			(pts
				(arc
					(start 412.241746 -436.160418)
					(mid 412.264064 -436.2143)
					(end 412.317946 -436.236618)
				)
				(arc
					(start 413.257746 -436.236618)
					(mid 413.311628 -436.2143)
					(end 413.333946 -436.160418)
				)
				(arc
					(start 413.333946 -433.618894)
					(mid 413.311628 -433.565012)
					(end 413.257746 -433.542694)
				)
				(arc
					(start 412.317946 -433.542694)
					(mid 412.264064 -433.565012)
					(end 412.241746 -433.618894)
				)
			)
		)
	)
	(zone
		(layers "In1.Cu" "In2.Cu" "In3.Cu" "In7.Cu" "In8.Cu" "In9.Cu" "In16.Cu")
		(hatch none 0.5)
		(connect_pads
			(clearance 0)
		)
		(min_thickness 0.25)
		(keepout
			(tracks not_allowed)
			(vias allowed)
			(pads allowed)
			(copperpour not_allowed)
			(footprints allowed)
		)
		(placement
			(enabled no)
			(sheetname "")
		)
		(fill yes
			(thermal_gap 0.5)
			(thermal_bridge_width 0.5)
			(island_removal_mode 0)
		)
		(polygon
			(pts
				(arc
					(start 387.241796 -436.160418)
					(mid 387.264114 -436.2143)
					(end 387.317996 -436.236618)
				)
				(arc
					(start 388.257796 -436.236618)
					(mid 388.311678 -436.2143)
					(end 388.333996 -436.160418)
				)
				(arc
					(start 388.333996 -433.618894)
					(mid 388.311678 -433.565012)
					(end 388.257796 -433.542694)
				)
				(arc
					(start 387.317996 -433.542694)
					(mid 387.264114 -433.565012)
					(end 387.241796 -433.618894)
				)
			)
		)
	)
	(zone
		(layers "In1.Cu" "In2.Cu" "In3.Cu" "In7.Cu" "In8.Cu" "In9.Cu" "In16.Cu")
		(hatch none 0.5)
		(connect_pads
			(clearance 0)
		)
		(min_thickness 0.25)
		(keepout
			(tracks not_allowed)
			(vias allowed)
			(pads allowed)
			(copperpour not_allowed)
			(footprints allowed)
		)
		(placement
			(enabled no)
			(sheetname "")
		)
		(fill yes
			(thermal_gap 0.5)
			(thermal_bridge_width 0.5)
			(island_removal_mode 0)
		)
		(polygon
			(pts
				(arc
					(start 406.241758 -435.16042)
					(mid 406.264076 -435.214302)
					(end 406.317958 -435.23662)
				)
				(arc
					(start 407.257758 -435.23662)
					(mid 407.31164 -435.214302)
					(end 407.333958 -435.16042)
				)
				(arc
					(start 407.333958 -432.618896)
					(mid 407.31164 -432.565014)
					(end 407.257758 -432.542696)
				)
				(arc
					(start 406.317958 -432.542696)
					(mid 406.264076 -432.565014)
					(end 406.241758 -432.618896)
				)
			)
		)
	)
	(zone
		(layers "In1.Cu" "In2.Cu" "In3.Cu" "In7.Cu" "In8.Cu" "In9.Cu" "In16.Cu")
		(hatch none 0.5)
		(connect_pads
			(clearance 0)
		)
		(min_thickness 0.25)
		(keepout
			(tracks not_allowed)
			(vias allowed)
			(pads allowed)
			(copperpour not_allowed)
			(footprints allowed)
		)
		(placement
			(enabled no)
			(sheetname "")
		)
		(fill yes
			(thermal_gap 0.5)
			(thermal_bridge_width 0.5)
			(island_removal_mode 0)
		)
		(polygon
			(pts
				(arc
					(start 398.241774 -435.16042)
					(mid 398.264092 -435.214302)
					(end 398.317974 -435.23662)
				)
				(arc
					(start 399.257774 -435.23662)
					(mid 399.311656 -435.214302)
					(end 399.333974 -435.16042)
				)
				(arc
					(start 399.333974 -432.618896)
					(mid 399.311656 -432.565014)
					(end 399.257774 -432.542696)
				)
				(arc
					(start 398.317974 -432.542696)
					(mid 398.264092 -432.565014)
					(end 398.241774 -432.618896)
				)
			)
		)
	)
	(zone
		(layers "In1.Cu" "In2.Cu" "In3.Cu" "In8.Cu" "In9.Cu" "In10.Cu" "In12.Cu"
			"In13.Cu" "In14.Cu" "In16.Cu"
		)
		(hatch none 0.5)
		(connect_pads
			(clearance 0)
		)
		(min_thickness 0.25)
		(keepout
			(tracks not_allowed)
			(vias allowed)
			(pads allowed)
			(copperpour not_allowed)
			(footprints allowed)
		)
		(placement
			(enabled no)
			(sheetname "")
		)
		(fill yes
			(thermal_gap 0.5)
			(thermal_bridge_width 0.5)
			(island_removal_mode 0)
		)
		(polygon
			(pts
				(arc
					(start 62.141862 -427.960536)
					(mid 62.16418 -428.014418)
					(end 62.218062 -428.036736)
				)
				(arc
					(start 63.157862 -428.036736)
					(mid 63.211744 -428.014418)
					(end 63.234062 -427.960536)
				)
				(arc
					(start 63.234062 -425.419012)
					(mid 63.211744 -425.36513)
					(end 63.157862 -425.342812)
				)
				(arc
					(start 62.218062 -425.342812)
					(mid 62.16418 -425.36513)
					(end 62.141862 -425.419012)
				)
			)
		)
	)
	(zone
		(layers "In1.Cu" "In2.Cu" "In3.Cu" "In8.Cu" "In9.Cu" "In10.Cu" "In12.Cu"
			"In13.Cu" "In14.Cu" "In16.Cu"
		)
		(hatch none 0.5)
		(connect_pads
			(clearance 0)
		)
		(min_thickness 0.25)
		(keepout
			(tracks not_allowed)
			(vias allowed)
			(pads allowed)
			(copperpour not_allowed)
			(footprints allowed)
		)
		(placement
			(enabled no)
			(sheetname "")
		)
		(fill yes
			(thermal_gap 0.5)
			(thermal_bridge_width 0.5)
			(island_removal_mode 0)
		)
		(polygon
			(pts
				(arc
					(start 66.141854 -427.960536)
					(mid 66.164172 -428.014418)
					(end 66.218054 -428.036736)
				)
				(arc
					(start 67.157854 -428.036736)
					(mid 67.211736 -428.014418)
					(end 67.234054 -427.960536)
				)
				(arc
					(start 67.234054 -425.419012)
					(mid 67.211736 -425.36513)
					(end 67.157854 -425.342812)
				)
				(arc
					(start 66.218054 -425.342812)
					(mid 66.164172 -425.36513)
					(end 66.141854 -425.419012)
				)
			)
		)
	)
	(zone
		(layers "In1.Cu" "In2.Cu" "In3.Cu" "In8.Cu" "In9.Cu" "In10.Cu" "In12.Cu"
			"In13.Cu" "In14.Cu" "In16.Cu"
		)
		(hatch none 0.5)
		(connect_pads
			(clearance 0)
		)
		(min_thickness 0.25)
		(keepout
			(tracks not_allowed)
			(vias allowed)
			(pads allowed)
			(copperpour not_allowed)
			(footprints allowed)
		)
		(placement
			(enabled no)
			(sheetname "")
		)
		(fill yes
			(thermal_gap 0.5)
			(thermal_bridge_width 0.5)
			(island_removal_mode 0)
		)
		(polygon
			(pts
				(arc
					(start 129.241804 -427.960536)
					(mid 129.264122 -428.014418)
					(end 129.318004 -428.036736)
				)
				(arc
					(start 130.257804 -428.036736)
					(mid 130.311686 -428.014418)
					(end 130.334004 -427.960536)
				)
				(arc
					(start 130.334004 -425.419012)
					(mid 130.311686 -425.36513)
					(end 130.257804 -425.342812)
				)
				(arc
					(start 129.318004 -425.342812)
					(mid 129.264122 -425.36513)
					(end 129.241804 -425.419012)
				)
			)
		)
	)
	(zone
		(layers "In1.Cu" "In2.Cu" "In3.Cu" "In8.Cu" "In9.Cu" "In10.Cu" "In12.Cu"
			"In13.Cu" "In14.Cu" "In16.Cu"
		)
		(hatch none 0.5)
		(connect_pads
			(clearance 0)
		)
		(min_thickness 0.25)
		(keepout
			(tracks not_allowed)
			(vias allowed)
			(pads allowed)
			(copperpour not_allowed)
			(footprints allowed)
		)
		(placement
			(enabled no)
			(sheetname "")
		)
		(fill yes
			(thermal_gap 0.5)
			(thermal_bridge_width 0.5)
			(island_removal_mode 0)
		)
		(polygon
			(pts
				(arc
					(start 70.141846 -427.960536)
					(mid 70.164164 -428.014418)
					(end 70.218046 -428.036736)
				)
				(arc
					(start 71.157846 -428.036736)
					(mid 71.211728 -428.014418)
					(end 71.234046 -427.960536)
				)
				(arc
					(start 71.234046 -425.419012)
					(mid 71.211728 -425.36513)
					(end 71.157846 -425.342812)
				)
				(arc
					(start 70.218046 -425.342812)
					(mid 70.164164 -425.36513)
					(end 70.141846 -425.419012)
				)
			)
		)
	)
	(zone
		(layers "In1.Cu" "In2.Cu" "In3.Cu" "In8.Cu" "In9.Cu" "In10.Cu" "In12.Cu"
			"In13.Cu" "In14.Cu" "In16.Cu"
		)
		(hatch none 0.5)
		(connect_pads
			(clearance 0)
		)
		(min_thickness 0.25)
		(keepout
			(tracks not_allowed)
			(vias allowed)
			(pads allowed)
			(copperpour not_allowed)
			(footprints allowed)
		)
		(placement
			(enabled no)
			(sheetname "")
		)
		(fill yes
			(thermal_gap 0.5)
			(thermal_bridge_width 0.5)
			(island_removal_mode 0)
		)
		(polygon
			(pts
				(arc
					(start 137.241788 -427.960536)
					(mid 137.264106 -428.014418)
					(end 137.317988 -428.036736)
				)
				(arc
					(start 138.257788 -428.036736)
					(mid 138.31167 -428.014418)
					(end 138.333988 -427.960536)
				)
				(arc
					(start 138.333988 -425.419012)
					(mid 138.31167 -425.36513)
					(end 138.257788 -425.342812)
				)
				(arc
					(start 137.317988 -425.342812)
					(mid 137.264106 -425.36513)
					(end 137.241788 -425.419012)
				)
			)
		)
	)
	(zone
		(layers "In1.Cu" "In2.Cu" "In3.Cu" "In8.Cu" "In9.Cu" "In10.Cu" "In12.Cu"
			"In13.Cu" "In14.Cu" "In16.Cu"
		)
		(hatch none 0.5)
		(connect_pads
			(clearance 0)
		)
		(min_thickness 0.25)
		(keepout
			(tracks not_allowed)
			(vias allowed)
			(pads allowed)
			(copperpour not_allowed)
			(footprints allowed)
		)
		(placement
			(enabled no)
			(sheetname "")
		)
		(fill yes
			(thermal_gap 0.5)
			(thermal_bridge_width 0.5)
			(island_removal_mode 0)
		)
		(polygon
			(pts
				(arc
					(start 79.141828 -427.960536)
					(mid 79.164146 -428.014418)
					(end 79.218028 -428.036736)
				)
				(arc
					(start 80.157828 -428.036736)
					(mid 80.21171 -428.014418)
					(end 80.234028 -427.960536)
				)
				(arc
					(start 80.234028 -425.419012)
					(mid 80.21171 -425.36513)
					(end 80.157828 -425.342812)
				)
				(arc
					(start 79.218028 -425.342812)
					(mid 79.164146 -425.36513)
					(end 79.141828 -425.419012)
				)
			)
		)
	)
	(zone
		(layers "In1.Cu" "In2.Cu" "In3.Cu" "In8.Cu" "In9.Cu" "In10.Cu" "In12.Cu"
			"In13.Cu" "In14.Cu" "In16.Cu"
		)
		(hatch none 0.5)
		(connect_pads
			(clearance 0)
		)
		(min_thickness 0.25)
		(keepout
			(tracks not_allowed)
			(vias allowed)
			(pads allowed)
			(copperpour not_allowed)
			(footprints allowed)
		)
		(placement
			(enabled no)
			(sheetname "")
		)
		(fill yes
			(thermal_gap 0.5)
			(thermal_bridge_width 0.5)
			(island_removal_mode 0)
		)
		(polygon
			(pts
				(arc
					(start 87.141812 -427.960536)
					(mid 87.16413 -428.014418)
					(end 87.218012 -428.036736)
				)
				(arc
					(start 88.157812 -428.036736)
					(mid 88.211694 -428.014418)
					(end 88.234012 -427.960536)
				)
				(arc
					(start 88.234012 -425.419012)
					(mid 88.211694 -425.36513)
					(end 88.157812 -425.342812)
				)
				(arc
					(start 87.218012 -425.342812)
					(mid 87.16413 -425.36513)
					(end 87.141812 -425.419012)
				)
			)
		)
	)
	(zone
		(layers "In1.Cu" "In2.Cu" "In3.Cu" "In8.Cu" "In9.Cu" "In10.Cu" "In12.Cu"
			"In13.Cu" "In14.Cu" "In16.Cu"
		)
		(hatch none 0.5)
		(connect_pads
			(clearance 0)
		)
		(min_thickness 0.25)
		(keepout
			(tracks not_allowed)
			(vias allowed)
			(pads allowed)
			(copperpour not_allowed)
			(footprints allowed)
		)
		(placement
			(enabled no)
			(sheetname "")
		)
		(fill yes
			(thermal_gap 0.5)
			(thermal_bridge_width 0.5)
			(island_removal_mode 0)
		)
		(polygon
			(pts
				(arc
					(start 58.14187 -427.960536)
					(mid 58.164188 -428.014418)
					(end 58.21807 -428.036736)
				)
				(arc
					(start 59.15787 -428.036736)
					(mid 59.211752 -428.014418)
					(end 59.23407 -427.960536)
				)
				(arc
					(start 59.23407 -425.419012)
					(mid 59.211752 -425.36513)
					(end 59.15787 -425.342812)
				)
				(arc
					(start 58.21807 -425.342812)
					(mid 58.164188 -425.36513)
					(end 58.14187 -425.419012)
				)
			)
		)
	)
	(zone
		(layers "In1.Cu" "In2.Cu" "In3.Cu" "In8.Cu" "In9.Cu" "In10.Cu" "In12.Cu"
			"In13.Cu" "In14.Cu" "In16.Cu"
		)
		(hatch none 0.5)
		(connect_pads
			(clearance 0)
		)
		(min_thickness 0.25)
		(keepout
			(tracks not_allowed)
			(vias allowed)
			(pads allowed)
			(copperpour not_allowed)
			(footprints allowed)
		)
		(placement
			(enabled no)
			(sheetname "")
		)
		(fill yes
			(thermal_gap 0.5)
			(thermal_bridge_width 0.5)
			(island_removal_mode 0)
		)
		(polygon
			(pts
				(arc
					(start 142.241778 -427.960536)
					(mid 142.264096 -428.014418)
					(end 142.317978 -428.036736)
				)
				(arc
					(start 143.257778 -428.036736)
					(mid 143.31166 -428.014418)
					(end 143.333978 -427.960536)
				)
				(arc
					(start 143.333978 -425.419012)
					(mid 143.31166 -425.36513)
					(end 143.257778 -425.342812)
				)
				(arc
					(start 142.317978 -425.342812)
					(mid 142.264096 -425.36513)
					(end 142.241778 -425.419012)
				)
			)
		)
	)
	(zone
		(layers "In1.Cu" "In2.Cu" "In3.Cu" "In8.Cu" "In9.Cu" "In10.Cu" "In12.Cu"
			"In13.Cu" "In14.Cu" "In16.Cu"
		)
		(hatch none 0.5)
		(connect_pads
			(clearance 0)
		)
		(min_thickness 0.25)
		(keepout
			(tracks not_allowed)
			(vias allowed)
			(pads allowed)
			(copperpour not_allowed)
			(footprints allowed)
		)
		(placement
			(enabled no)
			(sheetname "")
		)
		(fill yes
			(thermal_gap 0.5)
			(thermal_bridge_width 0.5)
			(island_removal_mode 0)
		)
		(polygon
			(pts
				(arc
					(start 146.24177 -427.960536)
					(mid 146.264088 -428.014418)
					(end 146.31797 -428.036736)
				)
				(arc
					(start 147.25777 -428.036736)
					(mid 147.311652 -428.014418)
					(end 147.33397 -427.960536)
				)
				(arc
					(start 147.33397 -425.419012)
					(mid 147.311652 -425.36513)
					(end 147.25777 -425.342812)
				)
				(arc
					(start 146.31797 -425.342812)
					(mid 146.264088 -425.36513)
					(end 146.24177 -425.419012)
				)
			)
		)
	)
	(zone
		(layers "In1.Cu" "In2.Cu" "In3.Cu" "In8.Cu" "In9.Cu" "In10.Cu" "In12.Cu"
			"In13.Cu" "In14.Cu" "In16.Cu"
		)
		(hatch none 0.5)
		(connect_pads
			(clearance 0)
		)
		(min_thickness 0.25)
		(keepout
			(tracks not_allowed)
			(vias allowed)
			(pads allowed)
			(copperpour not_allowed)
			(footprints allowed)
		)
		(placement
			(enabled no)
			(sheetname "")
		)
		(fill yes
			(thermal_gap 0.5)
			(thermal_bridge_width 0.5)
			(island_removal_mode 0)
		)
		(polygon
			(pts
				(arc
					(start 83.14182 -427.960536)
					(mid 83.164138 -428.014418)
					(end 83.21802 -428.036736)
				)
				(arc
					(start 84.15782 -428.036736)
					(mid 84.211702 -428.014418)
					(end 84.23402 -427.960536)
				)
				(arc
					(start 84.23402 -425.419012)
					(mid 84.211702 -425.36513)
					(end 84.15782 -425.342812)
				)
				(arc
					(start 83.21802 -425.342812)
					(mid 83.164138 -425.36513)
					(end 83.14182 -425.419012)
				)
			)
		)
	)
	(zone
		(layers "In1.Cu" "In2.Cu" "In3.Cu" "In8.Cu" "In9.Cu" "In10.Cu" "In12.Cu"
			"In13.Cu" "In14.Cu" "In16.Cu"
		)
		(hatch none 0.5)
		(connect_pads
			(clearance 0)
		)
		(min_thickness 0.25)
		(keepout
			(tracks not_allowed)
			(vias allowed)
			(pads allowed)
			(copperpour not_allowed)
			(footprints allowed)
		)
		(placement
			(enabled no)
			(sheetname "")
		)
		(fill yes
			(thermal_gap 0.5)
			(thermal_bridge_width 0.5)
			(island_removal_mode 0)
		)
		(polygon
			(pts
				(arc
					(start 154.241754 -427.960536)
					(mid 154.264072 -428.014418)
					(end 154.317954 -428.036736)
				)
				(arc
					(start 155.257754 -428.036736)
					(mid 155.311636 -428.014418)
					(end 155.333954 -427.960536)
				)
				(arc
					(start 155.333954 -425.419012)
					(mid 155.311636 -425.36513)
					(end 155.257754 -425.342812)
				)
				(arc
					(start 154.317954 -425.342812)
					(mid 154.264072 -425.36513)
					(end 154.241754 -425.419012)
				)
			)
		)
	)
	(zone
		(layers "In1.Cu" "In2.Cu" "In3.Cu" "In8.Cu" "In9.Cu" "In10.Cu" "In12.Cu"
			"In13.Cu" "In14.Cu" "In16.Cu"
		)
		(hatch none 0.5)
		(connect_pads
			(clearance 0)
		)
		(min_thickness 0.25)
		(keepout
			(tracks not_allowed)
			(vias allowed)
			(pads allowed)
			(copperpour not_allowed)
			(footprints allowed)
		)
		(placement
			(enabled no)
			(sheetname "")
		)
		(fill yes
			(thermal_gap 0.5)
			(thermal_bridge_width 0.5)
			(island_removal_mode 0)
		)
		(polygon
			(pts
				(arc
					(start 125.241812 -427.960536)
					(mid 125.26413 -428.014418)
					(end 125.318012 -428.036736)
				)
				(arc
					(start 126.257812 -428.036736)
					(mid 126.311694 -428.014418)
					(end 126.334012 -427.960536)
				)
				(arc
					(start 126.334012 -425.419012)
					(mid 126.311694 -425.36513)
					(end 126.257812 -425.342812)
				)
				(arc
					(start 125.318012 -425.342812)
					(mid 125.26413 -425.36513)
					(end 125.241812 -425.419012)
				)
			)
		)
	)
	(zone
		(layers "In1.Cu" "In2.Cu" "In3.Cu" "In8.Cu" "In9.Cu" "In10.Cu" "In12.Cu"
			"In13.Cu" "In14.Cu" "In16.Cu"
		)
		(hatch none 0.5)
		(connect_pads
			(clearance 0)
		)
		(min_thickness 0.25)
		(keepout
			(tracks not_allowed)
			(vias allowed)
			(pads allowed)
			(copperpour not_allowed)
			(footprints allowed)
		)
		(placement
			(enabled no)
			(sheetname "")
		)
		(fill yes
			(thermal_gap 0.5)
			(thermal_bridge_width 0.5)
			(island_removal_mode 0)
		)
		(polygon
			(pts
				(arc
					(start 133.241796 -427.960536)
					(mid 133.264114 -428.014418)
					(end 133.317996 -428.036736)
				)
				(arc
					(start 134.257796 -428.036736)
					(mid 134.311678 -428.014418)
					(end 134.333996 -427.960536)
				)
				(arc
					(start 134.333996 -425.419012)
					(mid 134.311678 -425.36513)
					(end 134.257796 -425.342812)
				)
				(arc
					(start 133.317996 -425.342812)
					(mid 133.264114 -425.36513)
					(end 133.241796 -425.419012)
				)
			)
		)
	)
	(zone
		(layers "In1.Cu" "In2.Cu" "In3.Cu" "In8.Cu" "In9.Cu" "In10.Cu" "In12.Cu"
			"In13.Cu" "In14.Cu" "In16.Cu"
		)
		(hatch none 0.5)
		(connect_pads
			(clearance 0)
		)
		(min_thickness 0.25)
		(keepout
			(tracks not_allowed)
			(vias allowed)
			(pads allowed)
			(copperpour not_allowed)
			(footprints allowed)
		)
		(placement
			(enabled no)
			(sheetname "")
		)
		(fill yes
			(thermal_gap 0.5)
			(thermal_bridge_width 0.5)
			(island_removal_mode 0)
		)
		(polygon
			(pts
				(arc
					(start 75.141836 -427.960536)
					(mid 75.164154 -428.014418)
					(end 75.218036 -428.036736)
				)
				(arc
					(start 76.157836 -428.036736)
					(mid 76.211718 -428.014418)
					(end 76.234036 -427.960536)
				)
				(arc
					(start 76.234036 -425.419012)
					(mid 76.211718 -425.36513)
					(end 76.157836 -425.342812)
				)
				(arc
					(start 75.218036 -425.342812)
					(mid 75.164154 -425.36513)
					(end 75.141836 -425.419012)
				)
			)
		)
	)
	(zone
		(layers "In1.Cu" "In2.Cu" "In3.Cu" "In8.Cu" "In9.Cu" "In10.Cu" "In12.Cu"
			"In13.Cu" "In14.Cu" "In16.Cu"
		)
		(hatch none 0.5)
		(connect_pads
			(clearance 0)
		)
		(min_thickness 0.25)
		(keepout
			(tracks not_allowed)
			(vias allowed)
			(pads allowed)
			(copperpour not_allowed)
			(footprints allowed)
		)
		(placement
			(enabled no)
			(sheetname "")
		)
		(fill yes
			(thermal_gap 0.5)
			(thermal_bridge_width 0.5)
			(island_removal_mode 0)
		)
		(polygon
			(pts
				(arc
					(start 150.241762 -427.960536)
					(mid 150.26408 -428.014418)
					(end 150.317962 -428.036736)
				)
				(arc
					(start 151.257762 -428.036736)
					(mid 151.311644 -428.014418)
					(end 151.333962 -427.960536)
				)
				(arc
					(start 151.333962 -425.419012)
					(mid 151.311644 -425.36513)
					(end 151.257762 -425.342812)
				)
				(arc
					(start 150.317962 -425.342812)
					(mid 150.26408 -425.36513)
					(end 150.241762 -425.419012)
				)
			)
		)
	)
	(zone
		(layers "In1.Cu" "In2.Cu" "In3.Cu" "In8.Cu" "In9.Cu" "In10.Cu" "In13.Cu"
			"In14.Cu" "In16.Cu"
		)
		(hatch none 0.5)
		(connect_pads
			(clearance 0)
		)
		(min_thickness 0.25)
		(keepout
			(tracks not_allowed)
			(vias allowed)
			(pads allowed)
			(copperpour not_allowed)
			(footprints allowed)
		)
		(placement
			(enabled no)
			(sheetname "")
		)
		(fill yes
			(thermal_gap 0.5)
			(thermal_bridge_width 0.5)
			(island_removal_mode 0)
		)
		(polygon
			(pts
				(arc
					(start 389.241792 -427.960536)
					(mid 389.26411 -428.014418)
					(end 389.317992 -428.036736)
				)
				(arc
					(start 390.257792 -428.036736)
					(mid 390.311674 -428.014418)
					(end 390.333992 -427.960536)
				)
				(arc
					(start 390.333992 -425.419012)
					(mid 390.311674 -425.36513)
					(end 390.257792 -425.342812)
				)
				(arc
					(start 389.317992 -425.342812)
					(mid 389.26411 -425.36513)
					(end 389.241792 -425.419012)
				)
			)
		)
	)
	(zone
		(layers "In1.Cu" "In2.Cu" "In3.Cu" "In8.Cu" "In9.Cu" "In10.Cu" "In13.Cu"
			"In14.Cu" "In16.Cu"
		)
		(hatch none 0.5)
		(connect_pads
			(clearance 0)
		)
		(min_thickness 0.25)
		(keepout
			(tracks not_allowed)
			(vias allowed)
			(pads allowed)
			(copperpour not_allowed)
			(footprints allowed)
		)
		(placement
			(enabled no)
			(sheetname "")
		)
		(fill yes
			(thermal_gap 0.5)
			(thermal_bridge_width 0.5)
			(island_removal_mode 0)
		)
		(polygon
			(pts
				(arc
					(start 393.241784 -427.960536)
					(mid 393.264102 -428.014418)
					(end 393.317984 -428.036736)
				)
				(arc
					(start 394.257784 -428.036736)
					(mid 394.311666 -428.014418)
					(end 394.333984 -427.960536)
				)
				(arc
					(start 394.333984 -425.419012)
					(mid 394.311666 -425.36513)
					(end 394.257784 -425.342812)
				)
				(arc
					(start 393.317984 -425.342812)
					(mid 393.264102 -425.36513)
					(end 393.241784 -425.419012)
				)
			)
		)
	)
	(zone
		(layers "In1.Cu" "In2.Cu" "In3.Cu" "In8.Cu" "In9.Cu" "In10.Cu" "In13.Cu"
			"In14.Cu" "In16.Cu"
		)
		(hatch none 0.5)
		(connect_pads
			(clearance 0)
		)
		(min_thickness 0.25)
		(keepout
			(tracks not_allowed)
			(vias allowed)
			(pads allowed)
			(copperpour not_allowed)
			(footprints allowed)
		)
		(placement
			(enabled no)
			(sheetname "")
		)
		(fill yes
			(thermal_gap 0.5)
			(thermal_bridge_width 0.5)
			(island_removal_mode 0)
		)
		(polygon
			(pts
				(arc
					(start 410.24175 -427.960536)
					(mid 410.264068 -428.014418)
					(end 410.31795 -428.036736)
				)
				(arc
					(start 411.25775 -428.036736)
					(mid 411.311632 -428.014418)
					(end 411.33395 -427.960536)
				)
				(arc
					(start 411.33395 -425.419012)
					(mid 411.311632 -425.36513)
					(end 411.25775 -425.342812)
				)
				(arc
					(start 410.31795 -425.342812)
					(mid 410.264068 -425.36513)
					(end 410.24175 -425.419012)
				)
			)
		)
	)
	(zone
		(layers "In1.Cu" "In2.Cu" "In3.Cu" "In8.Cu" "In9.Cu" "In10.Cu" "In13.Cu"
			"In14.Cu" "In16.Cu"
		)
		(hatch none 0.5)
		(connect_pads
			(clearance 0)
		)
		(min_thickness 0.25)
		(keepout
			(tracks not_allowed)
			(vias allowed)
			(pads allowed)
			(copperpour not_allowed)
			(footprints allowed)
		)
		(placement
			(enabled no)
			(sheetname "")
		)
		(fill yes
			(thermal_gap 0.5)
			(thermal_bridge_width 0.5)
			(island_removal_mode 0)
		)
		(polygon
			(pts
				(arc
					(start 406.241758 -427.960536)
					(mid 406.264076 -428.014418)
					(end 406.317958 -428.036736)
				)
				(arc
					(start 407.257758 -428.036736)
					(mid 407.31164 -428.014418)
					(end 407.333958 -427.960536)
				)
				(arc
					(start 407.333958 -425.419012)
					(mid 407.31164 -425.36513)
					(end 407.257758 -425.342812)
				)
				(arc
					(start 406.317958 -425.342812)
					(mid 406.264076 -425.36513)
					(end 406.241758 -425.419012)
				)
			)
		)
	)
	(zone
		(layers "In1.Cu" "In2.Cu" "In3.Cu" "In8.Cu" "In9.Cu" "In10.Cu" "In13.Cu"
			"In14.Cu" "In16.Cu"
		)
		(hatch none 0.5)
		(connect_pads
			(clearance 0)
		)
		(min_thickness 0.25)
		(keepout
			(tracks not_allowed)
			(vias allowed)
			(pads allowed)
			(copperpour not_allowed)
			(footprints allowed)
		)
		(placement
			(enabled no)
			(sheetname "")
		)
		(fill yes
			(thermal_gap 0.5)
			(thermal_bridge_width 0.5)
			(island_removal_mode 0)
		)
		(polygon
			(pts
				(arc
					(start 385.2418 -427.960536)
					(mid 385.264118 -428.014418)
					(end 385.318 -428.036736)
				)
				(arc
					(start 386.2578 -428.036736)
					(mid 386.311682 -428.014418)
					(end 386.334 -427.960536)
				)
				(arc
					(start 386.334 -425.419012)
					(mid 386.311682 -425.36513)
					(end 386.2578 -425.342812)
				)
				(arc
					(start 385.318 -425.342812)
					(mid 385.264118 -425.36513)
					(end 385.2418 -425.419012)
				)
			)
		)
	)
	(zone
		(layers "In1.Cu" "In2.Cu" "In3.Cu" "In8.Cu" "In9.Cu" "In10.Cu" "In13.Cu"
			"In14.Cu" "In16.Cu"
		)
		(hatch none 0.5)
		(connect_pads
			(clearance 0)
		)
		(min_thickness 0.25)
		(keepout
			(tracks not_allowed)
			(vias allowed)
			(pads allowed)
			(copperpour not_allowed)
			(footprints allowed)
		)
		(placement
			(enabled no)
			(sheetname "")
		)
		(fill yes
			(thermal_gap 0.5)
			(thermal_bridge_width 0.5)
			(island_removal_mode 0)
		)
		(polygon
			(pts
				(arc
					(start 381.241808 -427.960536)
					(mid 381.264126 -428.014418)
					(end 381.318008 -428.036736)
				)
				(arc
					(start 382.257808 -428.036736)
					(mid 382.31169 -428.014418)
					(end 382.334008 -427.960536)
				)
				(arc
					(start 382.334008 -425.419012)
					(mid 382.31169 -425.36513)
					(end 382.257808 -425.342812)
				)
				(arc
					(start 381.318008 -425.342812)
					(mid 381.264126 -425.36513)
					(end 381.241808 -425.419012)
				)
			)
		)
	)
	(zone
		(layers "In1.Cu" "In2.Cu" "In3.Cu" "In8.Cu" "In9.Cu" "In10.Cu" "In13.Cu"
			"In14.Cu" "In16.Cu"
		)
		(hatch none 0.5)
		(connect_pads
			(clearance 0)
		)
		(min_thickness 0.25)
		(keepout
			(tracks not_allowed)
			(vias allowed)
			(pads allowed)
			(copperpour not_allowed)
			(footprints allowed)
		)
		(placement
			(enabled no)
			(sheetname "")
		)
		(fill yes
			(thermal_gap 0.5)
			(thermal_bridge_width 0.5)
			(island_removal_mode 0)
		)
		(polygon
			(pts
				(arc
					(start 402.241766 -427.960536)
					(mid 402.264084 -428.014418)
					(end 402.317966 -428.036736)
				)
				(arc
					(start 403.257766 -428.036736)
					(mid 403.311648 -428.014418)
					(end 403.333966 -427.960536)
				)
				(arc
					(start 403.333966 -425.419012)
					(mid 403.311648 -425.36513)
					(end 403.257766 -425.342812)
				)
				(arc
					(start 402.317966 -425.342812)
					(mid 402.264084 -425.36513)
					(end 402.241766 -425.419012)
				)
			)
		)
	)
	(zone
		(layers "In1.Cu" "In2.Cu" "In3.Cu" "In8.Cu" "In9.Cu" "In10.Cu" "In13.Cu"
			"In14.Cu" "In16.Cu"
		)
		(hatch none 0.5)
		(connect_pads
			(clearance 0)
		)
		(min_thickness 0.25)
		(keepout
			(tracks not_allowed)
			(vias allowed)
			(pads allowed)
			(copperpour not_allowed)
			(footprints allowed)
		)
		(placement
			(enabled no)
			(sheetname "")
		)
		(fill yes
			(thermal_gap 0.5)
			(thermal_bridge_width 0.5)
			(island_removal_mode 0)
		)
		(polygon
			(pts
				(arc
					(start 398.241774 -427.960536)
					(mid 398.264092 -428.014418)
					(end 398.317974 -428.036736)
				)
				(arc
					(start 399.257774 -428.036736)
					(mid 399.311656 -428.014418)
					(end 399.333974 -427.960536)
				)
				(arc
					(start 399.333974 -425.419012)
					(mid 399.311656 -425.36513)
					(end 399.257774 -425.342812)
				)
				(arc
					(start 398.317974 -425.342812)
					(mid 398.264092 -425.36513)
					(end 398.241774 -425.419012)
				)
			)
		)
	)
	(zone
		(layers "In1.Cu" "In2.Cu" "In3.Cu" "In8.Cu" "In9.Cu" "In14.Cu" "In16.Cu")
		(hatch none 0.5)
		(connect_pads
			(clearance 0)
		)
		(min_thickness 0.25)
		(keepout
			(tracks not_allowed)
			(vias allowed)
			(pads allowed)
			(copperpour not_allowed)
			(footprints allowed)
		)
		(placement
			(enabled no)
			(sheetname "")
		)
		(fill yes
			(thermal_gap 0.5)
			(thermal_bridge_width 0.5)
			(island_removal_mode 0)
		)
		(polygon
			(pts
				(arc
					(start 412.241746 -432.560476)
					(mid 412.264064 -432.614358)
					(end 412.317946 -432.636676)
				)
				(arc
					(start 413.257746 -432.636676)
					(mid 413.311628 -432.614358)
					(end 413.333946 -432.560476)
				)
				(arc
					(start 413.333946 -430.018952)
					(mid 413.311628 -429.96507)
					(end 413.257746 -429.942752)
				)
				(arc
					(start 412.317946 -429.942752)
					(mid 412.264064 -429.96507)
					(end 412.241746 -430.018952)
				)
			)
		)
	)
	(zone
		(layers "In1.Cu" "In2.Cu" "In3.Cu" "In8.Cu" "In9.Cu" "In14.Cu" "In16.Cu")
		(hatch none 0.5)
		(connect_pads
			(clearance 0)
		)
		(min_thickness 0.25)
		(keepout
			(tracks not_allowed)
			(vias allowed)
			(pads allowed)
			(copperpour not_allowed)
			(footprints allowed)
		)
		(placement
			(enabled no)
			(sheetname "")
		)
		(fill yes
			(thermal_gap 0.5)
			(thermal_bridge_width 0.5)
			(island_removal_mode 0)
		)
		(polygon
			(pts
				(arc
					(start 335.141824 -431.560478)
					(mid 335.164142 -431.61436)
					(end 335.218024 -431.636678)
				)
				(arc
					(start 336.157824 -431.636678)
					(mid 336.211706 -431.61436)
					(end 336.234024 -431.560478)
				)
				(arc
					(start 336.234024 -429.018954)
					(mid 336.211706 -428.965072)
					(end 336.157824 -428.942754)
				)
				(arc
					(start 335.218024 -428.942754)
					(mid 335.164142 -428.965072)
					(end 335.141824 -429.018954)
				)
			)
		)
	)
	(zone
		(layers "In1.Cu" "In2.Cu" "In3.Cu" "In8.Cu" "In9.Cu" "In14.Cu" "In16.Cu")
		(hatch none 0.5)
		(connect_pads
			(clearance 0)
		)
		(min_thickness 0.25)
		(keepout
			(tracks not_allowed)
			(vias allowed)
			(pads allowed)
			(copperpour not_allowed)
			(footprints allowed)
		)
		(placement
			(enabled no)
			(sheetname "")
		)
		(fill yes
			(thermal_gap 0.5)
			(thermal_bridge_width 0.5)
			(island_removal_mode 0)
		)
		(polygon
			(pts
				(arc
					(start 333.141828 -432.560476)
					(mid 333.164146 -432.614358)
					(end 333.218028 -432.636676)
				)
				(arc
					(start 334.157828 -432.636676)
					(mid 334.21171 -432.614358)
					(end 334.234028 -432.560476)
				)
				(arc
					(start 334.234028 -430.018952)
					(mid 334.21171 -429.96507)
					(end 334.157828 -429.942752)
				)
				(arc
					(start 333.218028 -429.942752)
					(mid 333.164146 -429.96507)
					(end 333.141828 -430.018952)
				)
			)
		)
	)
	(zone
		(layers "In1.Cu" "In2.Cu" "In3.Cu" "In8.Cu" "In9.Cu" "In14.Cu" "In16.Cu")
		(hatch none 0.5)
		(connect_pads
			(clearance 0)
		)
		(min_thickness 0.25)
		(keepout
			(tracks not_allowed)
			(vias allowed)
			(pads allowed)
			(copperpour not_allowed)
			(footprints allowed)
		)
		(placement
			(enabled no)
			(sheetname "")
		)
		(fill yes
			(thermal_gap 0.5)
			(thermal_bridge_width 0.5)
			(island_removal_mode 0)
		)
		(polygon
			(pts
				(arc
					(start 341.141812 -432.560476)
					(mid 341.16413 -432.614358)
					(end 341.218012 -432.636676)
				)
				(arc
					(start 342.157812 -432.636676)
					(mid 342.211694 -432.614358)
					(end 342.234012 -432.560476)
				)
				(arc
					(start 342.234012 -430.018952)
					(mid 342.211694 -429.96507)
					(end 342.157812 -429.942752)
				)
				(arc
					(start 341.218012 -429.942752)
					(mid 341.16413 -429.96507)
					(end 341.141812 -430.018952)
				)
			)
		)
	)
	(zone
		(layers "In1.Cu" "In2.Cu" "In3.Cu" "In8.Cu" "In9.Cu" "In14.Cu" "In16.Cu")
		(hatch none 0.5)
		(connect_pads
			(clearance 0)
		)
		(min_thickness 0.25)
		(keepout
			(tracks not_allowed)
			(vias allowed)
			(pads allowed)
			(copperpour not_allowed)
			(footprints allowed)
		)
		(placement
			(enabled no)
			(sheetname "")
		)
		(fill yes
			(thermal_gap 0.5)
			(thermal_bridge_width 0.5)
			(island_removal_mode 0)
		)
		(polygon
			(pts
				(arc
					(start 408.241754 -432.560476)
					(mid 408.264072 -432.614358)
					(end 408.317954 -432.636676)
				)
				(arc
					(start 409.257754 -432.636676)
					(mid 409.311636 -432.614358)
					(end 409.333954 -432.560476)
				)
				(arc
					(start 409.333954 -430.018952)
					(mid 409.311636 -429.96507)
					(end 409.257754 -429.942752)
				)
				(arc
					(start 408.317954 -429.942752)
					(mid 408.264072 -429.96507)
					(end 408.241754 -430.018952)
				)
			)
		)
	)
	(zone
		(layers "In1.Cu" "In2.Cu" "In3.Cu" "In8.Cu" "In9.Cu" "In14.Cu" "In16.Cu")
		(hatch none 0.5)
		(connect_pads
			(clearance 0)
		)
		(min_thickness 0.25)
		(keepout
			(tracks not_allowed)
			(vias allowed)
			(pads allowed)
			(copperpour not_allowed)
			(footprints allowed)
		)
		(placement
			(enabled no)
			(sheetname "")
		)
		(fill yes
			(thermal_gap 0.5)
			(thermal_bridge_width 0.5)
			(island_removal_mode 0)
		)
		(polygon
			(pts
				(arc
					(start 393.241784 -431.560478)
					(mid 393.264102 -431.61436)
					(end 393.317984 -431.636678)
				)
				(arc
					(start 394.257784 -431.636678)
					(mid 394.311666 -431.61436)
					(end 394.333984 -431.560478)
				)
				(arc
					(start 394.333984 -429.018954)
					(mid 394.311666 -428.965072)
					(end 394.257784 -428.942754)
				)
				(arc
					(start 393.317984 -428.942754)
					(mid 393.264102 -428.965072)
					(end 393.241784 -429.018954)
				)
			)
		)
	)
	(zone
		(layers "In1.Cu" "In2.Cu" "In3.Cu" "In8.Cu" "In9.Cu" "In14.Cu" "In16.Cu")
		(hatch none 0.5)
		(connect_pads
			(clearance 0)
		)
		(min_thickness 0.25)
		(keepout
			(tracks not_allowed)
			(vias allowed)
			(pads allowed)
			(copperpour not_allowed)
			(footprints allowed)
		)
		(placement
			(enabled no)
			(sheetname "")
		)
		(fill yes
			(thermal_gap 0.5)
			(thermal_bridge_width 0.5)
			(island_removal_mode 0)
		)
		(polygon
			(pts
				(arc
					(start 395.24178 -432.560476)
					(mid 395.264098 -432.614358)
					(end 395.31798 -432.636676)
				)
				(arc
					(start 396.25778 -432.636676)
					(mid 396.311662 -432.614358)
					(end 396.33398 -432.560476)
				)
				(arc
					(start 396.33398 -430.018952)
					(mid 396.311662 -429.96507)
					(end 396.25778 -429.942752)
				)
				(arc
					(start 395.31798 -429.942752)
					(mid 395.264098 -429.96507)
					(end 395.24178 -430.018952)
				)
			)
		)
	)
	(zone
		(layers "In1.Cu" "In2.Cu" "In3.Cu" "In8.Cu" "In9.Cu" "In14.Cu" "In16.Cu")
		(hatch none 0.5)
		(connect_pads
			(clearance 0)
		)
		(min_thickness 0.25)
		(keepout
			(tracks not_allowed)
			(vias allowed)
			(pads allowed)
			(copperpour not_allowed)
			(footprints allowed)
		)
		(placement
			(enabled no)
			(sheetname "")
		)
		(fill yes
			(thermal_gap 0.5)
			(thermal_bridge_width 0.5)
			(island_removal_mode 0)
		)
		(polygon
			(pts
				(arc
					(start 385.2418 -431.560478)
					(mid 385.264118 -431.61436)
					(end 385.318 -431.636678)
				)
				(arc
					(start 386.2578 -431.636678)
					(mid 386.311682 -431.61436)
					(end 386.334 -431.560478)
				)
				(arc
					(start 386.334 -429.018954)
					(mid 386.311682 -428.965072)
					(end 386.2578 -428.942754)
				)
				(arc
					(start 385.318 -428.942754)
					(mid 385.264118 -428.965072)
					(end 385.2418 -429.018954)
				)
			)
		)
	)
	(zone
		(layers "In1.Cu" "In2.Cu" "In3.Cu" "In8.Cu" "In9.Cu" "In14.Cu" "In16.Cu")
		(hatch none 0.5)
		(connect_pads
			(clearance 0)
		)
		(min_thickness 0.25)
		(keepout
			(tracks not_allowed)
			(vias allowed)
			(pads allowed)
			(copperpour not_allowed)
			(footprints allowed)
		)
		(placement
			(enabled no)
			(sheetname "")
		)
		(fill yes
			(thermal_gap 0.5)
			(thermal_bridge_width 0.5)
			(island_removal_mode 0)
		)
		(polygon
			(pts
				(arc
					(start 381.241808 -431.560478)
					(mid 381.264126 -431.61436)
					(end 381.318008 -431.636678)
				)
				(arc
					(start 382.257808 -431.636678)
					(mid 382.31169 -431.61436)
					(end 382.334008 -431.560478)
				)
				(arc
					(start 382.334008 -429.018954)
					(mid 382.31169 -428.965072)
					(end 382.257808 -428.942754)
				)
				(arc
					(start 381.318008 -428.942754)
					(mid 381.264126 -428.965072)
					(end 381.241808 -429.018954)
				)
			)
		)
	)
	(zone
		(layers "In1.Cu" "In2.Cu" "In3.Cu" "In8.Cu" "In9.Cu" "In14.Cu" "In16.Cu")
		(hatch none 0.5)
		(connect_pads
			(clearance 0)
		)
		(min_thickness 0.25)
		(keepout
			(tracks not_allowed)
			(vias allowed)
			(pads allowed)
			(copperpour not_allowed)
			(footprints allowed)
		)
		(placement
			(enabled no)
			(sheetname "")
		)
		(fill yes
			(thermal_gap 0.5)
			(thermal_bridge_width 0.5)
			(island_removal_mode 0)
		)
		(polygon
			(pts
				(arc
					(start 345.141804 -432.560476)
					(mid 345.164122 -432.614358)
					(end 345.218004 -432.636676)
				)
				(arc
					(start 346.157804 -432.636676)
					(mid 346.211686 -432.614358)
					(end 346.234004 -432.560476)
				)
				(arc
					(start 346.234004 -430.018952)
					(mid 346.211686 -429.96507)
					(end 346.157804 -429.942752)
				)
				(arc
					(start 345.218004 -429.942752)
					(mid 345.164122 -429.96507)
					(end 345.141804 -430.018952)
				)
			)
		)
	)
	(zone
		(layers "In1.Cu" "In2.Cu" "In3.Cu" "In8.Cu" "In9.Cu" "In14.Cu" "In16.Cu")
		(hatch none 0.5)
		(connect_pads
			(clearance 0)
		)
		(min_thickness 0.25)
		(keepout
			(tracks not_allowed)
			(vias allowed)
			(pads allowed)
			(copperpour not_allowed)
			(footprints allowed)
		)
		(placement
			(enabled no)
			(sheetname "")
		)
		(fill yes
			(thermal_gap 0.5)
			(thermal_bridge_width 0.5)
			(island_removal_mode 0)
		)
		(polygon
			(pts
				(arc
					(start 389.241792 -431.560478)
					(mid 389.26411 -431.61436)
					(end 389.317992 -431.636678)
				)
				(arc
					(start 390.257792 -431.636678)
					(mid 390.311674 -431.61436)
					(end 390.333992 -431.560478)
				)
				(arc
					(start 390.333992 -429.018954)
					(mid 390.311674 -428.965072)
					(end 390.257792 -428.942754)
				)
				(arc
					(start 389.317992 -428.942754)
					(mid 389.26411 -428.965072)
					(end 389.241792 -429.018954)
				)
			)
		)
	)
	(zone
		(layers "In1.Cu" "In2.Cu" "In3.Cu" "In8.Cu" "In9.Cu" "In14.Cu" "In16.Cu")
		(hatch none 0.5)
		(connect_pads
			(clearance 0)
		)
		(min_thickness 0.25)
		(keepout
			(tracks not_allowed)
			(vias allowed)
			(pads allowed)
			(copperpour not_allowed)
			(footprints allowed)
		)
		(placement
			(enabled no)
			(sheetname "")
		)
		(fill yes
			(thermal_gap 0.5)
			(thermal_bridge_width 0.5)
			(island_removal_mode 0)
		)
		(polygon
			(pts
				(arc
					(start 406.241758 -431.560478)
					(mid 406.264076 -431.61436)
					(end 406.317958 -431.636678)
				)
				(arc
					(start 407.257758 -431.636678)
					(mid 407.31164 -431.61436)
					(end 407.333958 -431.560478)
				)
				(arc
					(start 407.333958 -429.018954)
					(mid 407.31164 -428.965072)
					(end 407.257758 -428.942754)
				)
				(arc
					(start 406.317958 -428.942754)
					(mid 406.264076 -428.965072)
					(end 406.241758 -429.018954)
				)
			)
		)
	)
	(zone
		(layers "In1.Cu" "In2.Cu" "In3.Cu" "In8.Cu" "In9.Cu" "In14.Cu" "In16.Cu")
		(hatch none 0.5)
		(connect_pads
			(clearance 0)
		)
		(min_thickness 0.25)
		(keepout
			(tracks not_allowed)
			(vias allowed)
			(pads allowed)
			(copperpour not_allowed)
			(footprints allowed)
		)
		(placement
			(enabled no)
			(sheetname "")
		)
		(fill yes
			(thermal_gap 0.5)
			(thermal_bridge_width 0.5)
			(island_removal_mode 0)
		)
		(polygon
			(pts
				(arc
					(start 404.241762 -432.560476)
					(mid 404.26408 -432.614358)
					(end 404.317962 -432.636676)
				)
				(arc
					(start 405.257762 -432.636676)
					(mid 405.311644 -432.614358)
					(end 405.333962 -432.560476)
				)
				(arc
					(start 405.333962 -430.018952)
					(mid 405.311644 -429.96507)
					(end 405.257762 -429.942752)
				)
				(arc
					(start 404.317962 -429.942752)
					(mid 404.26408 -429.96507)
					(end 404.241762 -430.018952)
				)
			)
		)
	)
	(zone
		(layers "In1.Cu" "In2.Cu" "In3.Cu" "In8.Cu" "In9.Cu" "In14.Cu" "In16.Cu")
		(hatch none 0.5)
		(connect_pads
			(clearance 0)
		)
		(min_thickness 0.25)
		(keepout
			(tracks not_allowed)
			(vias allowed)
			(pads allowed)
			(copperpour not_allowed)
			(footprints allowed)
		)
		(placement
			(enabled no)
			(sheetname "")
		)
		(fill yes
			(thermal_gap 0.5)
			(thermal_bridge_width 0.5)
			(island_removal_mode 0)
		)
		(polygon
			(pts
				(arc
					(start 331.141832 -431.560478)
					(mid 331.16415 -431.61436)
					(end 331.218032 -431.636678)
				)
				(arc
					(start 332.157832 -431.636678)
					(mid 332.211714 -431.61436)
					(end 332.234032 -431.560478)
				)
				(arc
					(start 332.234032 -429.018954)
					(mid 332.211714 -428.965072)
					(end 332.157832 -428.942754)
				)
				(arc
					(start 331.218032 -428.942754)
					(mid 331.16415 -428.965072)
					(end 331.141832 -429.018954)
				)
			)
		)
	)
	(zone
		(layers "In1.Cu" "In2.Cu" "In3.Cu" "In8.Cu" "In9.Cu" "In14.Cu" "In16.Cu")
		(hatch none 0.5)
		(connect_pads
			(clearance 0)
		)
		(min_thickness 0.25)
		(keepout
			(tracks not_allowed)
			(vias allowed)
			(pads allowed)
			(copperpour not_allowed)
			(footprints allowed)
		)
		(placement
			(enabled no)
			(sheetname "")
		)
		(fill yes
			(thermal_gap 0.5)
			(thermal_bridge_width 0.5)
			(island_removal_mode 0)
		)
		(polygon
			(pts
				(arc
					(start 383.241804 -432.560476)
					(mid 383.264122 -432.614358)
					(end 383.318004 -432.636676)
				)
				(arc
					(start 384.257804 -432.636676)
					(mid 384.311686 -432.614358)
					(end 384.334004 -432.560476)
				)
				(arc
					(start 384.334004 -430.018952)
					(mid 384.311686 -429.96507)
					(end 384.257804 -429.942752)
				)
				(arc
					(start 383.318004 -429.942752)
					(mid 383.264122 -429.96507)
					(end 383.241804 -430.018952)
				)
			)
		)
	)
	(zone
		(layers "In1.Cu" "In2.Cu" "In3.Cu" "In8.Cu" "In9.Cu" "In14.Cu" "In16.Cu")
		(hatch none 0.5)
		(connect_pads
			(clearance 0)
		)
		(min_thickness 0.25)
		(keepout
			(tracks not_allowed)
			(vias allowed)
			(pads allowed)
			(copperpour not_allowed)
			(footprints allowed)
		)
		(placement
			(enabled no)
			(sheetname "")
		)
		(fill yes
			(thermal_gap 0.5)
			(thermal_bridge_width 0.5)
			(island_removal_mode 0)
		)
		(polygon
			(pts
				(arc
					(start 339.141816 -431.560478)
					(mid 339.164134 -431.61436)
					(end 339.218016 -431.636678)
				)
				(arc
					(start 340.157816 -431.636678)
					(mid 340.211698 -431.61436)
					(end 340.234016 -431.560478)
				)
				(arc
					(start 340.234016 -429.018954)
					(mid 340.211698 -428.965072)
					(end 340.157816 -428.942754)
				)
				(arc
					(start 339.218016 -428.942754)
					(mid 339.164134 -428.965072)
					(end 339.141816 -429.018954)
				)
			)
		)
	)
	(zone
		(layers "In1.Cu" "In2.Cu" "In3.Cu" "In8.Cu" "In9.Cu" "In14.Cu" "In16.Cu")
		(hatch none 0.5)
		(connect_pads
			(clearance 0)
		)
		(min_thickness 0.25)
		(keepout
			(tracks not_allowed)
			(vias allowed)
			(pads allowed)
			(copperpour not_allowed)
			(footprints allowed)
		)
		(placement
			(enabled no)
			(sheetname "")
		)
		(fill yes
			(thermal_gap 0.5)
			(thermal_bridge_width 0.5)
			(island_removal_mode 0)
		)
		(polygon
			(pts
				(arc
					(start 402.241766 -431.560478)
					(mid 402.264084 -431.61436)
					(end 402.317966 -431.636678)
				)
				(arc
					(start 403.257766 -431.636678)
					(mid 403.311648 -431.61436)
					(end 403.333966 -431.560478)
				)
				(arc
					(start 403.333966 -429.018954)
					(mid 403.311648 -428.965072)
					(end 403.257766 -428.942754)
				)
				(arc
					(start 402.317966 -428.942754)
					(mid 402.264084 -428.965072)
					(end 402.241766 -429.018954)
				)
			)
		)
	)
	(zone
		(layers "In1.Cu" "In2.Cu" "In3.Cu" "In8.Cu" "In9.Cu" "In14.Cu" "In16.Cu")
		(hatch none 0.5)
		(connect_pads
			(clearance 0)
		)
		(min_thickness 0.25)
		(keepout
			(tracks not_allowed)
			(vias allowed)
			(pads allowed)
			(copperpour not_allowed)
			(footprints allowed)
		)
		(placement
			(enabled no)
			(sheetname "")
		)
		(fill yes
			(thermal_gap 0.5)
			(thermal_bridge_width 0.5)
			(island_removal_mode 0)
		)
		(polygon
			(pts
				(arc
					(start 343.141808 -431.560478)
					(mid 343.164126 -431.61436)
					(end 343.218008 -431.636678)
				)
				(arc
					(start 344.157808 -431.636678)
					(mid 344.21169 -431.61436)
					(end 344.234008 -431.560478)
				)
				(arc
					(start 344.234008 -429.018954)
					(mid 344.21169 -428.965072)
					(end 344.157808 -428.942754)
				)
				(arc
					(start 343.218008 -428.942754)
					(mid 343.164126 -428.965072)
					(end 343.141808 -429.018954)
				)
			)
		)
	)
	(zone
		(layers "In1.Cu" "In2.Cu" "In3.Cu" "In8.Cu" "In9.Cu" "In14.Cu" "In16.Cu")
		(hatch none 0.5)
		(connect_pads
			(clearance 0)
		)
		(min_thickness 0.25)
		(keepout
			(tracks not_allowed)
			(vias allowed)
			(pads allowed)
			(copperpour not_allowed)
			(footprints allowed)
		)
		(placement
			(enabled no)
			(sheetname "")
		)
		(fill yes
			(thermal_gap 0.5)
			(thermal_bridge_width 0.5)
			(island_removal_mode 0)
		)
		(polygon
			(pts
				(arc
					(start 398.241774 -431.560478)
					(mid 398.264092 -431.61436)
					(end 398.317974 -431.636678)
				)
				(arc
					(start 399.257774 -431.636678)
					(mid 399.311656 -431.61436)
					(end 399.333974 -431.560478)
				)
				(arc
					(start 399.333974 -429.018954)
					(mid 399.311656 -428.965072)
					(end 399.257774 -428.942754)
				)
				(arc
					(start 398.317974 -428.942754)
					(mid 398.264092 -428.965072)
					(end 398.241774 -429.018954)
				)
			)
		)
	)
	(zone
		(layers "In1.Cu" "In2.Cu" "In3.Cu" "In8.Cu" "In9.Cu" "In14.Cu" "In16.Cu")
		(hatch none 0.5)
		(connect_pads
			(clearance 0)
		)
		(min_thickness 0.25)
		(keepout
			(tracks not_allowed)
			(vias allowed)
			(pads allowed)
			(copperpour not_allowed)
			(footprints allowed)
		)
		(placement
			(enabled no)
			(sheetname "")
		)
		(fill yes
			(thermal_gap 0.5)
			(thermal_bridge_width 0.5)
			(island_removal_mode 0)
		)
		(polygon
			(pts
				(arc
					(start 387.241796 -432.560476)
					(mid 387.264114 -432.614358)
					(end 387.317996 -432.636676)
				)
				(arc
					(start 388.257796 -432.636676)
					(mid 388.311678 -432.614358)
					(end 388.333996 -432.560476)
				)
				(arc
					(start 388.333996 -430.018952)
					(mid 388.311678 -429.96507)
					(end 388.257796 -429.942752)
				)
				(arc
					(start 387.317996 -429.942752)
					(mid 387.264114 -429.96507)
					(end 387.241796 -430.018952)
				)
			)
		)
	)
	(zone
		(layers "In1.Cu" "In2.Cu" "In3.Cu" "In8.Cu" "In9.Cu" "In14.Cu" "In16.Cu")
		(hatch none 0.5)
		(connect_pads
			(clearance 0)
		)
		(min_thickness 0.25)
		(keepout
			(tracks not_allowed)
			(vias allowed)
			(pads allowed)
			(copperpour not_allowed)
			(footprints allowed)
		)
		(placement
			(enabled no)
			(sheetname "")
		)
		(fill yes
			(thermal_gap 0.5)
			(thermal_bridge_width 0.5)
			(island_removal_mode 0)
		)
		(polygon
			(pts
				(arc
					(start 391.241788 -432.560476)
					(mid 391.264106 -432.614358)
					(end 391.317988 -432.636676)
				)
				(arc
					(start 392.257788 -432.636676)
					(mid 392.31167 -432.614358)
					(end 392.333988 -432.560476)
				)
				(arc
					(start 392.333988 -430.018952)
					(mid 392.31167 -429.96507)
					(end 392.257788 -429.942752)
				)
				(arc
					(start 391.317988 -429.942752)
					(mid 391.264106 -429.96507)
					(end 391.241788 -430.018952)
				)
			)
		)
	)
	(zone
		(layers "In1.Cu" "In2.Cu" "In3.Cu" "In8.Cu" "In9.Cu" "In14.Cu" "In16.Cu")
		(hatch none 0.5)
		(connect_pads
			(clearance 0)
		)
		(min_thickness 0.25)
		(keepout
			(tracks not_allowed)
			(vias allowed)
			(pads allowed)
			(copperpour not_allowed)
			(footprints allowed)
		)
		(placement
			(enabled no)
			(sheetname "")
		)
		(fill yes
			(thermal_gap 0.5)
			(thermal_bridge_width 0.5)
			(island_removal_mode 0)
		)
		(polygon
			(pts
				(arc
					(start 410.24175 -431.560478)
					(mid 410.264068 -431.61436)
					(end 410.31795 -431.636678)
				)
				(arc
					(start 411.25775 -431.636678)
					(mid 411.311632 -431.61436)
					(end 411.33395 -431.560478)
				)
				(arc
					(start 411.33395 -429.018954)
					(mid 411.311632 -428.965072)
					(end 411.25775 -428.942754)
				)
				(arc
					(start 410.31795 -428.942754)
					(mid 410.264068 -428.965072)
					(end 410.24175 -429.018954)
				)
			)
		)
	)
	(zone
		(layers "In1.Cu" "In2.Cu" "In3.Cu" "In8.Cu" "In9.Cu" "In14.Cu" "In16.Cu")
		(hatch none 0.5)
		(connect_pads
			(clearance 0)
		)
		(min_thickness 0.25)
		(keepout
			(tracks not_allowed)
			(vias allowed)
			(pads allowed)
			(copperpour not_allowed)
			(footprints allowed)
		)
		(placement
			(enabled no)
			(sheetname "")
		)
		(fill yes
			(thermal_gap 0.5)
			(thermal_bridge_width 0.5)
			(island_removal_mode 0)
		)
		(polygon
			(pts
				(arc
					(start 400.24177 -432.560476)
					(mid 400.264088 -432.614358)
					(end 400.31797 -432.636676)
				)
				(arc
					(start 401.25777 -432.636676)
					(mid 401.311652 -432.614358)
					(end 401.33397 -432.560476)
				)
				(arc
					(start 401.33397 -430.018952)
					(mid 401.311652 -429.96507)
					(end 401.25777 -429.942752)
				)
				(arc
					(start 400.31797 -429.942752)
					(mid 400.264088 -429.96507)
					(end 400.24177 -430.018952)
				)
			)
		)
	)
	(zone
		(layers "In1.Cu" "In2.Cu" "In3.Cu" "In8.Cu" "In9.Cu" "In14.Cu" "In16.Cu")
		(hatch none 0.5)
		(connect_pads
			(clearance 0)
		)
		(min_thickness 0.25)
		(keepout
			(tracks not_allowed)
			(vias allowed)
			(pads allowed)
			(copperpour not_allowed)
			(footprints allowed)
		)
		(placement
			(enabled no)
			(sheetname "")
		)
		(fill yes
			(thermal_gap 0.5)
			(thermal_bridge_width 0.5)
			(island_removal_mode 0)
		)
		(polygon
			(pts
				(arc
					(start 337.14182 -432.560476)
					(mid 337.164138 -432.614358)
					(end 337.21802 -432.636676)
				)
				(arc
					(start 338.15782 -432.636676)
					(mid 338.211702 -432.614358)
					(end 338.23402 -432.560476)
				)
				(arc
					(start 338.23402 -430.018952)
					(mid 338.211702 -429.96507)
					(end 338.15782 -429.942752)
				)
				(arc
					(start 337.21802 -429.942752)
					(mid 337.164138 -429.96507)
					(end 337.14182 -430.018952)
				)
			)
		)
	)
	(zone
		(layers "In1.Cu" "In2.Cu" "In3.Cu" "In8.Cu" "In9.Cu" "In16.Cu")
		(hatch none 0.5)
		(connect_pads
			(clearance 0)
		)
		(min_thickness 0.25)
		(keepout
			(tracks not_allowed)
			(vias allowed)
			(pads allowed)
			(copperpour not_allowed)
			(footprints allowed)
		)
		(placement
			(enabled no)
			(sheetname "")
		)
		(fill yes
			(thermal_gap 0.5)
			(thermal_bridge_width 0.5)
			(island_removal_mode 0)
		)
		(polygon
			(pts
				(arc
					(start 154.241754 -431.560478)
					(mid 154.264072 -431.61436)
					(end 154.317954 -431.636678)
				)
				(arc
					(start 155.257754 -431.636678)
					(mid 155.311636 -431.61436)
					(end 155.333954 -431.560478)
				)
				(arc
					(start 155.333954 -429.018954)
					(mid 155.311636 -428.965072)
					(end 155.257754 -428.942754)
				)
				(arc
					(start 154.317954 -428.942754)
					(mid 154.264072 -428.965072)
					(end 154.241754 -429.018954)
				)
			)
		)
	)
	(zone
		(layers "In1.Cu" "In2.Cu" "In3.Cu" "In8.Cu" "In9.Cu" "In16.Cu")
		(hatch none 0.5)
		(connect_pads
			(clearance 0)
		)
		(min_thickness 0.25)
		(keepout
			(tracks not_allowed)
			(vias allowed)
			(pads allowed)
			(copperpour not_allowed)
			(footprints allowed)
		)
		(placement
			(enabled no)
			(sheetname "")
		)
		(fill yes
			(thermal_gap 0.5)
			(thermal_bridge_width 0.5)
			(island_removal_mode 0)
		)
		(polygon
			(pts
				(arc
					(start 148.241766 -432.560476)
					(mid 148.264084 -432.614358)
					(end 148.317966 -432.636676)
				)
				(arc
					(start 149.257766 -432.636676)
					(mid 149.311648 -432.614358)
					(end 149.333966 -432.560476)
				)
				(arc
					(start 149.333966 -430.018952)
					(mid 149.311648 -429.96507)
					(end 149.257766 -429.942752)
				)
				(arc
					(start 148.317966 -429.942752)
					(mid 148.264084 -429.96507)
					(end 148.241766 -430.018952)
				)
			)
		)
	)
	(zone
		(layers "In1.Cu" "In2.Cu" "In3.Cu" "In8.Cu" "In9.Cu" "In16.Cu")
		(hatch none 0.5)
		(connect_pads
			(clearance 0)
		)
		(min_thickness 0.25)
		(keepout
			(tracks not_allowed)
			(vias allowed)
			(pads allowed)
			(copperpour not_allowed)
			(footprints allowed)
		)
		(placement
			(enabled no)
			(sheetname "")
		)
		(fill yes
			(thermal_gap 0.5)
			(thermal_bridge_width 0.5)
			(island_removal_mode 0)
		)
		(polygon
			(pts
				(arc
					(start 156.24175 -432.560476)
					(mid 156.264068 -432.614358)
					(end 156.31795 -432.636676)
				)
				(arc
					(start 157.25775 -432.636676)
					(mid 157.311632 -432.614358)
					(end 157.33395 -432.560476)
				)
				(arc
					(start 157.33395 -430.018952)
					(mid 157.311632 -429.96507)
					(end 157.25775 -429.942752)
				)
				(arc
					(start 156.31795 -429.942752)
					(mid 156.264068 -429.96507)
					(end 156.24175 -430.018952)
				)
			)
		)
	)
	(zone
		(layers "In1.Cu" "In2.Cu" "In3.Cu" "In8.Cu" "In9.Cu" "In16.Cu")
		(hatch none 0.5)
		(connect_pads
			(clearance 0)
		)
		(min_thickness 0.25)
		(keepout
			(tracks not_allowed)
			(vias allowed)
			(pads allowed)
			(copperpour not_allowed)
			(footprints allowed)
		)
		(placement
			(enabled no)
			(sheetname "")
		)
		(fill yes
			(thermal_gap 0.5)
			(thermal_bridge_width 0.5)
			(island_removal_mode 0)
		)
		(polygon
			(pts
				(arc
					(start 146.24177 -431.560478)
					(mid 146.264088 -431.61436)
					(end 146.31797 -431.636678)
				)
				(arc
					(start 147.25777 -431.636678)
					(mid 147.311652 -431.61436)
					(end 147.33397 -431.560478)
				)
				(arc
					(start 147.33397 -429.018954)
					(mid 147.311652 -428.965072)
					(end 147.25777 -428.942754)
				)
				(arc
					(start 146.31797 -428.942754)
					(mid 146.264088 -428.965072)
					(end 146.24177 -429.018954)
				)
			)
		)
	)
	(zone
		(layers "In1.Cu" "In2.Cu" "In3.Cu" "In8.Cu" "In9.Cu" "In16.Cu")
		(hatch none 0.5)
		(connect_pads
			(clearance 0)
		)
		(min_thickness 0.25)
		(keepout
			(tracks not_allowed)
			(vias allowed)
			(pads allowed)
			(copperpour not_allowed)
			(footprints allowed)
		)
		(placement
			(enabled no)
			(sheetname "")
		)
		(fill yes
			(thermal_gap 0.5)
			(thermal_bridge_width 0.5)
			(island_removal_mode 0)
		)
		(polygon
			(pts
				(arc
					(start 144.241774 -432.560476)
					(mid 144.264092 -432.614358)
					(end 144.317974 -432.636676)
				)
				(arc
					(start 145.257774 -432.636676)
					(mid 145.311656 -432.614358)
					(end 145.333974 -432.560476)
				)
				(arc
					(start 145.333974 -430.018952)
					(mid 145.311656 -429.96507)
					(end 145.257774 -429.942752)
				)
				(arc
					(start 144.317974 -429.942752)
					(mid 144.264092 -429.96507)
					(end 144.241774 -430.018952)
				)
			)
		)
	)
	(zone
		(layers "In1.Cu" "In2.Cu" "In3.Cu" "In8.Cu" "In9.Cu" "In16.Cu")
		(hatch none 0.5)
		(connect_pads
			(clearance 0)
		)
		(min_thickness 0.25)
		(keepout
			(tracks not_allowed)
			(vias allowed)
			(pads allowed)
			(copperpour not_allowed)
			(footprints allowed)
		)
		(placement
			(enabled no)
			(sheetname "")
		)
		(fill yes
			(thermal_gap 0.5)
			(thermal_bridge_width 0.5)
			(island_removal_mode 0)
		)
		(polygon
			(pts
				(arc
					(start 142.241778 -431.560478)
					(mid 142.264096 -431.61436)
					(end 142.317978 -431.636678)
				)
				(arc
					(start 143.257778 -431.636678)
					(mid 143.31166 -431.61436)
					(end 143.333978 -431.560478)
				)
				(arc
					(start 143.333978 -429.018954)
					(mid 143.31166 -428.965072)
					(end 143.257778 -428.942754)
				)
				(arc
					(start 142.317978 -428.942754)
					(mid 142.264096 -428.965072)
					(end 142.241778 -429.018954)
				)
			)
		)
	)
	(zone
		(layers "In1.Cu" "In2.Cu" "In3.Cu" "In8.Cu" "In9.Cu" "In16.Cu")
		(hatch none 0.5)
		(connect_pads
			(clearance 0)
		)
		(min_thickness 0.25)
		(keepout
			(tracks not_allowed)
			(vias allowed)
			(pads allowed)
			(copperpour not_allowed)
			(footprints allowed)
		)
		(placement
			(enabled no)
			(sheetname "")
		)
		(fill yes
			(thermal_gap 0.5)
			(thermal_bridge_width 0.5)
			(island_removal_mode 0)
		)
		(polygon
			(pts
				(arc
					(start 152.241758 -432.560476)
					(mid 152.264076 -432.614358)
					(end 152.317958 -432.636676)
				)
				(arc
					(start 153.257758 -432.636676)
					(mid 153.31164 -432.614358)
					(end 153.333958 -432.560476)
				)
				(arc
					(start 153.333958 -430.018952)
					(mid 153.31164 -429.96507)
					(end 153.257758 -429.942752)
				)
				(arc
					(start 152.317958 -429.942752)
					(mid 152.264076 -429.96507)
					(end 152.241758 -430.018952)
				)
			)
		)
	)
	(zone
		(layers "In1.Cu" "In2.Cu" "In3.Cu" "In8.Cu" "In9.Cu" "In16.Cu")
		(hatch none 0.5)
		(connect_pads
			(clearance 0)
		)
		(min_thickness 0.25)
		(keepout
			(tracks not_allowed)
			(vias allowed)
			(pads allowed)
			(copperpour not_allowed)
			(footprints allowed)
		)
		(placement
			(enabled no)
			(sheetname "")
		)
		(fill yes
			(thermal_gap 0.5)
			(thermal_bridge_width 0.5)
			(island_removal_mode 0)
		)
		(polygon
			(pts
				(arc
					(start 150.241762 -431.560478)
					(mid 150.26408 -431.61436)
					(end 150.317962 -431.636678)
				)
				(arc
					(start 151.257762 -431.636678)
					(mid 151.311644 -431.61436)
					(end 151.333962 -431.560478)
				)
				(arc
					(start 151.333962 -429.018954)
					(mid 151.311644 -428.965072)
					(end 151.257762 -428.942754)
				)
				(arc
					(start 150.317962 -428.942754)
					(mid 150.26408 -428.965072)
					(end 150.241762 -429.018954)
				)
			)
		)
	)
	(zone
		(layers "In1.Cu" "In2.Cu" "In4.Cu" "In6.Cu")
		(hatch none 0.5)
		(connect_pads
			(clearance 0)
		)
		(min_thickness 0.25)
		(keepout
			(tracks not_allowed)
			(vias allowed)
			(pads allowed)
			(copperpour not_allowed)
			(footprints allowed)
		)
		(placement
			(enabled no)
			(sheetname "")
		)
		(fill yes
			(thermal_gap 0.5)
			(thermal_bridge_width 0.5)
			(island_removal_mode 0)
		)
		(polygon
			(pts
				(arc
					(start 100.80117 -285.93161)
					(mid 100.49637 -286.23641)
					(end 100.80117 -286.54121)
				)
				(arc
					(start 101.741224 -286.54121)
					(mid 102.046024 -286.23641)
					(end 101.741224 -285.93161)
				)
			)
		)
	)
	(zone
		(layers "In1.Cu" "In2.Cu" "In4.Cu" "In6.Cu")
		(hatch none 0.5)
		(connect_pads
			(clearance 0)
		)
		(min_thickness 0.25)
		(keepout
			(tracks not_allowed)
			(vias allowed)
			(pads allowed)
			(copperpour not_allowed)
			(footprints allowed)
		)
		(placement
			(enabled no)
			(sheetname "")
		)
		(fill yes
			(thermal_gap 0.5)
			(thermal_bridge_width 0.5)
			(island_removal_mode 0)
		)
		(polygon
			(pts
				(arc
					(start 106.440986 -284.311598)
					(mid 106.136186 -284.616398)
					(end 106.440986 -284.921198)
				)
				(arc
					(start 107.38104 -284.921198)
					(mid 107.68584 -284.616398)
					(end 107.38104 -284.311598)
				)
			)
		)
	)
	(zone
		(layers "In1.Cu" "In2.Cu" "In4.Cu" "In6.Cu")
		(hatch none 0.5)
		(connect_pads
			(clearance 0)
		)
		(min_thickness 0.25)
		(keepout
			(tracks not_allowed)
			(vias allowed)
			(pads allowed)
			(copperpour not_allowed)
			(footprints allowed)
		)
		(placement
			(enabled no)
			(sheetname "")
		)
		(fill yes
			(thermal_gap 0.5)
			(thermal_bridge_width 0.5)
			(island_removal_mode 0)
		)
		(polygon
			(pts
				(arc
					(start 100.80117 -282.691586)
					(mid 100.49637 -282.996386)
					(end 100.80117 -283.301186)
				)
				(arc
					(start 101.741224 -283.301186)
					(mid 102.046024 -282.996386)
					(end 101.741224 -282.691586)
				)
			)
		)
	)
	(zone
		(layers "In1.Cu" "In2.Cu" "In4.Cu" "In6.Cu")
		(hatch none 0.5)
		(connect_pads
			(clearance 0)
		)
		(min_thickness 0.25)
		(keepout
			(tracks not_allowed)
			(vias allowed)
			(pads allowed)
			(copperpour not_allowed)
			(footprints allowed)
		)
		(placement
			(enabled no)
			(sheetname "")
		)
		(fill yes
			(thermal_gap 0.5)
			(thermal_bridge_width 0.5)
			(island_removal_mode 0)
		)
		(polygon
			(pts
				(arc
					(start 103.621078 -282.691586)
					(mid 103.316278 -282.996386)
					(end 103.621078 -283.301186)
				)
				(arc
					(start 104.561132 -283.301186)
					(mid 104.865932 -282.996386)
					(end 104.561132 -282.691586)
				)
			)
		)
	)
	(zone
		(layers "In1.Cu" "In2.Cu" "In4.Cu" "In6.Cu")
		(hatch none 0.5)
		(connect_pads
			(clearance 0)
		)
		(min_thickness 0.25)
		(keepout
			(tracks not_allowed)
			(vias allowed)
			(pads allowed)
			(copperpour not_allowed)
			(footprints allowed)
		)
		(placement
			(enabled no)
			(sheetname "")
		)
		(fill yes
			(thermal_gap 0.5)
			(thermal_bridge_width 0.5)
			(island_removal_mode 0)
		)
		(polygon
			(pts
				(arc
					(start 108.49102 -248.229628)
					(mid 108.18622 -248.534428)
					(end 108.49102 -248.839228)
				)
				(arc
					(start 109.431074 -248.839228)
					(mid 109.735874 -248.534428)
					(end 109.431074 -248.229628)
				)
			)
		)
	)
	(zone
		(layers "In1.Cu" "In2.Cu" "In4.Cu" "In6.Cu")
		(hatch none 0.5)
		(connect_pads
			(clearance 0)
		)
		(min_thickness 0.25)
		(keepout
			(tracks not_allowed)
			(vias allowed)
			(pads allowed)
			(copperpour not_allowed)
			(footprints allowed)
		)
		(placement
			(enabled no)
			(sheetname "")
		)
		(fill yes
			(thermal_gap 0.5)
			(thermal_bridge_width 0.5)
			(island_removal_mode 0)
		)
		(polygon
			(pts
				(arc
					(start 362.064808 -244.98935)
					(mid 361.760008 -245.29415)
					(end 362.064808 -245.59895)
				)
				(arc
					(start 363.004862 -245.59895)
					(mid 363.309662 -245.29415)
					(end 363.004862 -244.98935)
				)
			)
		)
	)
	(zone
		(layers "In1.Cu" "In2.Cu" "In4.Cu" "In6.Cu")
		(hatch none 0.5)
		(connect_pads
			(clearance 0)
		)
		(min_thickness 0.25)
		(keepout
			(tracks not_allowed)
			(vias allowed)
			(pads allowed)
			(copperpour not_allowed)
			(footprints allowed)
		)
		(placement
			(enabled no)
			(sheetname "")
		)
		(fill yes
			(thermal_gap 0.5)
			(thermal_bridge_width 0.5)
			(island_removal_mode 0)
		)
		(polygon
			(pts
				(arc
					(start 354.381054 -282.691332)
					(mid 354.076254 -282.996132)
					(end 354.381054 -283.300932)
				)
				(arc
					(start 355.321108 -283.300932)
					(mid 355.625908 -282.996132)
					(end 355.321108 -282.691332)
				)
			)
		)
	)
	(zone
		(layers "In1.Cu" "In2.Cu" "In4.Cu" "In6.Cu")
		(hatch none 0.5)
		(connect_pads
			(clearance 0)
		)
		(min_thickness 0.25)
		(keepout
			(tracks not_allowed)
			(vias allowed)
			(pads allowed)
			(copperpour not_allowed)
			(footprints allowed)
		)
		(placement
			(enabled no)
			(sheetname "")
		)
		(fill yes
			(thermal_gap 0.5)
			(thermal_bridge_width 0.5)
			(island_removal_mode 0)
		)
		(polygon
			(pts
				(arc
					(start 348.741238 -285.931356)
					(mid 348.436438 -286.236156)
					(end 348.741238 -286.540956)
				)
				(arc
					(start 349.681292 -286.540956)
					(mid 349.986092 -286.236156)
					(end 349.681292 -285.931356)
				)
			)
		)
	)
	(zone
		(layers "In1.Cu" "In2.Cu" "In4.Cu" "In6.Cu")
		(hatch none 0.5)
		(connect_pads
			(clearance 0)
		)
		(min_thickness 0.25)
		(keepout
			(tracks not_allowed)
			(vias allowed)
			(pads allowed)
			(copperpour not_allowed)
			(footprints allowed)
		)
		(placement
			(enabled no)
			(sheetname "")
		)
		(fill yes
			(thermal_gap 0.5)
			(thermal_bridge_width 0.5)
			(island_removal_mode 0)
		)
		(polygon
			(pts
				(arc
					(start 362.064808 -248.229374)
					(mid 361.760008 -248.534174)
					(end 362.064808 -248.838974)
				)
				(arc
					(start 363.004862 -248.838974)
					(mid 363.309662 -248.534174)
					(end 363.004862 -248.229374)
				)
			)
		)
	)
	(zone
		(layers "In1.Cu" "In2.Cu" "In4.Cu" "In6.Cu")
		(hatch none 0.5)
		(connect_pads
			(clearance 0)
		)
		(min_thickness 0.25)
		(keepout
			(tracks not_allowed)
			(vias allowed)
			(pads allowed)
			(copperpour not_allowed)
			(footprints allowed)
		)
		(placement
			(enabled no)
			(sheetname "")
		)
		(fill yes
			(thermal_gap 0.5)
			(thermal_bridge_width 0.5)
			(island_removal_mode 0)
		)
		(polygon
			(pts
				(arc
					(start 345.921076 -281.07132)
					(mid 345.616276 -281.37612)
					(end 345.921076 -281.68092)
				)
				(arc
					(start 346.86113 -281.68092)
					(mid 347.16593 -281.37612)
					(end 346.86113 -281.07132)
				)
			)
		)
	)
	(zone
		(layers "In1.Cu" "In2.Cu" "In4.Cu" "In6.Cu")
		(hatch none 0.5)
		(connect_pads
			(clearance 0)
		)
		(min_thickness 0.25)
		(keepout
			(tracks not_allowed)
			(vias allowed)
			(pads allowed)
			(copperpour not_allowed)
			(footprints allowed)
		)
		(placement
			(enabled no)
			(sheetname "")
		)
		(fill yes
			(thermal_gap 0.5)
			(thermal_bridge_width 0.5)
			(island_removal_mode 0)
		)
		(polygon
			(pts
				(arc
					(start 106.141012 -245.79961)
					(mid 105.836212 -246.10441)
					(end 106.141012 -246.40921)
				)
				(arc
					(start 107.081066 -246.40921)
					(mid 107.385866 -246.10441)
					(end 107.081066 -245.79961)
				)
			)
		)
	)
	(zone
		(layers "In1.Cu" "In2.Cu" "In4.Cu" "In6.Cu")
		(hatch none 0.5)
		(connect_pads
			(clearance 0)
		)
		(min_thickness 0.25)
		(keepout
			(tracks not_allowed)
			(vias allowed)
			(pads allowed)
			(copperpour not_allowed)
			(footprints allowed)
		)
		(placement
			(enabled no)
			(sheetname "")
		)
		(fill yes
			(thermal_gap 0.5)
			(thermal_bridge_width 0.5)
			(island_removal_mode 0)
		)
		(polygon
			(pts
				(arc
					(start 367.234724 -247.419368)
					(mid 366.929924 -247.724168)
					(end 367.234724 -248.028968)
				)
				(arc
					(start 368.174778 -248.028968)
					(mid 368.479578 -247.724168)
					(end 368.174778 -247.419368)
				)
			)
		)
	)
	(zone
		(layers "In1.Cu" "In2.Cu" "In4.Cu" "In6.Cu")
		(hatch none 0.5)
		(connect_pads
			(clearance 0)
		)
		(min_thickness 0.25)
		(keepout
			(tracks not_allowed)
			(vias allowed)
			(pads allowed)
			(copperpour not_allowed)
			(footprints allowed)
		)
		(placement
			(enabled no)
			(sheetname "")
		)
		(fill yes
			(thermal_gap 0.5)
			(thermal_bridge_width 0.5)
			(island_removal_mode 0)
		)
		(polygon
			(pts
				(arc
					(start 370.054886 -244.179344)
					(mid 369.750086 -244.484144)
					(end 370.054886 -244.788944)
				)
				(arc
					(start 370.99494 -244.788944)
					(mid 371.29974 -244.484144)
					(end 370.99494 -244.179344)
				)
			)
		)
	)
	(zone
		(layers "In1.Cu" "In2.Cu" "In4.Cu" "In6.Cu")
		(hatch none 0.5)
		(connect_pads
			(clearance 0)
		)
		(min_thickness 0.25)
		(keepout
			(tracks not_allowed)
			(vias allowed)
			(pads allowed)
			(copperpour not_allowed)
			(footprints allowed)
		)
		(placement
			(enabled no)
			(sheetname "")
		)
		(fill yes
			(thermal_gap 0.5)
			(thermal_bridge_width 0.5)
			(island_removal_mode 0)
		)
		(polygon
			(pts
				(arc
					(start 356.731062 -281.881326)
					(mid 356.426262 -282.186126)
					(end 356.731062 -282.490926)
				)
				(arc
					(start 357.671116 -282.490926)
					(mid 357.975916 -282.186126)
					(end 357.671116 -281.881326)
				)
			)
		)
	)
	(zone
		(layers "In1.Cu" "In2.Cu" "In4.Cu" "In6.Cu")
		(hatch none 0.5)
		(connect_pads
			(clearance 0)
		)
		(min_thickness 0.25)
		(keepout
			(tracks not_allowed)
			(vias allowed)
			(pads allowed)
			(copperpour not_allowed)
			(footprints allowed)
		)
		(placement
			(enabled no)
			(sheetname "")
		)
		(fill yes
			(thermal_gap 0.5)
			(thermal_bridge_width 0.5)
			(island_removal_mode 0)
		)
		(polygon
			(pts
				(arc
					(start 97.681034 -245.79961)
					(mid 97.376234 -246.10441)
					(end 97.681034 -246.40921)
				)
				(arc
					(start 98.621088 -246.40921)
					(mid 98.925888 -246.10441)
					(end 98.621088 -245.79961)
				)
			)
		)
	)
	(zone
		(layers "In1.Cu" "In2.Cu" "In4.Cu" "In6.Cu")
		(hatch none 0.5)
		(connect_pads
			(clearance 0)
		)
		(min_thickness 0.25)
		(keepout
			(tracks not_allowed)
			(vias allowed)
			(pads allowed)
			(copperpour not_allowed)
			(footprints allowed)
		)
		(placement
			(enabled no)
			(sheetname "")
		)
		(fill yes
			(thermal_gap 0.5)
			(thermal_bridge_width 0.5)
			(island_removal_mode 0)
		)
		(polygon
			(pts
				(arc
					(start 345.921076 -284.311344)
					(mid 345.616276 -284.616144)
					(end 345.921076 -284.920944)
				)
				(arc
					(start 346.86113 -284.920944)
					(mid 347.16593 -284.616144)
					(end 346.86113 -284.311344)
				)
			)
		)
	)
	(zone
		(layers "In1.Cu" "In2.Cu" "In4.Cu" "In6.Cu")
		(hatch none 0.5)
		(connect_pads
			(clearance 0)
		)
		(min_thickness 0.25)
		(keepout
			(tracks not_allowed)
			(vias allowed)
			(pads allowed)
			(copperpour not_allowed)
			(footprints allowed)
		)
		(placement
			(enabled no)
			(sheetname "")
		)
		(fill yes
			(thermal_gap 0.5)
			(thermal_bridge_width 0.5)
			(island_removal_mode 0)
		)
		(polygon
			(pts
				(arc
					(start 348.741238 -284.311344)
					(mid 348.436438 -284.616144)
					(end 348.741238 -284.920944)
				)
				(arc
					(start 349.681292 -284.920944)
					(mid 349.986092 -284.616144)
					(end 349.681292 -284.311344)
				)
			)
		)
	)
	(zone
		(layers "In1.Cu" "In2.Cu" "In4.Cu" "In6.Cu")
		(hatch none 0.5)
		(connect_pads
			(clearance 0)
		)
		(min_thickness 0.25)
		(keepout
			(tracks not_allowed)
			(vias allowed)
			(pads allowed)
			(copperpour not_allowed)
			(footprints allowed)
		)
		(placement
			(enabled no)
			(sheetname "")
		)
		(fill yes
			(thermal_gap 0.5)
			(thermal_bridge_width 0.5)
			(island_removal_mode 0)
		)
		(polygon
			(pts
				(arc
					(start 367.234724 -245.799356)
					(mid 366.929924 -246.104156)
					(end 367.234724 -246.408956)
				)
				(arc
					(start 368.174778 -246.408956)
					(mid 368.479578 -246.104156)
					(end 368.174778 -245.799356)
				)
			)
		)
	)
	(zone
		(layers "In1.Cu" "In2.Cu" "In4.Cu" "In6.Cu")
		(hatch none 0.5)
		(connect_pads
			(clearance 0)
		)
		(min_thickness 0.25)
		(keepout
			(tracks not_allowed)
			(vias allowed)
			(pads allowed)
			(copperpour not_allowed)
			(footprints allowed)
		)
		(placement
			(enabled no)
			(sheetname "")
		)
		(fill yes
			(thermal_gap 0.5)
			(thermal_bridge_width 0.5)
			(island_removal_mode 0)
		)
		(polygon
			(pts
				(arc
					(start 372.874794 -244.179344)
					(mid 372.569994 -244.484144)
					(end 372.874794 -244.788944)
				)
				(arc
					(start 373.814848 -244.788944)
					(mid 374.119648 -244.484144)
					(end 373.814848 -244.179344)
				)
			)
		)
	)
	(zone
		(layers "In1.Cu" "In2.Cu" "In4.Cu" "In6.Cu")
		(hatch none 0.5)
		(connect_pads
			(clearance 0)
		)
		(min_thickness 0.25)
		(keepout
			(tracks not_allowed)
			(vias allowed)
			(pads allowed)
			(copperpour not_allowed)
			(footprints allowed)
		)
		(placement
			(enabled no)
			(sheetname "")
		)
		(fill yes
			(thermal_gap 0.5)
			(thermal_bridge_width 0.5)
			(island_removal_mode 0)
		)
		(polygon
			(pts
				(arc
					(start 356.731062 -283.501338)
					(mid 356.426262 -283.806138)
					(end 356.731062 -284.110938)
				)
				(arc
					(start 357.671116 -284.110938)
					(mid 357.975916 -283.806138)
					(end 357.671116 -283.501338)
				)
			)
		)
	)
	(zone
		(layers "In1.Cu" "In2.Cu" "In4.Cu" "In6.Cu")
		(hatch none 0.5)
		(connect_pads
			(clearance 0)
		)
		(min_thickness 0.25)
		(keepout
			(tracks not_allowed)
			(vias allowed)
			(pads allowed)
			(copperpour not_allowed)
			(footprints allowed)
		)
		(placement
			(enabled no)
			(sheetname "")
		)
		(fill yes
			(thermal_gap 0.5)
			(thermal_bridge_width 0.5)
			(island_removal_mode 0)
		)
		(polygon
			(pts
				(arc
					(start 103.321104 -245.79961)
					(mid 103.016304 -246.10441)
					(end 103.321104 -246.40921)
				)
				(arc
					(start 104.261158 -246.40921)
					(mid 104.565958 -246.10441)
					(end 104.261158 -245.79961)
				)
			)
		)
	)
	(zone
		(layers "In1.Cu" "In2.Cu" "In4.Cu" "In6.Cu")
		(hatch none 0.5)
		(connect_pads
			(clearance 0)
		)
		(min_thickness 0.25)
		(keepout
			(tracks not_allowed)
			(vias allowed)
			(pads allowed)
			(copperpour not_allowed)
			(footprints allowed)
		)
		(placement
			(enabled no)
			(sheetname "")
		)
		(fill yes
			(thermal_gap 0.5)
			(thermal_bridge_width 0.5)
			(island_removal_mode 0)
		)
		(polygon
			(pts
				(arc
					(start 367.234724 -244.179344)
					(mid 366.929924 -244.484144)
					(end 367.234724 -244.788944)
				)
				(arc
					(start 368.174778 -244.788944)
					(mid 368.479578 -244.484144)
					(end 368.174778 -244.179344)
				)
			)
		)
	)
	(zone
		(layers "In1.Cu" "In2.Cu" "In4.Cu" "In6.Cu")
		(hatch none 0.5)
		(connect_pads
			(clearance 0)
		)
		(min_thickness 0.25)
		(keepout
			(tracks not_allowed)
			(vias allowed)
			(pads allowed)
			(copperpour not_allowed)
			(footprints allowed)
		)
		(placement
			(enabled no)
			(sheetname "")
		)
		(fill yes
			(thermal_gap 0.5)
			(thermal_bridge_width 0.5)
			(island_removal_mode 0)
		)
		(polygon
			(pts
				(arc
					(start 351.561146 -284.311344)
					(mid 351.256346 -284.616144)
					(end 351.561146 -284.920944)
				)
				(arc
					(start 352.5012 -284.920944)
					(mid 352.806 -284.616144)
					(end 352.5012 -284.311344)
				)
			)
		)
	)
	(zone
		(layers "In1.Cu" "In2.Cu" "In4.Cu" "In6.Cu")
		(hatch none 0.5)
		(connect_pads
			(clearance 0)
		)
		(min_thickness 0.25)
		(keepout
			(tracks not_allowed)
			(vias allowed)
			(pads allowed)
			(copperpour not_allowed)
			(footprints allowed)
		)
		(placement
			(enabled no)
			(sheetname "")
		)
		(fill yes
			(thermal_gap 0.5)
			(thermal_bridge_width 0.5)
			(island_removal_mode 0)
		)
		(polygon
			(pts
				(arc
					(start 97.981008 -282.691586)
					(mid 97.676208 -282.996386)
					(end 97.981008 -283.301186)
				)
				(arc
					(start 98.921062 -283.301186)
					(mid 99.225862 -282.996386)
					(end 98.921062 -282.691586)
				)
			)
		)
	)
	(zone
		(layers "In1.Cu" "In2.Cu" "In4.Cu" "In6.Cu")
		(hatch none 0.5)
		(connect_pads
			(clearance 0)
		)
		(min_thickness 0.25)
		(keepout
			(tracks not_allowed)
			(vias allowed)
			(pads allowed)
			(copperpour not_allowed)
			(footprints allowed)
		)
		(placement
			(enabled no)
			(sheetname "")
		)
		(fill yes
			(thermal_gap 0.5)
			(thermal_bridge_width 0.5)
			(island_removal_mode 0)
		)
		(polygon
			(pts
				(arc
					(start 100.80117 -284.311598)
					(mid 100.49637 -284.616398)
					(end 100.80117 -284.921198)
				)
				(arc
					(start 101.741224 -284.921198)
					(mid 102.046024 -284.616398)
					(end 101.741224 -284.311598)
				)
			)
		)
	)
	(zone
		(layers "In1.Cu" "In2.Cu" "In4.Cu" "In6.Cu")
		(hatch none 0.5)
		(connect_pads
			(clearance 0)
		)
		(min_thickness 0.25)
		(keepout
			(tracks not_allowed)
			(vias allowed)
			(pads allowed)
			(copperpour not_allowed)
			(footprints allowed)
		)
		(placement
			(enabled no)
			(sheetname "")
		)
		(fill yes
			(thermal_gap 0.5)
			(thermal_bridge_width 0.5)
			(island_removal_mode 0)
		)
		(polygon
			(pts
				(arc
					(start 100.80117 -281.071574)
					(mid 100.49637 -281.376374)
					(end 100.80117 -281.681174)
				)
				(arc
					(start 101.741224 -281.681174)
					(mid 102.046024 -281.376374)
					(end 101.741224 -281.071574)
				)
			)
		)
	)
	(zone
		(layers "In1.Cu" "In2.Cu" "In4.Cu" "In6.Cu")
		(hatch none 0.5)
		(connect_pads
			(clearance 0)
		)
		(min_thickness 0.25)
		(keepout
			(tracks not_allowed)
			(vias allowed)
			(pads allowed)
			(copperpour not_allowed)
			(footprints allowed)
		)
		(placement
			(enabled no)
			(sheetname "")
		)
		(fill yes
			(thermal_gap 0.5)
			(thermal_bridge_width 0.5)
			(island_removal_mode 0)
		)
		(polygon
			(pts
				(arc
					(start 372.874794 -247.419368)
					(mid 372.569994 -247.724168)
					(end 372.874794 -248.028968)
				)
				(arc
					(start 373.814848 -248.028968)
					(mid 374.119648 -247.724168)
					(end 373.814848 -247.419368)
				)
			)
		)
	)
	(zone
		(layers "In1.Cu" "In2.Cu" "In4.Cu" "In6.Cu")
		(hatch none 0.5)
		(connect_pads
			(clearance 0)
		)
		(min_thickness 0.25)
		(keepout
			(tracks not_allowed)
			(vias allowed)
			(pads allowed)
			(copperpour not_allowed)
			(footprints allowed)
		)
		(placement
			(enabled no)
			(sheetname "")
		)
		(fill yes
			(thermal_gap 0.5)
			(thermal_bridge_width 0.5)
			(island_removal_mode 0)
		)
		(polygon
			(pts
				(arc
					(start 106.440986 -282.691586)
					(mid 106.136186 -282.996386)
					(end 106.440986 -283.301186)
				)
				(arc
					(start 107.38104 -283.301186)
					(mid 107.68584 -282.996386)
					(end 107.38104 -282.691586)
				)
			)
		)
	)
	(zone
		(layers "In1.Cu" "In2.Cu" "In4.Cu" "In6.Cu")
		(hatch none 0.5)
		(connect_pads
			(clearance 0)
		)
		(min_thickness 0.25)
		(keepout
			(tracks not_allowed)
			(vias allowed)
			(pads allowed)
			(copperpour not_allowed)
			(footprints allowed)
		)
		(placement
			(enabled no)
			(sheetname "")
		)
		(fill yes
			(thermal_gap 0.5)
			(thermal_bridge_width 0.5)
			(island_removal_mode 0)
		)
		(polygon
			(pts
				(arc
					(start 370.054886 -247.419368)
					(mid 369.750086 -247.724168)
					(end 370.054886 -248.028968)
				)
				(arc
					(start 370.99494 -248.028968)
					(mid 371.29974 -247.724168)
					(end 370.99494 -247.419368)
				)
			)
		)
	)
	(zone
		(layers "In1.Cu" "In2.Cu" "In4.Cu" "In6.Cu")
		(hatch none 0.5)
		(connect_pads
			(clearance 0)
		)
		(min_thickness 0.25)
		(keepout
			(tracks not_allowed)
			(vias allowed)
			(pads allowed)
			(copperpour not_allowed)
			(footprints allowed)
		)
		(placement
			(enabled no)
			(sheetname "")
		)
		(fill yes
			(thermal_gap 0.5)
			(thermal_bridge_width 0.5)
			(island_removal_mode 0)
		)
		(polygon
			(pts
				(arc
					(start 348.741238 -282.691332)
					(mid 348.436438 -282.996132)
					(end 348.741238 -283.300932)
				)
				(arc
					(start 349.681292 -283.300932)
					(mid 349.986092 -282.996132)
					(end 349.681292 -282.691332)
				)
			)
		)
	)
	(zone
		(layers "In1.Cu" "In2.Cu" "In4.Cu" "In6.Cu")
		(hatch none 0.5)
		(connect_pads
			(clearance 0)
		)
		(min_thickness 0.25)
		(keepout
			(tracks not_allowed)
			(vias allowed)
			(pads allowed)
			(copperpour not_allowed)
			(footprints allowed)
		)
		(placement
			(enabled no)
			(sheetname "")
		)
		(fill yes
			(thermal_gap 0.5)
			(thermal_bridge_width 0.5)
			(island_removal_mode 0)
		)
		(polygon
			(pts
				(arc
					(start 103.621078 -284.311598)
					(mid 103.316278 -284.616398)
					(end 103.621078 -284.921198)
				)
				(arc
					(start 104.561132 -284.921198)
					(mid 104.865932 -284.616398)
					(end 104.561132 -284.311598)
				)
			)
		)
	)
	(zone
		(layers "In1.Cu" "In2.Cu" "In4.Cu" "In6.Cu")
		(hatch none 0.5)
		(connect_pads
			(clearance 0)
		)
		(min_thickness 0.25)
		(keepout
			(tracks not_allowed)
			(vias allowed)
			(pads allowed)
			(copperpour not_allowed)
			(footprints allowed)
		)
		(placement
			(enabled no)
			(sheetname "")
		)
		(fill yes
			(thermal_gap 0.5)
			(thermal_bridge_width 0.5)
			(island_removal_mode 0)
		)
		(polygon
			(pts
				(arc
					(start 370.054886 -245.799356)
					(mid 369.750086 -246.104156)
					(end 370.054886 -246.408956)
				)
				(arc
					(start 370.99494 -246.408956)
					(mid 371.29974 -246.104156)
					(end 370.99494 -245.799356)
				)
			)
		)
	)
	(zone
		(layers "In1.Cu" "In2.Cu" "In4.Cu" "In6.Cu")
		(hatch none 0.5)
		(connect_pads
			(clearance 0)
		)
		(min_thickness 0.25)
		(keepout
			(tracks not_allowed)
			(vias allowed)
			(pads allowed)
			(copperpour not_allowed)
			(footprints allowed)
		)
		(placement
			(enabled no)
			(sheetname "")
		)
		(fill yes
			(thermal_gap 0.5)
			(thermal_bridge_width 0.5)
			(island_removal_mode 0)
		)
		(polygon
			(pts
				(arc
					(start 372.874794 -245.799356)
					(mid 372.569994 -246.104156)
					(end 372.874794 -246.408956)
				)
				(arc
					(start 373.814848 -246.408956)
					(mid 374.119648 -246.104156)
					(end 373.814848 -245.799356)
				)
			)
		)
	)
	(zone
		(layers "In1.Cu" "In2.Cu" "In4.Cu" "In6.Cu")
		(hatch none 0.5)
		(connect_pads
			(clearance 0)
		)
		(min_thickness 0.25)
		(keepout
			(tracks not_allowed)
			(vias allowed)
			(pads allowed)
			(copperpour not_allowed)
			(footprints allowed)
		)
		(placement
			(enabled no)
			(sheetname "")
		)
		(fill yes
			(thermal_gap 0.5)
			(thermal_bridge_width 0.5)
			(island_removal_mode 0)
		)
		(polygon
			(pts
				(arc
					(start 108.790994 -281.88158)
					(mid 108.486194 -282.18638)
					(end 108.790994 -282.49118)
				)
				(arc
					(start 109.731048 -282.49118)
					(mid 110.035848 -282.18638)
					(end 109.731048 -281.88158)
				)
			)
		)
	)
	(zone
		(layers "In1.Cu" "In2.Cu" "In4.Cu" "In6.Cu")
		(hatch none 0.5)
		(connect_pads
			(clearance 0)
		)
		(min_thickness 0.25)
		(keepout
			(tracks not_allowed)
			(vias allowed)
			(pads allowed)
			(copperpour not_allowed)
			(footprints allowed)
		)
		(placement
			(enabled no)
			(sheetname "")
		)
		(fill yes
			(thermal_gap 0.5)
			(thermal_bridge_width 0.5)
			(island_removal_mode 0)
		)
		(polygon
			(pts
				(arc
					(start 100.500942 -245.79961)
					(mid 100.196142 -246.10441)
					(end 100.500942 -246.40921)
				)
				(arc
					(start 101.440996 -246.40921)
					(mid 101.745796 -246.10441)
					(end 101.440996 -245.79961)
				)
			)
		)
	)
	(zone
		(layers "In1.Cu" "In2.Cu" "In4.Cu" "In6.Cu")
		(hatch none 0.5)
		(connect_pads
			(clearance 0)
		)
		(min_thickness 0.25)
		(keepout
			(tracks not_allowed)
			(vias allowed)
			(pads allowed)
			(copperpour not_allowed)
			(footprints allowed)
		)
		(placement
			(enabled no)
			(sheetname "")
		)
		(fill yes
			(thermal_gap 0.5)
			(thermal_bridge_width 0.5)
			(island_removal_mode 0)
		)
		(polygon
			(pts
				(arc
					(start 364.414816 -247.419368)
					(mid 364.110016 -247.724168)
					(end 364.414816 -248.028968)
				)
				(arc
					(start 365.35487 -248.028968)
					(mid 365.65967 -247.724168)
					(end 365.35487 -247.419368)
				)
			)
		)
	)
	(zone
		(layers "In1.Cu" "In2.Cu" "In4.Cu" "In6.Cu")
		(hatch none 0.5)
		(connect_pads
			(clearance 0)
		)
		(min_thickness 0.25)
		(keepout
			(tracks not_allowed)
			(vias allowed)
			(pads allowed)
			(copperpour not_allowed)
			(footprints allowed)
		)
		(placement
			(enabled no)
			(sheetname "")
		)
		(fill yes
			(thermal_gap 0.5)
			(thermal_bridge_width 0.5)
			(island_removal_mode 0)
		)
		(polygon
			(pts
				(arc
					(start 356.731062 -285.12135)
					(mid 356.426262 -285.42615)
					(end 356.731062 -285.73095)
				)
				(arc
					(start 357.671116 -285.73095)
					(mid 357.975916 -285.42615)
					(end 357.671116 -285.12135)
				)
			)
		)
	)
	(zone
		(layers "In1.Cu" "In2.Cu" "In4.Cu" "In6.Cu")
		(hatch none 0.5)
		(connect_pads
			(clearance 0)
		)
		(min_thickness 0.25)
		(keepout
			(tracks not_allowed)
			(vias allowed)
			(pads allowed)
			(copperpour not_allowed)
			(footprints allowed)
		)
		(placement
			(enabled no)
			(sheetname "")
		)
		(fill yes
			(thermal_gap 0.5)
			(thermal_bridge_width 0.5)
			(island_removal_mode 0)
		)
		(polygon
			(pts
				(arc
					(start 103.321104 -247.419622)
					(mid 103.016304 -247.724422)
					(end 103.321104 -248.029222)
				)
				(arc
					(start 104.261158 -248.029222)
					(mid 104.565958 -247.724422)
					(end 104.261158 -247.419622)
				)
			)
		)
	)
	(zone
		(layers "In1.Cu" "In2.Cu" "In4.Cu" "In6.Cu")
		(hatch none 0.5)
		(connect_pads
			(clearance 0)
		)
		(min_thickness 0.25)
		(keepout
			(tracks not_allowed)
			(vias allowed)
			(pads allowed)
			(copperpour not_allowed)
			(footprints allowed)
		)
		(placement
			(enabled no)
			(sheetname "")
		)
		(fill yes
			(thermal_gap 0.5)
			(thermal_bridge_width 0.5)
			(island_removal_mode 0)
		)
		(polygon
			(pts
				(arc
					(start 351.561146 -282.691332)
					(mid 351.256346 -282.996132)
					(end 351.561146 -283.300932)
				)
				(arc
					(start 352.5012 -283.300932)
					(mid 352.806 -282.996132)
					(end 352.5012 -282.691332)
				)
			)
		)
	)
	(zone
		(layers "In1.Cu" "In2.Cu" "In4.Cu" "In6.Cu")
		(hatch none 0.5)
		(connect_pads
			(clearance 0)
		)
		(min_thickness 0.25)
		(keepout
			(tracks not_allowed)
			(vias allowed)
			(pads allowed)
			(copperpour not_allowed)
			(footprints allowed)
		)
		(placement
			(enabled no)
			(sheetname "")
		)
		(fill yes
			(thermal_gap 0.5)
			(thermal_bridge_width 0.5)
			(island_removal_mode 0)
		)
		(polygon
			(pts
				(arc
					(start 97.681034 -247.419622)
					(mid 97.376234 -247.724422)
					(end 97.681034 -248.029222)
				)
				(arc
					(start 98.621088 -248.029222)
					(mid 98.925888 -247.724422)
					(end 98.621088 -247.419622)
				)
			)
		)
	)
	(zone
		(layers "In1.Cu" "In2.Cu" "In4.Cu" "In6.Cu")
		(hatch none 0.5)
		(connect_pads
			(clearance 0)
		)
		(min_thickness 0.25)
		(keepout
			(tracks not_allowed)
			(vias allowed)
			(pads allowed)
			(copperpour not_allowed)
			(footprints allowed)
		)
		(placement
			(enabled no)
			(sheetname "")
		)
		(fill yes
			(thermal_gap 0.5)
			(thermal_bridge_width 0.5)
			(island_removal_mode 0)
		)
		(polygon
			(pts
				(arc
					(start 348.741238 -281.07132)
					(mid 348.436438 -281.37612)
					(end 348.741238 -281.68092)
				)
				(arc
					(start 349.681292 -281.68092)
					(mid 349.986092 -281.37612)
					(end 349.681292 -281.07132)
				)
			)
		)
	)
	(zone
		(layers "In1.Cu" "In2.Cu" "In4.Cu" "In6.Cu")
		(hatch none 0.5)
		(connect_pads
			(clearance 0)
		)
		(min_thickness 0.25)
		(keepout
			(tracks not_allowed)
			(vias allowed)
			(pads allowed)
			(copperpour not_allowed)
			(footprints allowed)
		)
		(placement
			(enabled no)
			(sheetname "")
		)
		(fill yes
			(thermal_gap 0.5)
			(thermal_bridge_width 0.5)
			(island_removal_mode 0)
		)
		(polygon
			(pts
				(arc
					(start 100.500942 -244.179598)
					(mid 100.196142 -244.484398)
					(end 100.500942 -244.789198)
				)
				(arc
					(start 101.440996 -244.789198)
					(mid 101.745796 -244.484398)
					(end 101.440996 -244.179598)
				)
			)
		)
	)
	(zone
		(layers "In1.Cu" "In2.Cu" "In4.Cu" "In6.Cu")
		(hatch none 0.5)
		(connect_pads
			(clearance 0)
		)
		(min_thickness 0.25)
		(keepout
			(tracks not_allowed)
			(vias allowed)
			(pads allowed)
			(copperpour not_allowed)
			(footprints allowed)
		)
		(placement
			(enabled no)
			(sheetname "")
		)
		(fill yes
			(thermal_gap 0.5)
			(thermal_bridge_width 0.5)
			(island_removal_mode 0)
		)
		(polygon
			(pts
				(arc
					(start 108.790994 -285.121604)
					(mid 108.486194 -285.426404)
					(end 108.790994 -285.731204)
				)
				(arc
					(start 109.731048 -285.731204)
					(mid 110.035848 -285.426404)
					(end 109.731048 -285.121604)
				)
			)
		)
	)
	(zone
		(layers "In1.Cu" "In2.Cu" "In4.Cu" "In6.Cu")
		(hatch none 0.5)
		(connect_pads
			(clearance 0)
		)
		(min_thickness 0.25)
		(keepout
			(tracks not_allowed)
			(vias allowed)
			(pads allowed)
			(copperpour not_allowed)
			(footprints allowed)
		)
		(placement
			(enabled no)
			(sheetname "")
		)
		(fill yes
			(thermal_gap 0.5)
			(thermal_bridge_width 0.5)
			(island_removal_mode 0)
		)
		(polygon
			(pts
				(arc
					(start 97.981008 -284.311598)
					(mid 97.676208 -284.616398)
					(end 97.981008 -284.921198)
				)
				(arc
					(start 98.921062 -284.921198)
					(mid 99.225862 -284.616398)
					(end 98.921062 -284.311598)
				)
			)
		)
	)
	(zone
		(layers "In1.Cu" "In2.Cu" "In4.Cu" "In6.Cu")
		(hatch none 0.5)
		(connect_pads
			(clearance 0)
		)
		(min_thickness 0.25)
		(keepout
			(tracks not_allowed)
			(vias allowed)
			(pads allowed)
			(copperpour not_allowed)
			(footprints allowed)
		)
		(placement
			(enabled no)
			(sheetname "")
		)
		(fill yes
			(thermal_gap 0.5)
			(thermal_bridge_width 0.5)
			(island_removal_mode 0)
		)
		(polygon
			(pts
				(arc
					(start 108.790994 -283.501592)
					(mid 108.486194 -283.806392)
					(end 108.790994 -284.111192)
				)
				(arc
					(start 109.731048 -284.111192)
					(mid 110.035848 -283.806392)
					(end 109.731048 -283.501592)
				)
			)
		)
	)
	(zone
		(layers "In1.Cu" "In2.Cu" "In4.Cu" "In6.Cu")
		(hatch none 0.5)
		(connect_pads
			(clearance 0)
		)
		(min_thickness 0.25)
		(keepout
			(tracks not_allowed)
			(vias allowed)
			(pads allowed)
			(copperpour not_allowed)
			(footprints allowed)
		)
		(placement
			(enabled no)
			(sheetname "")
		)
		(fill yes
			(thermal_gap 0.5)
			(thermal_bridge_width 0.5)
			(island_removal_mode 0)
		)
		(polygon
			(pts
				(arc
					(start 354.381054 -285.931356)
					(mid 354.076254 -286.236156)
					(end 354.381054 -286.540956)
				)
				(arc
					(start 355.321108 -286.540956)
					(mid 355.625908 -286.236156)
					(end 355.321108 -285.931356)
				)
			)
		)
	)
	(zone
		(layers "In1.Cu" "In2.Cu" "In4.Cu" "In6.Cu")
		(hatch none 0.5)
		(connect_pads
			(clearance 0)
		)
		(min_thickness 0.25)
		(keepout
			(tracks not_allowed)
			(vias allowed)
			(pads allowed)
			(copperpour not_allowed)
			(footprints allowed)
		)
		(placement
			(enabled no)
			(sheetname "")
		)
		(fill yes
			(thermal_gap 0.5)
			(thermal_bridge_width 0.5)
			(island_removal_mode 0)
		)
		(polygon
			(pts
				(arc
					(start 108.49102 -246.609616)
					(mid 108.18622 -246.914416)
					(end 108.49102 -247.219216)
				)
				(arc
					(start 109.431074 -247.219216)
					(mid 109.735874 -246.914416)
					(end 109.431074 -246.609616)
				)
			)
		)
	)
	(zone
		(layers "In1.Cu" "In2.Cu" "In4.Cu" "In6.Cu")
		(hatch none 0.5)
		(connect_pads
			(clearance 0)
		)
		(min_thickness 0.25)
		(keepout
			(tracks not_allowed)
			(vias allowed)
			(pads allowed)
			(copperpour not_allowed)
			(footprints allowed)
		)
		(placement
			(enabled no)
			(sheetname "")
		)
		(fill yes
			(thermal_gap 0.5)
			(thermal_bridge_width 0.5)
			(island_removal_mode 0)
		)
		(polygon
			(pts
				(arc
					(start 345.921076 -282.691332)
					(mid 345.616276 -282.996132)
					(end 345.921076 -283.300932)
				)
				(arc
					(start 346.86113 -283.300932)
					(mid 347.16593 -282.996132)
					(end 346.86113 -282.691332)
				)
			)
		)
	)
	(zone
		(layers "In1.Cu" "In2.Cu" "In4.Cu" "In6.Cu")
		(hatch none 0.5)
		(connect_pads
			(clearance 0)
		)
		(min_thickness 0.25)
		(keepout
			(tracks not_allowed)
			(vias allowed)
			(pads allowed)
			(copperpour not_allowed)
			(footprints allowed)
		)
		(placement
			(enabled no)
			(sheetname "")
		)
		(fill yes
			(thermal_gap 0.5)
			(thermal_bridge_width 0.5)
			(island_removal_mode 0)
		)
		(polygon
			(pts
				(arc
					(start 103.321104 -244.179598)
					(mid 103.016304 -244.484398)
					(end 103.321104 -244.789198)
				)
				(arc
					(start 104.261158 -244.789198)
					(mid 104.565958 -244.484398)
					(end 104.261158 -244.179598)
				)
			)
		)
	)
	(zone
		(layers "In1.Cu" "In2.Cu" "In4.Cu" "In6.Cu")
		(hatch none 0.5)
		(connect_pads
			(clearance 0)
		)
		(min_thickness 0.25)
		(keepout
			(tracks not_allowed)
			(vias allowed)
			(pads allowed)
			(copperpour not_allowed)
			(footprints allowed)
		)
		(placement
			(enabled no)
			(sheetname "")
		)
		(fill yes
			(thermal_gap 0.5)
			(thermal_bridge_width 0.5)
			(island_removal_mode 0)
		)
		(polygon
			(pts
				(arc
					(start 97.981008 -281.071574)
					(mid 97.676208 -281.376374)
					(end 97.981008 -281.681174)
				)
				(arc
					(start 98.921062 -281.681174)
					(mid 99.225862 -281.376374)
					(end 98.921062 -281.071574)
				)
			)
		)
	)
	(zone
		(layers "In1.Cu" "In2.Cu" "In4.Cu" "In6.Cu")
		(hatch none 0.5)
		(connect_pads
			(clearance 0)
		)
		(min_thickness 0.25)
		(keepout
			(tracks not_allowed)
			(vias allowed)
			(pads allowed)
			(copperpour not_allowed)
			(footprints allowed)
		)
		(placement
			(enabled no)
			(sheetname "")
		)
		(fill yes
			(thermal_gap 0.5)
			(thermal_bridge_width 0.5)
			(island_removal_mode 0)
		)
		(polygon
			(pts
				(arc
					(start 364.414816 -244.179344)
					(mid 364.110016 -244.484144)
					(end 364.414816 -244.788944)
				)
				(arc
					(start 365.35487 -244.788944)
					(mid 365.65967 -244.484144)
					(end 365.35487 -244.179344)
				)
			)
		)
	)
	(zone
		(layers "In1.Cu" "In2.Cu" "In4.Cu" "In6.Cu")
		(hatch none 0.5)
		(connect_pads
			(clearance 0)
		)
		(min_thickness 0.25)
		(keepout
			(tracks not_allowed)
			(vias allowed)
			(pads allowed)
			(copperpour not_allowed)
			(footprints allowed)
		)
		(placement
			(enabled no)
			(sheetname "")
		)
		(fill yes
			(thermal_gap 0.5)
			(thermal_bridge_width 0.5)
			(island_removal_mode 0)
		)
		(polygon
			(pts
				(arc
					(start 364.414816 -245.799356)
					(mid 364.110016 -246.104156)
					(end 364.414816 -246.408956)
				)
				(arc
					(start 365.35487 -246.408956)
					(mid 365.65967 -246.104156)
					(end 365.35487 -245.799356)
				)
			)
		)
	)
	(zone
		(layers "In1.Cu" "In2.Cu" "In4.Cu" "In6.Cu")
		(hatch none 0.5)
		(connect_pads
			(clearance 0)
		)
		(min_thickness 0.25)
		(keepout
			(tracks not_allowed)
			(vias allowed)
			(pads allowed)
			(copperpour not_allowed)
			(footprints allowed)
		)
		(placement
			(enabled no)
			(sheetname "")
		)
		(fill yes
			(thermal_gap 0.5)
			(thermal_bridge_width 0.5)
			(island_removal_mode 0)
		)
		(polygon
			(pts
				(arc
					(start 103.621078 -285.93161)
					(mid 103.316278 -286.23641)
					(end 103.621078 -286.54121)
				)
				(arc
					(start 104.561132 -286.54121)
					(mid 104.865932 -286.23641)
					(end 104.561132 -285.93161)
				)
			)
		)
	)
	(zone
		(layers "In1.Cu" "In2.Cu" "In4.Cu" "In6.Cu")
		(hatch none 0.5)
		(connect_pads
			(clearance 0)
		)
		(min_thickness 0.25)
		(keepout
			(tracks not_allowed)
			(vias allowed)
			(pads allowed)
			(copperpour not_allowed)
			(footprints allowed)
		)
		(placement
			(enabled no)
			(sheetname "")
		)
		(fill yes
			(thermal_gap 0.5)
			(thermal_bridge_width 0.5)
			(island_removal_mode 0)
		)
		(polygon
			(pts
				(arc
					(start 362.064808 -243.369338)
					(mid 361.760008 -243.674138)
					(end 362.064808 -243.978938)
				)
				(arc
					(start 363.004862 -243.978938)
					(mid 363.309662 -243.674138)
					(end 363.004862 -243.369338)
				)
			)
		)
	)
	(zone
		(layers "In1.Cu" "In2.Cu" "In4.Cu" "In6.Cu")
		(hatch none 0.5)
		(connect_pads
			(clearance 0)
		)
		(min_thickness 0.25)
		(keepout
			(tracks not_allowed)
			(vias allowed)
			(pads allowed)
			(copperpour not_allowed)
			(footprints allowed)
		)
		(placement
			(enabled no)
			(sheetname "")
		)
		(fill yes
			(thermal_gap 0.5)
			(thermal_bridge_width 0.5)
			(island_removal_mode 0)
		)
		(polygon
			(pts
				(arc
					(start 351.561146 -285.931356)
					(mid 351.256346 -286.236156)
					(end 351.561146 -286.540956)
				)
				(arc
					(start 352.5012 -286.540956)
					(mid 352.806 -286.236156)
					(end 352.5012 -285.931356)
				)
			)
		)
	)
	(zone
		(layers "In1.Cu" "In2.Cu" "In4.Cu" "In6.Cu")
		(hatch none 0.5)
		(connect_pads
			(clearance 0)
		)
		(min_thickness 0.25)
		(keepout
			(tracks not_allowed)
			(vias allowed)
			(pads allowed)
			(copperpour not_allowed)
			(footprints allowed)
		)
		(placement
			(enabled no)
			(sheetname "")
		)
		(fill yes
			(thermal_gap 0.5)
			(thermal_bridge_width 0.5)
			(island_removal_mode 0)
		)
		(polygon
			(pts
				(arc
					(start 100.500942 -247.419622)
					(mid 100.196142 -247.724422)
					(end 100.500942 -248.029222)
				)
				(arc
					(start 101.440996 -248.029222)
					(mid 101.745796 -247.724422)
					(end 101.440996 -247.419622)
				)
			)
		)
	)
	(zone
		(layers "In1.Cu" "In2.Cu" "In4.Cu" "In6.Cu")
		(hatch none 0.5)
		(connect_pads
			(clearance 0)
		)
		(min_thickness 0.25)
		(keepout
			(tracks not_allowed)
			(vias allowed)
			(pads allowed)
			(copperpour not_allowed)
			(footprints allowed)
		)
		(placement
			(enabled no)
			(sheetname "")
		)
		(fill yes
			(thermal_gap 0.5)
			(thermal_bridge_width 0.5)
			(island_removal_mode 0)
		)
		(polygon
			(pts
				(arc
					(start 108.49102 -244.989604)
					(mid 108.18622 -245.294404)
					(end 108.49102 -245.599204)
				)
				(arc
					(start 109.431074 -245.599204)
					(mid 109.735874 -245.294404)
					(end 109.431074 -244.989604)
				)
			)
		)
	)
	(zone
		(layers "In1.Cu" "In2.Cu" "In4.Cu" "In6.Cu")
		(hatch none 0.5)
		(connect_pads
			(clearance 0)
		)
		(min_thickness 0.25)
		(keepout
			(tracks not_allowed)
			(vias allowed)
			(pads allowed)
			(copperpour not_allowed)
			(footprints allowed)
		)
		(placement
			(enabled no)
			(sheetname "")
		)
		(fill yes
			(thermal_gap 0.5)
			(thermal_bridge_width 0.5)
			(island_removal_mode 0)
		)
		(polygon
			(pts
				(arc
					(start 362.064808 -246.609362)
					(mid 361.760008 -246.914162)
					(end 362.064808 -247.218962)
				)
				(arc
					(start 363.004862 -247.218962)
					(mid 363.309662 -246.914162)
					(end 363.004862 -246.609362)
				)
			)
		)
	)
	(zone
		(layers "In1.Cu" "In2.Cu" "In4.Cu" "In6.Cu")
		(hatch none 0.5)
		(connect_pads
			(clearance 0)
		)
		(min_thickness 0.25)
		(keepout
			(tracks not_allowed)
			(vias allowed)
			(pads allowed)
			(copperpour not_allowed)
			(footprints allowed)
		)
		(placement
			(enabled no)
			(sheetname "")
		)
		(fill yes
			(thermal_gap 0.5)
			(thermal_bridge_width 0.5)
			(island_removal_mode 0)
		)
		(polygon
			(pts
				(arc
					(start 106.141012 -247.419622)
					(mid 105.836212 -247.724422)
					(end 106.141012 -248.029222)
				)
				(arc
					(start 107.081066 -248.029222)
					(mid 107.385866 -247.724422)
					(end 107.081066 -247.419622)
				)
			)
		)
	)
	(zone
		(layers "In1.Cu" "In2.Cu" "In4.Cu" "In6.Cu")
		(hatch none 0.5)
		(connect_pads
			(clearance 0)
		)
		(min_thickness 0.25)
		(keepout
			(tracks not_allowed)
			(vias allowed)
			(pads allowed)
			(copperpour not_allowed)
			(footprints allowed)
		)
		(placement
			(enabled no)
			(sheetname "")
		)
		(fill yes
			(thermal_gap 0.5)
			(thermal_bridge_width 0.5)
			(island_removal_mode 0)
		)
		(polygon
			(pts
				(arc
					(start 354.381054 -284.311344)
					(mid 354.076254 -284.616144)
					(end 354.381054 -284.920944)
				)
				(arc
					(start 355.321108 -284.920944)
					(mid 355.625908 -284.616144)
					(end 355.321108 -284.311344)
				)
			)
		)
	)
	(zone
		(layers "In1.Cu" "In2.Cu" "In4.Cu" "In6.Cu")
		(hatch none 0.5)
		(connect_pads
			(clearance 0)
		)
		(min_thickness 0.25)
		(keepout
			(tracks not_allowed)
			(vias allowed)
			(pads allowed)
			(copperpour not_allowed)
			(footprints allowed)
		)
		(placement
			(enabled no)
			(sheetname "")
		)
		(fill yes
			(thermal_gap 0.5)
			(thermal_bridge_width 0.5)
			(island_removal_mode 0)
		)
		(polygon
			(pts
				(arc
					(start 106.141012 -244.179598)
					(mid 105.836212 -244.484398)
					(end 106.141012 -244.789198)
				)
				(arc
					(start 107.081066 -244.789198)
					(mid 107.385866 -244.484398)
					(end 107.081066 -244.179598)
				)
			)
		)
	)
	(zone
		(layers "In1.Cu" "In2.Cu" "In4.Cu" "In6.Cu")
		(hatch none 0.5)
		(connect_pads
			(clearance 0)
		)
		(min_thickness 0.25)
		(keepout
			(tracks not_allowed)
			(vias allowed)
			(pads allowed)
			(copperpour not_allowed)
			(footprints allowed)
		)
		(placement
			(enabled no)
			(sheetname "")
		)
		(fill yes
			(thermal_gap 0.5)
			(thermal_bridge_width 0.5)
			(island_removal_mode 0)
		)
		(polygon
			(pts
				(arc
					(start 97.681034 -244.179598)
					(mid 97.376234 -244.484398)
					(end 97.681034 -244.789198)
				)
				(arc
					(start 98.621088 -244.789198)
					(mid 98.925888 -244.484398)
					(end 98.621088 -244.179598)
				)
			)
		)
	)
	(zone
		(layers "In1.Cu" "In2.Cu" "In4.Cu" "In6.Cu")
		(hatch none 0.5)
		(connect_pads
			(clearance 0)
		)
		(min_thickness 0.25)
		(keepout
			(tracks not_allowed)
			(vias allowed)
			(pads allowed)
			(copperpour not_allowed)
			(footprints allowed)
		)
		(placement
			(enabled no)
			(sheetname "")
		)
		(fill yes
			(thermal_gap 0.5)
			(thermal_bridge_width 0.5)
			(island_removal_mode 0)
		)
		(polygon
			(pts
				(arc
					(start 108.49102 -243.369592)
					(mid 108.18622 -243.674392)
					(end 108.49102 -243.979192)
				)
				(arc
					(start 109.431074 -243.979192)
					(mid 109.735874 -243.674392)
					(end 109.431074 -243.369592)
				)
			)
		)
	)
	(zone
		(layers "In1.Cu" "In2.Cu" "In4.Cu" "In6.Cu")
		(hatch none 0.5)
		(connect_pads
			(clearance 0)
		)
		(min_thickness 0.25)
		(keepout
			(tracks not_allowed)
			(vias allowed)
			(pads allowed)
			(copperpour not_allowed)
			(footprints allowed)
		)
		(placement
			(enabled no)
			(sheetname "")
		)
		(fill yes
			(thermal_gap 0.5)
			(thermal_bridge_width 0.5)
			(island_removal_mode 0)
		)
		(polygon
			(pts
				(arc
					(start 106.440986 -285.93161)
					(mid 106.136186 -286.23641)
					(end 106.440986 -286.54121)
				)
				(arc
					(start 107.38104 -286.54121)
					(mid 107.68584 -286.23641)
					(end 107.38104 -285.93161)
				)
			)
		)
	)
	(zone
		(layers "In1.Cu" "In2.Cu" "In7.Cu" "In8.Cu" "In9.Cu" "In16.Cu")
		(hatch none 0.5)
		(connect_pads
			(clearance 0)
		)
		(min_thickness 0.25)
		(keepout
			(tracks not_allowed)
			(vias allowed)
			(pads allowed)
			(copperpour not_allowed)
			(footprints allowed)
		)
		(placement
			(enabled no)
			(sheetname "")
		)
		(fill yes
			(thermal_gap 0.5)
			(thermal_bridge_width 0.5)
			(island_removal_mode 0)
		)
		(polygon
			(pts
				(arc
					(start 326.141842 -435.16042)
					(mid 326.16416 -435.214302)
					(end 326.218042 -435.23662)
				)
				(arc
					(start 327.157842 -435.23662)
					(mid 327.211724 -435.214302)
					(end 327.234042 -435.16042)
				)
				(arc
					(start 327.234042 -432.618896)
					(mid 327.211724 -432.565014)
					(end 327.157842 -432.542696)
				)
				(arc
					(start 326.218042 -432.542696)
					(mid 326.16416 -432.565014)
					(end 326.141842 -432.618896)
				)
			)
		)
	)
	(zone
		(layers "In1.Cu" "In2.Cu" "In7.Cu" "In8.Cu" "In9.Cu" "In16.Cu")
		(hatch none 0.5)
		(connect_pads
			(clearance 0)
		)
		(min_thickness 0.25)
		(keepout
			(tracks not_allowed)
			(vias allowed)
			(pads allowed)
			(copperpour not_allowed)
			(footprints allowed)
		)
		(placement
			(enabled no)
			(sheetname "")
		)
		(fill yes
			(thermal_gap 0.5)
			(thermal_bridge_width 0.5)
			(island_removal_mode 0)
		)
		(polygon
			(pts
				(arc
					(start 339.141816 -435.16042)
					(mid 339.164134 -435.214302)
					(end 339.218016 -435.23662)
				)
				(arc
					(start 340.157816 -435.23662)
					(mid 340.211698 -435.214302)
					(end 340.234016 -435.16042)
				)
				(arc
					(start 340.234016 -432.618896)
					(mid 340.211698 -432.565014)
					(end 340.157816 -432.542696)
				)
				(arc
					(start 339.218016 -432.542696)
					(mid 339.164134 -432.565014)
					(end 339.141816 -432.618896)
				)
			)
		)
	)
	(zone
		(layers "In1.Cu" "In2.Cu" "In7.Cu" "In8.Cu" "In9.Cu" "In16.Cu")
		(hatch none 0.5)
		(connect_pads
			(clearance 0)
		)
		(min_thickness 0.25)
		(keepout
			(tracks not_allowed)
			(vias allowed)
			(pads allowed)
			(copperpour not_allowed)
			(footprints allowed)
		)
		(placement
			(enabled no)
			(sheetname "")
		)
		(fill yes
			(thermal_gap 0.5)
			(thermal_bridge_width 0.5)
			(island_removal_mode 0)
		)
		(polygon
			(pts
				(arc
					(start 333.141828 -436.160418)
					(mid 333.164146 -436.2143)
					(end 333.218028 -436.236618)
				)
				(arc
					(start 334.157828 -436.236618)
					(mid 334.21171 -436.2143)
					(end 334.234028 -436.160418)
				)
				(arc
					(start 334.234028 -433.618894)
					(mid 334.21171 -433.565012)
					(end 334.157828 -433.542694)
				)
				(arc
					(start 333.218028 -433.542694)
					(mid 333.164146 -433.565012)
					(end 333.141828 -433.618894)
				)
			)
		)
	)
	(zone
		(layers "In1.Cu" "In2.Cu" "In7.Cu" "In8.Cu" "In9.Cu" "In16.Cu")
		(hatch none 0.5)
		(connect_pads
			(clearance 0)
		)
		(min_thickness 0.25)
		(keepout
			(tracks not_allowed)
			(vias allowed)
			(pads allowed)
			(copperpour not_allowed)
			(footprints allowed)
		)
		(placement
			(enabled no)
			(sheetname "")
		)
		(fill yes
			(thermal_gap 0.5)
			(thermal_bridge_width 0.5)
			(island_removal_mode 0)
		)
		(polygon
			(pts
				(arc
					(start 337.14182 -436.160418)
					(mid 337.164138 -436.2143)
					(end 337.21802 -436.236618)
				)
				(arc
					(start 338.15782 -436.236618)
					(mid 338.211702 -436.2143)
					(end 338.23402 -436.160418)
				)
				(arc
					(start 338.23402 -433.618894)
					(mid 338.211702 -433.565012)
					(end 338.15782 -433.542694)
				)
				(arc
					(start 337.21802 -433.542694)
					(mid 337.164138 -433.565012)
					(end 337.14182 -433.618894)
				)
			)
		)
	)
	(zone
		(layers "In1.Cu" "In2.Cu" "In7.Cu" "In8.Cu" "In9.Cu" "In16.Cu")
		(hatch none 0.5)
		(connect_pads
			(clearance 0)
		)
		(min_thickness 0.25)
		(keepout
			(tracks not_allowed)
			(vias allowed)
			(pads allowed)
			(copperpour not_allowed)
			(footprints allowed)
		)
		(placement
			(enabled no)
			(sheetname "")
		)
		(fill yes
			(thermal_gap 0.5)
			(thermal_bridge_width 0.5)
			(island_removal_mode 0)
		)
		(polygon
			(pts
				(arc
					(start 328.141838 -436.160418)
					(mid 328.164156 -436.2143)
					(end 328.218038 -436.236618)
				)
				(arc
					(start 329.157838 -436.236618)
					(mid 329.21172 -436.2143)
					(end 329.234038 -436.160418)
				)
				(arc
					(start 329.234038 -433.618894)
					(mid 329.21172 -433.565012)
					(end 329.157838 -433.542694)
				)
				(arc
					(start 328.218038 -433.542694)
					(mid 328.164156 -433.565012)
					(end 328.141838 -433.618894)
				)
			)
		)
	)
	(zone
		(layers "In1.Cu" "In2.Cu" "In7.Cu" "In8.Cu" "In9.Cu" "In16.Cu")
		(hatch none 0.5)
		(connect_pads
			(clearance 0)
		)
		(min_thickness 0.25)
		(keepout
			(tracks not_allowed)
			(vias allowed)
			(pads allowed)
			(copperpour not_allowed)
			(footprints allowed)
		)
		(placement
			(enabled no)
			(sheetname "")
		)
		(fill yes
			(thermal_gap 0.5)
			(thermal_bridge_width 0.5)
			(island_removal_mode 0)
		)
		(polygon
			(pts
				(arc
					(start 314.141866 -435.16042)
					(mid 314.164184 -435.214302)
					(end 314.218066 -435.23662)
				)
				(arc
					(start 315.157866 -435.23662)
					(mid 315.211748 -435.214302)
					(end 315.234066 -435.16042)
				)
				(arc
					(start 315.234066 -432.618896)
					(mid 315.211748 -432.565014)
					(end 315.157866 -432.542696)
				)
				(arc
					(start 314.218066 -432.542696)
					(mid 314.164184 -432.565014)
					(end 314.141866 -432.618896)
				)
			)
		)
	)
	(zone
		(layers "In1.Cu" "In2.Cu" "In7.Cu" "In8.Cu" "In9.Cu" "In16.Cu")
		(hatch none 0.5)
		(connect_pads
			(clearance 0)
		)
		(min_thickness 0.25)
		(keepout
			(tracks not_allowed)
			(vias allowed)
			(pads allowed)
			(copperpour not_allowed)
			(footprints allowed)
		)
		(placement
			(enabled no)
			(sheetname "")
		)
		(fill yes
			(thermal_gap 0.5)
			(thermal_bridge_width 0.5)
			(island_removal_mode 0)
		)
		(polygon
			(pts
				(arc
					(start 316.141862 -436.160418)
					(mid 316.16418 -436.2143)
					(end 316.218062 -436.236618)
				)
				(arc
					(start 317.157862 -436.236618)
					(mid 317.211744 -436.2143)
					(end 317.234062 -436.160418)
				)
				(arc
					(start 317.234062 -433.618894)
					(mid 317.211744 -433.565012)
					(end 317.157862 -433.542694)
				)
				(arc
					(start 316.218062 -433.542694)
					(mid 316.16418 -433.565012)
					(end 316.141862 -433.618894)
				)
			)
		)
	)
	(zone
		(layers "In1.Cu" "In2.Cu" "In7.Cu" "In8.Cu" "In9.Cu" "In16.Cu")
		(hatch none 0.5)
		(connect_pads
			(clearance 0)
		)
		(min_thickness 0.25)
		(keepout
			(tracks not_allowed)
			(vias allowed)
			(pads allowed)
			(copperpour not_allowed)
			(footprints allowed)
		)
		(placement
			(enabled no)
			(sheetname "")
		)
		(fill yes
			(thermal_gap 0.5)
			(thermal_bridge_width 0.5)
			(island_removal_mode 0)
		)
		(polygon
			(pts
				(arc
					(start 343.141808 -435.16042)
					(mid 343.164126 -435.214302)
					(end 343.218008 -435.23662)
				)
				(arc
					(start 344.157808 -435.23662)
					(mid 344.21169 -435.214302)
					(end 344.234008 -435.16042)
				)
				(arc
					(start 344.234008 -432.618896)
					(mid 344.21169 -432.565014)
					(end 344.157808 -432.542696)
				)
				(arc
					(start 343.218008 -432.542696)
					(mid 343.164126 -432.565014)
					(end 343.141808 -432.618896)
				)
			)
		)
	)
	(zone
		(layers "In1.Cu" "In2.Cu" "In7.Cu" "In8.Cu" "In9.Cu" "In16.Cu")
		(hatch none 0.5)
		(connect_pads
			(clearance 0)
		)
		(min_thickness 0.25)
		(keepout
			(tracks not_allowed)
			(vias allowed)
			(pads allowed)
			(copperpour not_allowed)
			(footprints allowed)
		)
		(placement
			(enabled no)
			(sheetname "")
		)
		(fill yes
			(thermal_gap 0.5)
			(thermal_bridge_width 0.5)
			(island_removal_mode 0)
		)
		(polygon
			(pts
				(arc
					(start 318.141858 -435.16042)
					(mid 318.164176 -435.214302)
					(end 318.218058 -435.23662)
				)
				(arc
					(start 319.157858 -435.23662)
					(mid 319.21174 -435.214302)
					(end 319.234058 -435.16042)
				)
				(arc
					(start 319.234058 -432.618896)
					(mid 319.21174 -432.565014)
					(end 319.157858 -432.542696)
				)
				(arc
					(start 318.218058 -432.542696)
					(mid 318.164176 -432.565014)
					(end 318.141858 -432.618896)
				)
			)
		)
	)
	(zone
		(layers "In1.Cu" "In2.Cu" "In7.Cu" "In8.Cu" "In9.Cu" "In16.Cu")
		(hatch none 0.5)
		(connect_pads
			(clearance 0)
		)
		(min_thickness 0.25)
		(keepout
			(tracks not_allowed)
			(vias allowed)
			(pads allowed)
			(copperpour not_allowed)
			(footprints allowed)
		)
		(placement
			(enabled no)
			(sheetname "")
		)
		(fill yes
			(thermal_gap 0.5)
			(thermal_bridge_width 0.5)
			(island_removal_mode 0)
		)
		(polygon
			(pts
				(arc
					(start 345.141804 -436.160418)
					(mid 345.164122 -436.2143)
					(end 345.218004 -436.236618)
				)
				(arc
					(start 346.157804 -436.236618)
					(mid 346.211686 -436.2143)
					(end 346.234004 -436.160418)
				)
				(arc
					(start 346.234004 -433.618894)
					(mid 346.211686 -433.565012)
					(end 346.157804 -433.542694)
				)
				(arc
					(start 345.218004 -433.542694)
					(mid 345.164122 -433.565012)
					(end 345.141804 -433.618894)
				)
			)
		)
	)
	(zone
		(layers "In1.Cu" "In2.Cu" "In7.Cu" "In8.Cu" "In9.Cu" "In16.Cu")
		(hatch none 0.5)
		(connect_pads
			(clearance 0)
		)
		(min_thickness 0.25)
		(keepout
			(tracks not_allowed)
			(vias allowed)
			(pads allowed)
			(copperpour not_allowed)
			(footprints allowed)
		)
		(placement
			(enabled no)
			(sheetname "")
		)
		(fill yes
			(thermal_gap 0.5)
			(thermal_bridge_width 0.5)
			(island_removal_mode 0)
		)
		(polygon
			(pts
				(arc
					(start 341.141812 -436.160418)
					(mid 341.16413 -436.2143)
					(end 341.218012 -436.236618)
				)
				(arc
					(start 342.157812 -436.236618)
					(mid 342.211694 -436.2143)
					(end 342.234012 -436.160418)
				)
				(arc
					(start 342.234012 -433.618894)
					(mid 342.211694 -433.565012)
					(end 342.157812 -433.542694)
				)
				(arc
					(start 341.218012 -433.542694)
					(mid 341.16413 -433.565012)
					(end 341.141812 -433.618894)
				)
			)
		)
	)
	(zone
		(layers "In1.Cu" "In2.Cu" "In7.Cu" "In8.Cu" "In9.Cu" "In16.Cu")
		(hatch none 0.5)
		(connect_pads
			(clearance 0)
		)
		(min_thickness 0.25)
		(keepout
			(tracks not_allowed)
			(vias allowed)
			(pads allowed)
			(copperpour not_allowed)
			(footprints allowed)
		)
		(placement
			(enabled no)
			(sheetname "")
		)
		(fill yes
			(thermal_gap 0.5)
			(thermal_bridge_width 0.5)
			(island_removal_mode 0)
		)
		(polygon
			(pts
				(arc
					(start 331.141832 -435.16042)
					(mid 331.16415 -435.214302)
					(end 331.218032 -435.23662)
				)
				(arc
					(start 332.157832 -435.23662)
					(mid 332.211714 -435.214302)
					(end 332.234032 -435.16042)
				)
				(arc
					(start 332.234032 -432.618896)
					(mid 332.211714 -432.565014)
					(end 332.157832 -432.542696)
				)
				(arc
					(start 331.218032 -432.542696)
					(mid 331.16415 -432.565014)
					(end 331.141832 -432.618896)
				)
			)
		)
	)
	(zone
		(layers "In1.Cu" "In2.Cu" "In7.Cu" "In8.Cu" "In9.Cu" "In16.Cu")
		(hatch none 0.5)
		(connect_pads
			(clearance 0)
		)
		(min_thickness 0.25)
		(keepout
			(tracks not_allowed)
			(vias allowed)
			(pads allowed)
			(copperpour not_allowed)
			(footprints allowed)
		)
		(placement
			(enabled no)
			(sheetname "")
		)
		(fill yes
			(thermal_gap 0.5)
			(thermal_bridge_width 0.5)
			(island_removal_mode 0)
		)
		(polygon
			(pts
				(arc
					(start 335.141824 -435.16042)
					(mid 335.164142 -435.214302)
					(end 335.218024 -435.23662)
				)
				(arc
					(start 336.157824 -435.23662)
					(mid 336.211706 -435.214302)
					(end 336.234024 -435.16042)
				)
				(arc
					(start 336.234024 -432.618896)
					(mid 336.211706 -432.565014)
					(end 336.157824 -432.542696)
				)
				(arc
					(start 335.218024 -432.542696)
					(mid 335.164142 -432.565014)
					(end 335.141824 -432.618896)
				)
			)
		)
	)
	(zone
		(layers "In1.Cu" "In2.Cu" "In7.Cu" "In8.Cu" "In9.Cu" "In16.Cu")
		(hatch none 0.5)
		(connect_pads
			(clearance 0)
		)
		(min_thickness 0.25)
		(keepout
			(tracks not_allowed)
			(vias allowed)
			(pads allowed)
			(copperpour not_allowed)
			(footprints allowed)
		)
		(placement
			(enabled no)
			(sheetname "")
		)
		(fill yes
			(thermal_gap 0.5)
			(thermal_bridge_width 0.5)
			(island_removal_mode 0)
		)
		(polygon
			(pts
				(arc
					(start 324.141846 -436.160418)
					(mid 324.164164 -436.2143)
					(end 324.218046 -436.236618)
				)
				(arc
					(start 325.157846 -436.236618)
					(mid 325.211728 -436.2143)
					(end 325.234046 -436.160418)
				)
				(arc
					(start 325.234046 -433.618894)
					(mid 325.211728 -433.565012)
					(end 325.157846 -433.542694)
				)
				(arc
					(start 324.218046 -433.542694)
					(mid 324.164164 -433.565012)
					(end 324.141846 -433.618894)
				)
			)
		)
	)
	(zone
		(layers "In1.Cu" "In2.Cu" "In7.Cu" "In8.Cu" "In9.Cu" "In16.Cu")
		(hatch none 0.5)
		(connect_pads
			(clearance 0)
		)
		(min_thickness 0.25)
		(keepout
			(tracks not_allowed)
			(vias allowed)
			(pads allowed)
			(copperpour not_allowed)
			(footprints allowed)
		)
		(placement
			(enabled no)
			(sheetname "")
		)
		(fill yes
			(thermal_gap 0.5)
			(thermal_bridge_width 0.5)
			(island_removal_mode 0)
		)
		(polygon
			(pts
				(arc
					(start 320.141854 -436.160418)
					(mid 320.164172 -436.2143)
					(end 320.218054 -436.236618)
				)
				(arc
					(start 321.157854 -436.236618)
					(mid 321.211736 -436.2143)
					(end 321.234054 -436.160418)
				)
				(arc
					(start 321.234054 -433.618894)
					(mid 321.211736 -433.565012)
					(end 321.157854 -433.542694)
				)
				(arc
					(start 320.218054 -433.542694)
					(mid 320.164172 -433.565012)
					(end 320.141854 -433.618894)
				)
			)
		)
	)
	(zone
		(layers "In1.Cu" "In2.Cu" "In7.Cu" "In8.Cu" "In9.Cu" "In16.Cu")
		(hatch none 0.5)
		(connect_pads
			(clearance 0)
		)
		(min_thickness 0.25)
		(keepout
			(tracks not_allowed)
			(vias allowed)
			(pads allowed)
			(copperpour not_allowed)
			(footprints allowed)
		)
		(placement
			(enabled no)
			(sheetname "")
		)
		(fill yes
			(thermal_gap 0.5)
			(thermal_bridge_width 0.5)
			(island_removal_mode 0)
		)
		(polygon
			(pts
				(arc
					(start 322.14185 -435.16042)
					(mid 322.164168 -435.214302)
					(end 322.21805 -435.23662)
				)
				(arc
					(start 323.15785 -435.23662)
					(mid 323.211732 -435.214302)
					(end 323.23405 -435.16042)
				)
				(arc
					(start 323.23405 -432.618896)
					(mid 323.211732 -432.565014)
					(end 323.15785 -432.542696)
				)
				(arc
					(start 322.21805 -432.542696)
					(mid 322.164168 -432.565014)
					(end 322.14185 -432.618896)
				)
			)
		)
	)
	(zone
		(layers "In1.Cu" "In2.Cu" "In8.Cu" "In9.Cu" "In10.Cu" "In12.Cu" "In13.Cu"
			"In14.Cu" "In16.Cu"
		)
		(hatch none 0.5)
		(connect_pads
			(clearance 0)
		)
		(min_thickness 0.25)
		(keepout
			(tracks not_allowed)
			(vias allowed)
			(pads allowed)
			(copperpour not_allowed)
			(footprints allowed)
		)
		(placement
			(enabled no)
			(sheetname "")
		)
		(fill yes
			(thermal_gap 0.5)
			(thermal_bridge_width 0.5)
			(island_removal_mode 0)
		)
		(polygon
			(pts
				(arc
					(start 322.14185 -427.960536)
					(mid 322.164168 -428.014418)
					(end 322.21805 -428.036736)
				)
				(arc
					(start 323.15785 -428.036736)
					(mid 323.211732 -428.014418)
					(end 323.23405 -427.960536)
				)
				(arc
					(start 323.23405 -425.419012)
					(mid 323.211732 -425.36513)
					(end 323.15785 -425.342812)
				)
				(arc
					(start 322.21805 -425.342812)
					(mid 322.164168 -425.36513)
					(end 322.14185 -425.419012)
				)
			)
		)
	)
	(zone
		(layers "In1.Cu" "In2.Cu" "In8.Cu" "In9.Cu" "In10.Cu" "In12.Cu" "In13.Cu"
			"In14.Cu" "In16.Cu"
		)
		(hatch none 0.5)
		(connect_pads
			(clearance 0)
		)
		(min_thickness 0.25)
		(keepout
			(tracks not_allowed)
			(vias allowed)
			(pads allowed)
			(copperpour not_allowed)
			(footprints allowed)
		)
		(placement
			(enabled no)
			(sheetname "")
		)
		(fill yes
			(thermal_gap 0.5)
			(thermal_bridge_width 0.5)
			(island_removal_mode 0)
		)
		(polygon
			(pts
				(arc
					(start 326.141842 -427.960536)
					(mid 326.16416 -428.014418)
					(end 326.218042 -428.036736)
				)
				(arc
					(start 327.157842 -428.036736)
					(mid 327.211724 -428.014418)
					(end 327.234042 -427.960536)
				)
				(arc
					(start 327.234042 -425.419012)
					(mid 327.211724 -425.36513)
					(end 327.157842 -425.342812)
				)
				(arc
					(start 326.218042 -425.342812)
					(mid 326.16416 -425.36513)
					(end 326.141842 -425.419012)
				)
			)
		)
	)
	(zone
		(layers "In1.Cu" "In2.Cu" "In8.Cu" "In9.Cu" "In10.Cu" "In12.Cu" "In13.Cu"
			"In14.Cu" "In16.Cu"
		)
		(hatch none 0.5)
		(connect_pads
			(clearance 0)
		)
		(min_thickness 0.25)
		(keepout
			(tracks not_allowed)
			(vias allowed)
			(pads allowed)
			(copperpour not_allowed)
			(footprints allowed)
		)
		(placement
			(enabled no)
			(sheetname "")
		)
		(fill yes
			(thermal_gap 0.5)
			(thermal_bridge_width 0.5)
			(island_removal_mode 0)
		)
		(polygon
			(pts
				(arc
					(start 314.141866 -427.960536)
					(mid 314.164184 -428.014418)
					(end 314.218066 -428.036736)
				)
				(arc
					(start 315.157866 -428.036736)
					(mid 315.211748 -428.014418)
					(end 315.234066 -427.960536)
				)
				(arc
					(start 315.234066 -425.419012)
					(mid 315.211748 -425.36513)
					(end 315.157866 -425.342812)
				)
				(arc
					(start 314.218066 -425.342812)
					(mid 314.164184 -425.36513)
					(end 314.141866 -425.419012)
				)
			)
		)
	)
	(zone
		(layers "In1.Cu" "In2.Cu" "In8.Cu" "In9.Cu" "In10.Cu" "In12.Cu" "In13.Cu"
			"In14.Cu" "In16.Cu"
		)
		(hatch none 0.5)
		(connect_pads
			(clearance 0)
		)
		(min_thickness 0.25)
		(keepout
			(tracks not_allowed)
			(vias allowed)
			(pads allowed)
			(copperpour not_allowed)
			(footprints allowed)
		)
		(placement
			(enabled no)
			(sheetname "")
		)
		(fill yes
			(thermal_gap 0.5)
			(thermal_bridge_width 0.5)
			(island_removal_mode 0)
		)
		(polygon
			(pts
				(arc
					(start 343.141808 -427.960536)
					(mid 343.164126 -428.014418)
					(end 343.218008 -428.036736)
				)
				(arc
					(start 344.157808 -428.036736)
					(mid 344.21169 -428.014418)
					(end 344.234008 -427.960536)
				)
				(arc
					(start 344.234008 -425.419012)
					(mid 344.21169 -425.36513)
					(end 344.157808 -425.342812)
				)
				(arc
					(start 343.218008 -425.342812)
					(mid 343.164126 -425.36513)
					(end 343.141808 -425.419012)
				)
			)
		)
	)
	(zone
		(layers "In1.Cu" "In2.Cu" "In8.Cu" "In9.Cu" "In10.Cu" "In12.Cu" "In13.Cu"
			"In14.Cu" "In16.Cu"
		)
		(hatch none 0.5)
		(connect_pads
			(clearance 0)
		)
		(min_thickness 0.25)
		(keepout
			(tracks not_allowed)
			(vias allowed)
			(pads allowed)
			(copperpour not_allowed)
			(footprints allowed)
		)
		(placement
			(enabled no)
			(sheetname "")
		)
		(fill yes
			(thermal_gap 0.5)
			(thermal_bridge_width 0.5)
			(island_removal_mode 0)
		)
		(polygon
			(pts
				(arc
					(start 318.141858 -427.960536)
					(mid 318.164176 -428.014418)
					(end 318.218058 -428.036736)
				)
				(arc
					(start 319.157858 -428.036736)
					(mid 319.21174 -428.014418)
					(end 319.234058 -427.960536)
				)
				(arc
					(start 319.234058 -425.419012)
					(mid 319.21174 -425.36513)
					(end 319.157858 -425.342812)
				)
				(arc
					(start 318.218058 -425.342812)
					(mid 318.164176 -425.36513)
					(end 318.141858 -425.419012)
				)
			)
		)
	)
	(zone
		(layers "In1.Cu" "In2.Cu" "In8.Cu" "In9.Cu" "In10.Cu" "In12.Cu" "In13.Cu"
			"In14.Cu" "In16.Cu"
		)
		(hatch none 0.5)
		(connect_pads
			(clearance 0)
		)
		(min_thickness 0.25)
		(keepout
			(tracks not_allowed)
			(vias allowed)
			(pads allowed)
			(copperpour not_allowed)
			(footprints allowed)
		)
		(placement
			(enabled no)
			(sheetname "")
		)
		(fill yes
			(thermal_gap 0.5)
			(thermal_bridge_width 0.5)
			(island_removal_mode 0)
		)
		(polygon
			(pts
				(arc
					(start 339.141816 -427.960536)
					(mid 339.164134 -428.014418)
					(end 339.218016 -428.036736)
				)
				(arc
					(start 340.157816 -428.036736)
					(mid 340.211698 -428.014418)
					(end 340.234016 -427.960536)
				)
				(arc
					(start 340.234016 -425.419012)
					(mid 340.211698 -425.36513)
					(end 340.157816 -425.342812)
				)
				(arc
					(start 339.218016 -425.342812)
					(mid 339.164134 -425.36513)
					(end 339.141816 -425.419012)
				)
			)
		)
	)
	(zone
		(layers "In1.Cu" "In2.Cu" "In8.Cu" "In9.Cu" "In10.Cu" "In12.Cu" "In13.Cu"
			"In14.Cu" "In16.Cu"
		)
		(hatch none 0.5)
		(connect_pads
			(clearance 0)
		)
		(min_thickness 0.25)
		(keepout
			(tracks not_allowed)
			(vias allowed)
			(pads allowed)
			(copperpour not_allowed)
			(footprints allowed)
		)
		(placement
			(enabled no)
			(sheetname "")
		)
		(fill yes
			(thermal_gap 0.5)
			(thermal_bridge_width 0.5)
			(island_removal_mode 0)
		)
		(polygon
			(pts
				(arc
					(start 335.141824 -427.960536)
					(mid 335.164142 -428.014418)
					(end 335.218024 -428.036736)
				)
				(arc
					(start 336.157824 -428.036736)
					(mid 336.211706 -428.014418)
					(end 336.234024 -427.960536)
				)
				(arc
					(start 336.234024 -425.419012)
					(mid 336.211706 -425.36513)
					(end 336.157824 -425.342812)
				)
				(arc
					(start 335.218024 -425.342812)
					(mid 335.164142 -425.36513)
					(end 335.141824 -425.419012)
				)
			)
		)
	)
	(zone
		(layers "In1.Cu" "In2.Cu" "In8.Cu" "In9.Cu" "In10.Cu" "In12.Cu" "In13.Cu"
			"In14.Cu" "In16.Cu"
		)
		(hatch none 0.5)
		(connect_pads
			(clearance 0)
		)
		(min_thickness 0.25)
		(keepout
			(tracks not_allowed)
			(vias allowed)
			(pads allowed)
			(copperpour not_allowed)
			(footprints allowed)
		)
		(placement
			(enabled no)
			(sheetname "")
		)
		(fill yes
			(thermal_gap 0.5)
			(thermal_bridge_width 0.5)
			(island_removal_mode 0)
		)
		(polygon
			(pts
				(arc
					(start 331.141832 -427.960536)
					(mid 331.16415 -428.014418)
					(end 331.218032 -428.036736)
				)
				(arc
					(start 332.157832 -428.036736)
					(mid 332.211714 -428.014418)
					(end 332.234032 -427.960536)
				)
				(arc
					(start 332.234032 -425.419012)
					(mid 332.211714 -425.36513)
					(end 332.157832 -425.342812)
				)
				(arc
					(start 331.218032 -425.342812)
					(mid 331.16415 -425.36513)
					(end 331.141832 -425.419012)
				)
			)
		)
	)
	(zone
		(layers "In1.Cu" "In3.Cu")
		(hatch none 0.5)
		(connect_pads
			(clearance 0)
		)
		(min_thickness 0.25)
		(keepout
			(tracks not_allowed)
			(vias allowed)
			(pads allowed)
			(copperpour not_allowed)
			(footprints allowed)
		)
		(placement
			(enabled no)
			(sheetname "")
		)
		(fill yes
			(thermal_gap 0.5)
			(thermal_bridge_width 0.5)
			(island_removal_mode 0)
		)
		(polygon
			(pts
				(arc
					(start 419.138354 -397.967962)
					(mid 419.250603 -398.103409)
					(end 419.419024 -398.154144)
				)
				(arc
					(start 419.419024 -398.154144)
					(mid 419.63455 -398.06487)
					(end 419.723824 -397.849344)
				)
				(arc
					(start 419.723824 -397.849344)
					(mid 419.71399 -397.772291)
					(end 419.684962 -397.700246)
				)
				(arc
					(start 419.305994 -397.053562)
					(mid 418.887481 -396.881187)
					(end 418.758878 -397.315182)
				)
			)
		)
	)
	(zone
		(layers "In1.Cu" "In3.Cu")
		(hatch none 0.5)
		(connect_pads
			(clearance 0)
		)
		(min_thickness 0.25)
		(keepout
			(tracks not_allowed)
			(vias allowed)
			(pads allowed)
			(copperpour not_allowed)
			(footprints allowed)
		)
		(placement
			(enabled no)
			(sheetname "")
		)
		(fill yes
			(thermal_gap 0.5)
			(thermal_bridge_width 0.5)
			(island_removal_mode 0)
		)
		(polygon
			(pts
				(arc
					(start 404.738332 -397.967962)
					(mid 404.850581 -398.103409)
					(end 405.019002 -398.154144)
				)
				(arc
					(start 405.019002 -398.154144)
					(mid 405.234528 -398.06487)
					(end 405.323802 -397.849344)
				)
				(arc
					(start 405.323802 -397.849344)
					(mid 405.313968 -397.772291)
					(end 405.28494 -397.700246)
				)
				(arc
					(start 404.905972 -397.053562)
					(mid 404.487459 -396.881187)
					(end 404.358856 -397.315182)
				)
			)
		)
	)
	(zone
		(layers "In1.Cu" "In3.Cu")
		(hatch none 0.5)
		(connect_pads
			(clearance 0)
		)
		(min_thickness 0.25)
		(keepout
			(tracks not_allowed)
			(vias allowed)
			(pads allowed)
			(copperpour not_allowed)
			(footprints allowed)
		)
		(placement
			(enabled no)
			(sheetname "")
		)
		(fill yes
			(thermal_gap 0.5)
			(thermal_bridge_width 0.5)
			(island_removal_mode 0)
		)
		(polygon
			(pts
				(arc
					(start 307.510434 -397.967962)
					(mid 307.622683 -398.103409)
					(end 307.791104 -398.154144)
				)
				(arc
					(start 307.791104 -398.154144)
					(mid 308.00663 -398.06487)
					(end 308.095904 -397.849344)
				)
				(arc
					(start 308.095904 -397.849344)
					(mid 308.08607 -397.772291)
					(end 308.057042 -397.700246)
				)
				(arc
					(start 307.678074 -397.053562)
					(mid 307.259561 -396.881187)
					(end 307.130958 -397.315182)
				)
			)
		)
	)
	(zone
		(layers "In1.Cu" "In3.Cu")
		(hatch none 0.5)
		(connect_pads
			(clearance 0)
		)
		(min_thickness 0.25)
		(keepout
			(tracks not_allowed)
			(vias allowed)
			(pads allowed)
			(copperpour not_allowed)
			(footprints allowed)
		)
		(placement
			(enabled no)
			(sheetname "")
		)
		(fill yes
			(thermal_gap 0.5)
			(thermal_bridge_width 0.5)
			(island_removal_mode 0)
		)
		(polygon
			(pts
				(arc
					(start 318.310514 -397.967962)
					(mid 318.422763 -398.103409)
					(end 318.591184 -398.154144)
				)
				(arc
					(start 318.591184 -398.154144)
					(mid 318.80671 -398.06487)
					(end 318.895984 -397.849344)
				)
				(arc
					(start 318.895984 -397.849344)
					(mid 318.88615 -397.772291)
					(end 318.857122 -397.700246)
				)
				(arc
					(start 318.478154 -397.053562)
					(mid 318.059641 -396.881187)
					(end 317.931038 -397.315182)
				)
			)
		)
	)
	(zone
		(layers "In1.Cu" "In3.Cu")
		(hatch none 0.5)
		(connect_pads
			(clearance 0)
		)
		(min_thickness 0.25)
		(keepout
			(tracks not_allowed)
			(vias allowed)
			(pads allowed)
			(copperpour not_allowed)
			(footprints allowed)
		)
		(placement
			(enabled no)
			(sheetname "")
		)
		(fill yes
			(thermal_gap 0.5)
			(thermal_bridge_width 0.5)
			(island_removal_mode 0)
		)
		(polygon
			(pts
				(arc
					(start 415.538412 -397.967962)
					(mid 415.650661 -398.103409)
					(end 415.819082 -398.154144)
				)
				(arc
					(start 415.819082 -398.154144)
					(mid 416.034608 -398.06487)
					(end 416.123882 -397.849344)
				)
				(arc
					(start 416.123882 -397.849344)
					(mid 416.114048 -397.772291)
					(end 416.08502 -397.700246)
				)
				(arc
					(start 415.706052 -397.053562)
					(mid 415.287539 -396.881187)
					(end 415.158936 -397.315182)
				)
			)
		)
	)
	(zone
		(layers "In1.Cu" "In3.Cu")
		(hatch none 0.5)
		(connect_pads
			(clearance 0)
		)
		(min_thickness 0.25)
		(keepout
			(tracks not_allowed)
			(vias allowed)
			(pads allowed)
			(copperpour not_allowed)
			(footprints allowed)
		)
		(placement
			(enabled no)
			(sheetname "")
		)
		(fill yes
			(thermal_gap 0.5)
			(thermal_bridge_width 0.5)
			(island_removal_mode 0)
		)
		(polygon
			(pts
				(arc
					(start 407.138378 -397.967962)
					(mid 407.250627 -398.103409)
					(end 407.419048 -398.154144)
				)
				(arc
					(start 407.419048 -398.154144)
					(mid 407.634574 -398.06487)
					(end 407.723848 -397.849344)
				)
				(arc
					(start 407.723848 -397.849344)
					(mid 407.714014 -397.772291)
					(end 407.684986 -397.700246)
				)
				(arc
					(start 407.306018 -397.053562)
					(mid 406.887505 -396.881187)
					(end 406.758902 -397.315182)
				)
			)
		)
	)
	(zone
		(layers "In1.Cu" "In3.Cu")
		(hatch none 0.5)
		(connect_pads
			(clearance 0)
		)
		(min_thickness 0.25)
		(keepout
			(tracks not_allowed)
			(vias allowed)
			(pads allowed)
			(copperpour not_allowed)
			(footprints allowed)
		)
		(placement
			(enabled no)
			(sheetname "")
		)
		(fill yes
			(thermal_gap 0.5)
			(thermal_bridge_width 0.5)
			(island_removal_mode 0)
		)
		(polygon
			(pts
				(arc
					(start 416.738308 -397.967962)
					(mid 416.850557 -398.103409)
					(end 417.018978 -398.154144)
				)
				(arc
					(start 417.018978 -398.154144)
					(mid 417.234504 -398.06487)
					(end 417.323778 -397.849344)
				)
				(arc
					(start 417.323778 -397.849344)
					(mid 417.313944 -397.772291)
					(end 417.284916 -397.700246)
				)
				(arc
					(start 416.905948 -397.053562)
					(mid 416.487435 -396.881187)
					(end 416.358832 -397.315182)
				)
			)
		)
	)
	(zone
		(layers "In1.Cu" "In3.Cu")
		(hatch none 0.5)
		(connect_pads
			(clearance 0)
		)
		(min_thickness 0.25)
		(keepout
			(tracks not_allowed)
			(vias allowed)
			(pads allowed)
			(copperpour not_allowed)
			(footprints allowed)
		)
		(placement
			(enabled no)
			(sheetname "")
		)
		(fill yes
			(thermal_gap 0.5)
			(thermal_bridge_width 0.5)
			(island_removal_mode 0)
		)
		(polygon
			(pts
				(arc
					(start 421.5384 -397.967962)
					(mid 421.650649 -398.103409)
					(end 421.81907 -398.154144)
				)
				(arc
					(start 421.81907 -398.154144)
					(mid 422.034596 -398.06487)
					(end 422.12387 -397.849344)
				)
				(arc
					(start 422.12387 -397.849344)
					(mid 422.114036 -397.772291)
					(end 422.085008 -397.700246)
				)
				(arc
					(start 421.70604 -397.053562)
					(mid 421.287527 -396.881187)
					(end 421.158924 -397.315182)
				)
			)
		)
	)
	(zone
		(layers "In1.Cu" "In3.Cu")
		(hatch none 0.5)
		(connect_pads
			(clearance 0)
		)
		(min_thickness 0.25)
		(keepout
			(tracks not_allowed)
			(vias allowed)
			(pads allowed)
			(copperpour not_allowed)
			(footprints allowed)
		)
		(placement
			(enabled no)
			(sheetname "")
		)
		(fill yes
			(thermal_gap 0.5)
			(thermal_bridge_width 0.5)
			(island_removal_mode 0)
		)
		(polygon
			(pts
				(arc
					(start 320.71056 -397.967962)
					(mid 320.822809 -398.103409)
					(end 320.99123 -398.154144)
				)
				(arc
					(start 320.99123 -398.154144)
					(mid 321.206756 -398.06487)
					(end 321.29603 -397.849344)
				)
				(arc
					(start 321.29603 -397.849344)
					(mid 321.286196 -397.772291)
					(end 321.257168 -397.700246)
				)
				(arc
					(start 320.8782 -397.053562)
					(mid 320.459687 -396.881187)
					(end 320.331084 -397.315182)
				)
			)
		)
	)
	(zone
		(layers "In1.Cu" "In3.Cu")
		(hatch none 0.5)
		(connect_pads
			(clearance 0)
		)
		(min_thickness 0.25)
		(keepout
			(tracks not_allowed)
			(vias allowed)
			(pads allowed)
			(copperpour not_allowed)
			(footprints allowed)
		)
		(placement
			(enabled no)
			(sheetname "")
		)
		(fill yes
			(thermal_gap 0.5)
			(thermal_bridge_width 0.5)
			(island_removal_mode 0)
		)
		(polygon
			(pts
				(arc
					(start 160.738312 -389.585962)
					(mid 160.850561 -389.721409)
					(end 161.018982 -389.772144)
				)
				(arc
					(start 161.018982 -389.772144)
					(mid 161.234508 -389.68287)
					(end 161.323782 -389.467344)
				)
				(arc
					(start 161.323782 -389.467344)
					(mid 161.313948 -389.390291)
					(end 161.28492 -389.318246)
				)
				(arc
					(start 160.905952 -388.671562)
					(mid 160.487439 -388.499187)
					(end 160.358836 -388.933182)
				)
			)
		)
	)
	(zone
		(layers "In1.Cu" "In3.Cu")
		(hatch none 0.5)
		(connect_pads
			(clearance 0)
		)
		(min_thickness 0.25)
		(keepout
			(tracks not_allowed)
			(vias allowed)
			(pads allowed)
			(copperpour not_allowed)
			(footprints allowed)
		)
		(placement
			(enabled no)
			(sheetname "")
		)
		(fill yes
			(thermal_gap 0.5)
			(thermal_bridge_width 0.5)
			(island_removal_mode 0)
		)
		(polygon
			(pts
				(arc
					(start 148.738336 -389.585962)
					(mid 148.850585 -389.721409)
					(end 149.019006 -389.772144)
				)
				(arc
					(start 149.019006 -389.772144)
					(mid 149.234532 -389.68287)
					(end 149.323806 -389.467344)
				)
				(arc
					(start 149.323806 -389.467344)
					(mid 149.313972 -389.390291)
					(end 149.284944 -389.318246)
				)
				(arc
					(start 148.905976 -388.671562)
					(mid 148.487463 -388.499187)
					(end 148.35886 -388.933182)
				)
			)
		)
	)
	(zone
		(layers "In1.Cu" "In3.Cu")
		(hatch none 0.5)
		(connect_pads
			(clearance 0)
		)
		(min_thickness 0.25)
		(keepout
			(tracks not_allowed)
			(vias allowed)
			(pads allowed)
			(copperpour not_allowed)
			(footprints allowed)
		)
		(placement
			(enabled no)
			(sheetname "")
		)
		(fill yes
			(thermal_gap 0.5)
			(thermal_bridge_width 0.5)
			(island_removal_mode 0)
		)
		(polygon
			(pts
				(arc
					(start 157.13837 -389.585962)
					(mid 157.250619 -389.721409)
					(end 157.41904 -389.772144)
				)
				(arc
					(start 157.41904 -389.772144)
					(mid 157.634566 -389.68287)
					(end 157.72384 -389.467344)
				)
				(arc
					(start 157.72384 -389.467344)
					(mid 157.714006 -389.390291)
					(end 157.684978 -389.318246)
				)
				(arc
					(start 157.30601 -388.671562)
					(mid 156.887497 -388.499187)
					(end 156.758894 -388.933182)
				)
			)
		)
	)
	(zone
		(layers "In1.Cu" "In3.Cu")
		(hatch none 0.5)
		(connect_pads
			(clearance 0)
		)
		(min_thickness 0.25)
		(keepout
			(tracks not_allowed)
			(vias allowed)
			(pads allowed)
			(copperpour not_allowed)
			(footprints allowed)
		)
		(placement
			(enabled no)
			(sheetname "")
		)
		(fill yes
			(thermal_gap 0.5)
			(thermal_bridge_width 0.5)
			(island_removal_mode 0)
		)
		(polygon
			(pts
				(arc
					(start 151.138382 -389.585962)
					(mid 151.250631 -389.721409)
					(end 151.419052 -389.772144)
				)
				(arc
					(start 151.419052 -389.772144)
					(mid 151.634578 -389.68287)
					(end 151.723852 -389.467344)
				)
				(arc
					(start 151.723852 -389.467344)
					(mid 151.714018 -389.390291)
					(end 151.68499 -389.318246)
				)
				(arc
					(start 151.306022 -388.671562)
					(mid 150.887509 -388.499187)
					(end 150.758906 -388.933182)
				)
			)
		)
	)
	(zone
		(layers "In1.Cu" "In3.Cu")
		(hatch none 0.5)
		(connect_pads
			(clearance 0)
		)
		(min_thickness 0.25)
		(keepout
			(tracks not_allowed)
			(vias allowed)
			(pads allowed)
			(copperpour not_allowed)
			(footprints allowed)
		)
		(placement
			(enabled no)
			(sheetname "")
		)
		(fill yes
			(thermal_gap 0.5)
			(thermal_bridge_width 0.5)
			(island_removal_mode 0)
		)
		(polygon
			(pts
				(arc
					(start 411.93847 -397.967962)
					(mid 412.050719 -398.103409)
					(end 412.21914 -398.154144)
				)
				(arc
					(start 412.21914 -398.154144)
					(mid 412.434666 -398.06487)
					(end 412.52394 -397.849344)
				)
				(arc
					(start 412.52394 -397.849344)
					(mid 412.514106 -397.772291)
					(end 412.485078 -397.700246)
				)
				(arc
					(start 412.10611 -397.053562)
					(mid 411.687597 -396.881187)
					(end 411.558994 -397.315182)
				)
			)
		)
	)
	(zone
		(layers "In1.Cu" "In3.Cu")
		(hatch none 0.5)
		(connect_pads
			(clearance 0)
		)
		(min_thickness 0.25)
		(keepout
			(tracks not_allowed)
			(vias allowed)
			(pads allowed)
			(copperpour not_allowed)
			(footprints allowed)
		)
		(placement
			(enabled no)
			(sheetname "")
		)
		(fill yes
			(thermal_gap 0.5)
			(thermal_bridge_width 0.5)
			(island_removal_mode 0)
		)
		(polygon
			(pts
				(arc
					(start 313.510422 -397.967962)
					(mid 313.622671 -398.103409)
					(end 313.791092 -398.154144)
				)
				(arc
					(start 313.791092 -398.154144)
					(mid 314.006618 -398.06487)
					(end 314.095892 -397.849344)
				)
				(arc
					(start 314.095892 -397.849344)
					(mid 314.086058 -397.772291)
					(end 314.05703 -397.700246)
				)
				(arc
					(start 313.678062 -397.053562)
					(mid 313.259549 -396.881187)
					(end 313.130946 -397.315182)
				)
			)
		)
	)
	(zone
		(layers "In1.Cu" "In3.Cu")
		(hatch none 0.5)
		(connect_pads
			(clearance 0)
		)
		(min_thickness 0.25)
		(keepout
			(tracks not_allowed)
			(vias allowed)
			(pads allowed)
			(copperpour not_allowed)
			(footprints allowed)
		)
		(placement
			(enabled no)
			(sheetname "")
		)
		(fill yes
			(thermal_gap 0.5)
			(thermal_bridge_width 0.5)
			(island_removal_mode 0)
		)
		(polygon
			(pts
				(arc
					(start 147.53844 -389.585962)
					(mid 147.650689 -389.721409)
					(end 147.81911 -389.772144)
				)
				(arc
					(start 147.81911 -389.772144)
					(mid 148.034636 -389.68287)
					(end 148.12391 -389.467344)
				)
				(arc
					(start 148.12391 -389.467344)
					(mid 148.114076 -389.390291)
					(end 148.085048 -389.318246)
				)
				(arc
					(start 147.70608 -388.671562)
					(mid 147.287567 -388.499187)
					(end 147.158964 -388.933182)
				)
			)
		)
	)
	(zone
		(layers "In1.Cu" "In3.Cu")
		(hatch none 0.5)
		(connect_pads
			(clearance 0)
		)
		(min_thickness 0.25)
		(keepout
			(tracks not_allowed)
			(vias allowed)
			(pads allowed)
			(copperpour not_allowed)
			(footprints allowed)
		)
		(placement
			(enabled no)
			(sheetname "")
		)
		(fill yes
			(thermal_gap 0.5)
			(thermal_bridge_width 0.5)
			(island_removal_mode 0)
		)
		(polygon
			(pts
				(arc
					(start 417.938458 -397.967962)
					(mid 418.050707 -398.103409)
					(end 418.219128 -398.154144)
				)
				(arc
					(start 418.219128 -398.154144)
					(mid 418.434654 -398.06487)
					(end 418.523928 -397.849344)
				)
				(arc
					(start 418.523928 -397.849344)
					(mid 418.514094 -397.772291)
					(end 418.485066 -397.700246)
				)
				(arc
					(start 418.106098 -397.053562)
					(mid 417.687585 -396.881187)
					(end 417.558982 -397.315182)
				)
			)
		)
	)
	(zone
		(layers "In1.Cu" "In3.Cu")
		(hatch none 0.5)
		(connect_pads
			(clearance 0)
		)
		(min_thickness 0.25)
		(keepout
			(tracks not_allowed)
			(vias allowed)
			(pads allowed)
			(copperpour not_allowed)
			(footprints allowed)
		)
		(placement
			(enabled no)
			(sheetname "")
		)
		(fill yes
			(thermal_gap 0.5)
			(thermal_bridge_width 0.5)
			(island_removal_mode 0)
		)
		(polygon
			(pts
				(arc
					(start 305.110388 -397.967962)
					(mid 305.222637 -398.103409)
					(end 305.391058 -398.154144)
				)
				(arc
					(start 305.391058 -398.154144)
					(mid 305.606584 -398.06487)
					(end 305.695858 -397.849344)
				)
				(arc
					(start 305.695858 -397.849344)
					(mid 305.686024 -397.772291)
					(end 305.656996 -397.700246)
				)
				(arc
					(start 305.278028 -397.053562)
					(mid 304.859515 -396.881187)
					(end 304.730912 -397.315182)
				)
			)
		)
	)
	(zone
		(layers "In1.Cu" "In3.Cu")
		(hatch none 0.5)
		(connect_pads
			(clearance 0)
		)
		(min_thickness 0.25)
		(keepout
			(tracks not_allowed)
			(vias allowed)
			(pads allowed)
			(copperpour not_allowed)
			(footprints allowed)
		)
		(placement
			(enabled no)
			(sheetname "")
		)
		(fill yes
			(thermal_gap 0.5)
			(thermal_bridge_width 0.5)
			(island_removal_mode 0)
		)
		(polygon
			(pts
				(arc
					(start 321.910456 -397.967962)
					(mid 322.022705 -398.103409)
					(end 322.191126 -398.154144)
				)
				(arc
					(start 322.191126 -398.154144)
					(mid 322.406652 -398.06487)
					(end 322.495926 -397.849344)
				)
				(arc
					(start 322.495926 -397.849344)
					(mid 322.486092 -397.772291)
					(end 322.457064 -397.700246)
				)
				(arc
					(start 322.078096 -397.053562)
					(mid 321.659583 -396.881187)
					(end 321.53098 -397.315182)
				)
			)
		)
	)
	(zone
		(layers "In1.Cu" "In3.Cu")
		(hatch none 0.5)
		(connect_pads
			(clearance 0)
		)
		(min_thickness 0.25)
		(keepout
			(tracks not_allowed)
			(vias allowed)
			(pads allowed)
			(copperpour not_allowed)
			(footprints allowed)
		)
		(placement
			(enabled no)
			(sheetname "")
		)
		(fill yes
			(thermal_gap 0.5)
			(thermal_bridge_width 0.5)
			(island_removal_mode 0)
		)
		(polygon
			(pts
				(arc
					(start 308.71033 -397.967962)
					(mid 308.822579 -398.103409)
					(end 308.991 -398.154144)
				)
				(arc
					(start 308.991 -398.154144)
					(mid 309.206526 -398.06487)
					(end 309.2958 -397.849344)
				)
				(arc
					(start 309.2958 -397.849344)
					(mid 309.285966 -397.772291)
					(end 309.256938 -397.700246)
				)
				(arc
					(start 308.87797 -397.053562)
					(mid 308.459457 -396.881187)
					(end 308.330854 -397.315182)
				)
			)
		)
	)
	(zone
		(layers "In1.Cu" "In3.Cu")
		(hatch none 0.5)
		(connect_pads
			(clearance 0)
		)
		(min_thickness 0.25)
		(keepout
			(tracks not_allowed)
			(vias allowed)
			(pads allowed)
			(copperpour not_allowed)
			(footprints allowed)
		)
		(placement
			(enabled no)
			(sheetname "")
		)
		(fill yes
			(thermal_gap 0.5)
			(thermal_bridge_width 0.5)
			(island_removal_mode 0)
		)
		(polygon
			(pts
				(arc
					(start 319.51041 -397.967962)
					(mid 319.622659 -398.103409)
					(end 319.79108 -398.154144)
				)
				(arc
					(start 319.79108 -398.154144)
					(mid 320.006606 -398.06487)
					(end 320.09588 -397.849344)
				)
				(arc
					(start 320.09588 -397.849344)
					(mid 320.086046 -397.772291)
					(end 320.057018 -397.700246)
				)
				(arc
					(start 319.67805 -397.053562)
					(mid 319.259537 -396.881187)
					(end 319.130934 -397.315182)
				)
			)
		)
	)
	(zone
		(layers "In1.Cu" "In3.Cu")
		(hatch none 0.5)
		(connect_pads
			(clearance 0)
		)
		(min_thickness 0.25)
		(keepout
			(tracks not_allowed)
			(vias allowed)
			(pads allowed)
			(copperpour not_allowed)
			(footprints allowed)
		)
		(placement
			(enabled no)
			(sheetname "")
		)
		(fill yes
			(thermal_gap 0.5)
			(thermal_bridge_width 0.5)
			(island_removal_mode 0)
		)
		(polygon
			(pts
				(arc
					(start 309.91048 -397.967962)
					(mid 310.022729 -398.103409)
					(end 310.19115 -398.154144)
				)
				(arc
					(start 310.19115 -398.154144)
					(mid 310.406676 -398.06487)
					(end 310.49595 -397.849344)
				)
				(arc
					(start 310.49595 -397.849344)
					(mid 310.486116 -397.772291)
					(end 310.457088 -397.700246)
				)
				(arc
					(start 310.07812 -397.053562)
					(mid 309.659607 -396.881187)
					(end 309.531004 -397.315182)
				)
			)
		)
	)
	(zone
		(layers "In1.Cu" "In3.Cu")
		(hatch none 0.5)
		(connect_pads
			(clearance 0)
		)
		(min_thickness 0.25)
		(keepout
			(tracks not_allowed)
			(vias allowed)
			(pads allowed)
			(copperpour not_allowed)
			(footprints allowed)
		)
		(placement
			(enabled no)
			(sheetname "")
		)
		(fill yes
			(thermal_gap 0.5)
			(thermal_bridge_width 0.5)
			(island_removal_mode 0)
		)
		(polygon
			(pts
				(arc
					(start 420.338504 -397.967962)
					(mid 420.450753 -398.103409)
					(end 420.619174 -398.154144)
				)
				(arc
					(start 420.619174 -398.154144)
					(mid 420.8347 -398.06487)
					(end 420.923974 -397.849344)
				)
				(arc
					(start 420.923974 -397.849344)
					(mid 420.91414 -397.772291)
					(end 420.885112 -397.700246)
				)
				(arc
					(start 420.506144 -397.053562)
					(mid 420.087631 -396.881187)
					(end 419.959028 -397.315182)
				)
			)
		)
	)
	(zone
		(layers "In1.Cu" "In3.Cu")
		(hatch none 0.5)
		(connect_pads
			(clearance 0)
		)
		(min_thickness 0.25)
		(keepout
			(tracks not_allowed)
			(vias allowed)
			(pads allowed)
			(copperpour not_allowed)
			(footprints allowed)
		)
		(placement
			(enabled no)
			(sheetname "")
		)
		(fill yes
			(thermal_gap 0.5)
			(thermal_bridge_width 0.5)
			(island_removal_mode 0)
		)
		(polygon
			(pts
				(arc
					(start 152.338278 -389.585962)
					(mid 152.450527 -389.721409)
					(end 152.618948 -389.772144)
				)
				(arc
					(start 152.618948 -389.772144)
					(mid 152.834474 -389.68287)
					(end 152.923748 -389.467344)
				)
				(arc
					(start 152.923748 -389.467344)
					(mid 152.913914 -389.390291)
					(end 152.884886 -389.318246)
				)
				(arc
					(start 152.505918 -388.671562)
					(mid 152.087405 -388.499187)
					(end 151.958802 -388.933182)
				)
			)
		)
	)
	(zone
		(layers "In1.Cu" "In3.Cu")
		(hatch none 0.5)
		(connect_pads
			(clearance 0)
		)
		(min_thickness 0.25)
		(keepout
			(tracks not_allowed)
			(vias allowed)
			(pads allowed)
			(copperpour not_allowed)
			(footprints allowed)
		)
		(placement
			(enabled no)
			(sheetname "")
		)
		(fill yes
			(thermal_gap 0.5)
			(thermal_bridge_width 0.5)
			(island_removal_mode 0)
		)
		(polygon
			(pts
				(arc
					(start 403.538436 -397.967962)
					(mid 403.650685 -398.103409)
					(end 403.819106 -398.154144)
				)
				(arc
					(start 403.819106 -398.154144)
					(mid 404.034632 -398.06487)
					(end 404.123906 -397.849344)
				)
				(arc
					(start 404.123906 -397.849344)
					(mid 404.114072 -397.772291)
					(end 404.085044 -397.700246)
				)
				(arc
					(start 403.706076 -397.053562)
					(mid 403.287563 -396.881187)
					(end 403.15896 -397.315182)
				)
			)
		)
	)
	(zone
		(layers "In1.Cu" "In3.Cu")
		(hatch none 0.5)
		(connect_pads
			(clearance 0)
		)
		(min_thickness 0.25)
		(keepout
			(tracks not_allowed)
			(vias allowed)
			(pads allowed)
			(copperpour not_allowed)
			(footprints allowed)
		)
		(placement
			(enabled no)
			(sheetname "")
		)
		(fill yes
			(thermal_gap 0.5)
			(thermal_bridge_width 0.5)
			(island_removal_mode 0)
		)
		(polygon
			(pts
				(arc
					(start 410.73832 -397.967962)
					(mid 410.850569 -398.103409)
					(end 411.01899 -398.154144)
				)
				(arc
					(start 411.01899 -398.154144)
					(mid 411.234516 -398.06487)
					(end 411.32379 -397.849344)
				)
				(arc
					(start 411.32379 -397.849344)
					(mid 411.313956 -397.772291)
					(end 411.284928 -397.700246)
				)
				(arc
					(start 410.90596 -397.053562)
					(mid 410.487447 -396.881187)
					(end 410.358844 -397.315182)
				)
			)
		)
	)
	(zone
		(layers "In1.Cu" "In3.Cu")
		(hatch none 0.5)
		(connect_pads
			(clearance 0)
		)
		(min_thickness 0.25)
		(keepout
			(tracks not_allowed)
			(vias allowed)
			(pads allowed)
			(copperpour not_allowed)
			(footprints allowed)
		)
		(placement
			(enabled no)
			(sheetname "")
		)
		(fill yes
			(thermal_gap 0.5)
			(thermal_bridge_width 0.5)
			(island_removal_mode 0)
		)
		(polygon
			(pts
				(arc
					(start 405.938482 -397.967962)
					(mid 406.050731 -398.103409)
					(end 406.219152 -398.154144)
				)
				(arc
					(start 406.219152 -398.154144)
					(mid 406.434678 -398.06487)
					(end 406.523952 -397.849344)
				)
				(arc
					(start 406.523952 -397.849344)
					(mid 406.514118 -397.772291)
					(end 406.48509 -397.700246)
				)
				(arc
					(start 406.106122 -397.053562)
					(mid 405.687609 -396.881187)
					(end 405.559006 -397.315182)
				)
			)
		)
	)
	(zone
		(layers "In1.Cu" "In3.Cu")
		(hatch none 0.5)
		(connect_pads
			(clearance 0)
		)
		(min_thickness 0.25)
		(keepout
			(tracks not_allowed)
			(vias allowed)
			(pads allowed)
			(copperpour not_allowed)
			(footprints allowed)
		)
		(placement
			(enabled no)
			(sheetname "")
		)
		(fill yes
			(thermal_gap 0.5)
			(thermal_bridge_width 0.5)
			(island_removal_mode 0)
		)
		(polygon
			(pts
				(arc
					(start 314.710318 -397.967962)
					(mid 314.822567 -398.103409)
					(end 314.990988 -398.154144)
				)
				(arc
					(start 314.990988 -398.154144)
					(mid 315.206514 -398.06487)
					(end 315.295788 -397.849344)
				)
				(arc
					(start 315.295788 -397.849344)
					(mid 315.285954 -397.772291)
					(end 315.256926 -397.700246)
				)
				(arc
					(start 314.877958 -397.053562)
					(mid 314.459445 -396.881187)
					(end 314.330842 -397.315182)
				)
			)
		)
	)
	(zone
		(layers "In1.Cu" "In3.Cu")
		(hatch none 0.5)
		(connect_pads
			(clearance 0)
		)
		(min_thickness 0.25)
		(keepout
			(tracks not_allowed)
			(vias allowed)
			(pads allowed)
			(copperpour not_allowed)
			(footprints allowed)
		)
		(placement
			(enabled no)
			(sheetname "")
		)
		(fill yes
			(thermal_gap 0.5)
			(thermal_bridge_width 0.5)
			(island_removal_mode 0)
		)
		(polygon
			(pts
				(arc
					(start 413.138366 -397.967962)
					(mid 413.250615 -398.103409)
					(end 413.419036 -398.154144)
				)
				(arc
					(start 413.419036 -398.154144)
					(mid 413.634562 -398.06487)
					(end 413.723836 -397.849344)
				)
				(arc
					(start 413.723836 -397.849344)
					(mid 413.714002 -397.772291)
					(end 413.684974 -397.700246)
				)
				(arc
					(start 413.306006 -397.053562)
					(mid 412.887493 -396.881187)
					(end 412.75889 -397.315182)
				)
			)
		)
	)
	(zone
		(layers "In1.Cu" "In3.Cu")
		(hatch none 0.5)
		(connect_pads
			(clearance 0)
		)
		(min_thickness 0.25)
		(keepout
			(tracks not_allowed)
			(vias allowed)
			(pads allowed)
			(copperpour not_allowed)
			(footprints allowed)
		)
		(placement
			(enabled no)
			(sheetname "")
		)
		(fill yes
			(thermal_gap 0.5)
			(thermal_bridge_width 0.5)
			(island_removal_mode 0)
		)
		(polygon
			(pts
				(arc
					(start 161.938462 -389.585962)
					(mid 162.050711 -389.721409)
					(end 162.219132 -389.772144)
				)
				(arc
					(start 162.219132 -389.772144)
					(mid 162.434658 -389.68287)
					(end 162.523932 -389.467344)
				)
				(arc
					(start 162.523932 -389.467344)
					(mid 162.514098 -389.390291)
					(end 162.48507 -389.318246)
				)
				(arc
					(start 162.106102 -388.671562)
					(mid 161.687589 -388.499187)
					(end 161.558986 -388.933182)
				)
			)
		)
	)
	(zone
		(layers "In1.Cu" "In3.Cu")
		(hatch none 0.5)
		(connect_pads
			(clearance 0)
		)
		(min_thickness 0.25)
		(keepout
			(tracks not_allowed)
			(vias allowed)
			(pads allowed)
			(copperpour not_allowed)
			(footprints allowed)
		)
		(placement
			(enabled no)
			(sheetname "")
		)
		(fill yes
			(thermal_gap 0.5)
			(thermal_bridge_width 0.5)
			(island_removal_mode 0)
		)
		(polygon
			(pts
				(arc
					(start 153.538428 -389.585962)
					(mid 153.650677 -389.721409)
					(end 153.819098 -389.772144)
				)
				(arc
					(start 153.819098 -389.772144)
					(mid 154.034624 -389.68287)
					(end 154.123898 -389.467344)
				)
				(arc
					(start 154.123898 -389.467344)
					(mid 154.114064 -389.390291)
					(end 154.085036 -389.318246)
				)
				(arc
					(start 153.706068 -388.671562)
					(mid 153.287555 -388.499187)
					(end 153.158952 -388.933182)
				)
			)
		)
	)
	(zone
		(layers "In1.Cu" "In3.Cu")
		(hatch none 0.5)
		(connect_pads
			(clearance 0)
		)
		(min_thickness 0.25)
		(keepout
			(tracks not_allowed)
			(vias allowed)
			(pads allowed)
			(copperpour not_allowed)
			(footprints allowed)
		)
		(placement
			(enabled no)
			(sheetname "")
		)
		(fill yes
			(thermal_gap 0.5)
			(thermal_bridge_width 0.5)
			(island_removal_mode 0)
		)
		(polygon
			(pts
				(arc
					(start 154.738324 -389.585962)
					(mid 154.850573 -389.721409)
					(end 155.018994 -389.772144)
				)
				(arc
					(start 155.018994 -389.772144)
					(mid 155.23452 -389.68287)
					(end 155.323794 -389.467344)
				)
				(arc
					(start 155.323794 -389.467344)
					(mid 155.31396 -389.390291)
					(end 155.284932 -389.318246)
				)
				(arc
					(start 154.905964 -388.671562)
					(mid 154.487451 -388.499187)
					(end 154.358848 -388.933182)
				)
			)
		)
	)
	(zone
		(layers "In1.Cu" "In3.Cu")
		(hatch none 0.5)
		(connect_pads
			(clearance 0)
		)
		(min_thickness 0.25)
		(keepout
			(tracks not_allowed)
			(vias allowed)
			(pads allowed)
			(copperpour not_allowed)
			(footprints allowed)
		)
		(placement
			(enabled no)
			(sheetname "")
		)
		(fill yes
			(thermal_gap 0.5)
			(thermal_bridge_width 0.5)
			(island_removal_mode 0)
		)
		(polygon
			(pts
				(arc
					(start 159.538416 -389.585962)
					(mid 159.650665 -389.721409)
					(end 159.819086 -389.772144)
				)
				(arc
					(start 159.819086 -389.772144)
					(mid 160.034612 -389.68287)
					(end 160.123886 -389.467344)
				)
				(arc
					(start 160.123886 -389.467344)
					(mid 160.114052 -389.390291)
					(end 160.085024 -389.318246)
				)
				(arc
					(start 159.706056 -388.671562)
					(mid 159.287543 -388.499187)
					(end 159.15894 -388.933182)
				)
			)
		)
	)
	(zone
		(layers "In1.Cu" "In3.Cu")
		(hatch none 0.5)
		(connect_pads
			(clearance 0)
		)
		(min_thickness 0.25)
		(keepout
			(tracks not_allowed)
			(vias allowed)
			(pads allowed)
			(copperpour not_allowed)
			(footprints allowed)
		)
		(placement
			(enabled no)
			(sheetname "")
		)
		(fill yes
			(thermal_gap 0.5)
			(thermal_bridge_width 0.5)
			(island_removal_mode 0)
		)
		(polygon
			(pts
				(arc
					(start 303.910492 -397.967962)
					(mid 304.022741 -398.103409)
					(end 304.191162 -398.154144)
				)
				(arc
					(start 304.191162 -398.154144)
					(mid 304.406688 -398.06487)
					(end 304.495962 -397.849344)
				)
				(arc
					(start 304.495962 -397.849344)
					(mid 304.486128 -397.772291)
					(end 304.4571 -397.700246)
				)
				(arc
					(start 304.078132 -397.053562)
					(mid 303.659619 -396.881187)
					(end 303.531016 -397.315182)
				)
			)
		)
	)
	(zone
		(layers "In1.Cu" "In3.Cu")
		(hatch none 0.5)
		(connect_pads
			(clearance 0)
		)
		(min_thickness 0.25)
		(keepout
			(tracks not_allowed)
			(vias allowed)
			(pads allowed)
			(copperpour not_allowed)
			(footprints allowed)
		)
		(placement
			(enabled no)
			(sheetname "")
		)
		(fill yes
			(thermal_gap 0.5)
			(thermal_bridge_width 0.5)
			(island_removal_mode 0)
		)
		(polygon
			(pts
				(arc
					(start 312.310526 -397.967962)
					(mid 312.422775 -398.103409)
					(end 312.591196 -398.154144)
				)
				(arc
					(start 312.591196 -398.154144)
					(mid 312.806722 -398.06487)
					(end 312.895996 -397.849344)
				)
				(arc
					(start 312.895996 -397.849344)
					(mid 312.886162 -397.772291)
					(end 312.857134 -397.700246)
				)
				(arc
					(start 312.478166 -397.053562)
					(mid 312.059653 -396.881187)
					(end 311.93105 -397.315182)
				)
			)
		)
	)
	(zone
		(layers "In1.Cu" "In3.Cu")
		(hatch none 0.5)
		(connect_pads
			(clearance 0)
		)
		(min_thickness 0.25)
		(keepout
			(tracks not_allowed)
			(vias allowed)
			(pads allowed)
			(copperpour not_allowed)
			(footprints allowed)
		)
		(placement
			(enabled no)
			(sheetname "")
		)
		(fill yes
			(thermal_gap 0.5)
			(thermal_bridge_width 0.5)
			(island_removal_mode 0)
		)
		(polygon
			(pts
				(arc
					(start 408.338274 -397.967962)
					(mid 408.450523 -398.103409)
					(end 408.618944 -398.154144)
				)
				(arc
					(start 408.618944 -398.154144)
					(mid 408.83447 -398.06487)
					(end 408.923744 -397.849344)
				)
				(arc
					(start 408.923744 -397.849344)
					(mid 408.91391 -397.772291)
					(end 408.884882 -397.700246)
				)
				(arc
					(start 408.505914 -397.053562)
					(mid 408.087401 -396.881187)
					(end 407.958798 -397.315182)
				)
			)
		)
	)
	(zone
		(layers "In1.Cu" "In3.Cu")
		(hatch none 0.5)
		(connect_pads
			(clearance 0)
		)
		(min_thickness 0.25)
		(keepout
			(tracks not_allowed)
			(vias allowed)
			(pads allowed)
			(copperpour not_allowed)
			(footprints allowed)
		)
		(placement
			(enabled no)
			(sheetname "")
		)
		(fill yes
			(thermal_gap 0.5)
			(thermal_bridge_width 0.5)
			(island_removal_mode 0)
		)
		(polygon
			(pts
				(arc
					(start 409.538424 -397.967962)
					(mid 409.650673 -398.103409)
					(end 409.819094 -398.154144)
				)
				(arc
					(start 409.819094 -398.154144)
					(mid 410.03462 -398.06487)
					(end 410.123894 -397.849344)
				)
				(arc
					(start 410.123894 -397.849344)
					(mid 410.11406 -397.772291)
					(end 410.085032 -397.700246)
				)
				(arc
					(start 409.706064 -397.053562)
					(mid 409.287551 -396.881187)
					(end 409.158948 -397.315182)
				)
			)
		)
	)
	(zone
		(layers "In1.Cu" "In3.Cu")
		(hatch none 0.5)
		(connect_pads
			(clearance 0)
		)
		(min_thickness 0.25)
		(keepout
			(tracks not_allowed)
			(vias allowed)
			(pads allowed)
			(copperpour not_allowed)
			(footprints allowed)
		)
		(placement
			(enabled no)
			(sheetname "")
		)
		(fill yes
			(thermal_gap 0.5)
			(thermal_bridge_width 0.5)
			(island_removal_mode 0)
		)
		(polygon
			(pts
				(arc
					(start 311.110376 -397.967962)
					(mid 311.222625 -398.103409)
					(end 311.391046 -398.154144)
				)
				(arc
					(start 311.391046 -398.154144)
					(mid 311.606572 -398.06487)
					(end 311.695846 -397.849344)
				)
				(arc
					(start 311.695846 -397.849344)
					(mid 311.686012 -397.772291)
					(end 311.656984 -397.700246)
				)
				(arc
					(start 311.278016 -397.053562)
					(mid 310.859503 -396.881187)
					(end 310.7309 -397.315182)
				)
			)
		)
	)
	(zone
		(layers "In1.Cu" "In3.Cu")
		(hatch none 0.5)
		(connect_pads
			(clearance 0)
		)
		(min_thickness 0.25)
		(keepout
			(tracks not_allowed)
			(vias allowed)
			(pads allowed)
			(copperpour not_allowed)
			(footprints allowed)
		)
		(placement
			(enabled no)
			(sheetname "")
		)
		(fill yes
			(thermal_gap 0.5)
			(thermal_bridge_width 0.5)
			(island_removal_mode 0)
		)
		(polygon
			(pts
				(arc
					(start 317.110364 -397.967962)
					(mid 317.222613 -398.103409)
					(end 317.391034 -398.154144)
				)
				(arc
					(start 317.391034 -398.154144)
					(mid 317.60656 -398.06487)
					(end 317.695834 -397.849344)
				)
				(arc
					(start 317.695834 -397.849344)
					(mid 317.686 -397.772291)
					(end 317.656972 -397.700246)
				)
				(arc
					(start 317.278004 -397.053562)
					(mid 316.859491 -396.881187)
					(end 316.730888 -397.315182)
				)
			)
		)
	)
	(zone
		(layers "In1.Cu" "In3.Cu")
		(hatch none 0.5)
		(connect_pads
			(clearance 0)
		)
		(min_thickness 0.25)
		(keepout
			(tracks not_allowed)
			(vias allowed)
			(pads allowed)
			(copperpour not_allowed)
			(footprints allowed)
		)
		(placement
			(enabled no)
			(sheetname "")
		)
		(fill yes
			(thermal_gap 0.5)
			(thermal_bridge_width 0.5)
			(island_removal_mode 0)
		)
		(polygon
			(pts
				(arc
					(start 315.910468 -397.967962)
					(mid 316.022717 -398.103409)
					(end 316.191138 -398.154144)
				)
				(arc
					(start 316.191138 -398.154144)
					(mid 316.406664 -398.06487)
					(end 316.495938 -397.849344)
				)
				(arc
					(start 316.495938 -397.849344)
					(mid 316.486104 -397.772291)
					(end 316.457076 -397.700246)
				)
				(arc
					(start 316.078108 -397.053562)
					(mid 315.659595 -396.881187)
					(end 315.530992 -397.315182)
				)
			)
		)
	)
	(zone
		(layers "In1.Cu" "In3.Cu")
		(hatch none 0.5)
		(connect_pads
			(clearance 0)
		)
		(min_thickness 0.25)
		(keepout
			(tracks not_allowed)
			(vias allowed)
			(pads allowed)
			(copperpour not_allowed)
			(footprints allowed)
		)
		(placement
			(enabled no)
			(sheetname "")
		)
		(fill yes
			(thermal_gap 0.5)
			(thermal_bridge_width 0.5)
			(island_removal_mode 0)
		)
		(polygon
			(pts
				(arc
					(start 163.138358 -389.585962)
					(mid 163.250607 -389.721409)
					(end 163.419028 -389.772144)
				)
				(arc
					(start 163.419028 -389.772144)
					(mid 163.634554 -389.68287)
					(end 163.723828 -389.467344)
				)
				(arc
					(start 163.723828 -389.467344)
					(mid 163.713994 -389.390291)
					(end 163.684966 -389.318246)
				)
				(arc
					(start 163.305998 -388.671562)
					(mid 162.887485 -388.499187)
					(end 162.758882 -388.933182)
				)
			)
		)
	)
	(zone
		(layers "In1.Cu" "In3.Cu")
		(hatch none 0.5)
		(connect_pads
			(clearance 0)
		)
		(min_thickness 0.25)
		(keepout
			(tracks not_allowed)
			(vias allowed)
			(pads allowed)
			(copperpour not_allowed)
			(footprints allowed)
		)
		(placement
			(enabled no)
			(sheetname "")
		)
		(fill yes
			(thermal_gap 0.5)
			(thermal_bridge_width 0.5)
			(island_removal_mode 0)
		)
		(polygon
			(pts
				(arc
					(start 155.938474 -389.585962)
					(mid 156.050723 -389.721409)
					(end 156.219144 -389.772144)
				)
				(arc
					(start 156.219144 -389.772144)
					(mid 156.43467 -389.68287)
					(end 156.523944 -389.467344)
				)
				(arc
					(start 156.523944 -389.467344)
					(mid 156.51411 -389.390291)
					(end 156.485082 -389.318246)
				)
				(arc
					(start 156.106114 -388.671562)
					(mid 155.687601 -388.499187)
					(end 155.558998 -388.933182)
				)
			)
		)
	)
	(zone
		(layers "In1.Cu" "In3.Cu")
		(hatch none 0.5)
		(connect_pads
			(clearance 0)
		)
		(min_thickness 0.25)
		(keepout
			(tracks not_allowed)
			(vias allowed)
			(pads allowed)
			(copperpour not_allowed)
			(footprints allowed)
		)
		(placement
			(enabled no)
			(sheetname "")
		)
		(fill yes
			(thermal_gap 0.5)
			(thermal_bridge_width 0.5)
			(island_removal_mode 0)
		)
		(polygon
			(pts
				(arc
					(start 164.338508 -389.585962)
					(mid 164.450757 -389.721409)
					(end 164.619178 -389.772144)
				)
				(arc
					(start 164.619178 -389.772144)
					(mid 164.834704 -389.68287)
					(end 164.923978 -389.467344)
				)
				(arc
					(start 164.923978 -389.467344)
					(mid 164.914144 -389.390291)
					(end 164.885116 -389.318246)
				)
				(arc
					(start 164.506148 -388.671562)
					(mid 164.087635 -388.499187)
					(end 163.959032 -388.933182)
				)
			)
		)
	)
	(zone
		(layers "In1.Cu" "In3.Cu")
		(hatch none 0.5)
		(connect_pads
			(clearance 0)
		)
		(min_thickness 0.25)
		(keepout
			(tracks not_allowed)
			(vias allowed)
			(pads allowed)
			(copperpour not_allowed)
			(footprints allowed)
		)
		(placement
			(enabled no)
			(sheetname "")
		)
		(fill yes
			(thermal_gap 0.5)
			(thermal_bridge_width 0.5)
			(island_removal_mode 0)
		)
		(polygon
			(pts
				(arc
					(start 414.338262 -397.967962)
					(mid 414.450511 -398.103409)
					(end 414.618932 -398.154144)
				)
				(arc
					(start 414.618932 -398.154144)
					(mid 414.834458 -398.06487)
					(end 414.923732 -397.849344)
				)
				(arc
					(start 414.923732 -397.849344)
					(mid 414.913898 -397.772291)
					(end 414.88487 -397.700246)
				)
				(arc
					(start 414.505902 -397.053562)
					(mid 414.087389 -396.881187)
					(end 413.958786 -397.315182)
				)
			)
		)
	)
	(zone
		(layers "In1.Cu" "In3.Cu")
		(hatch none 0.5)
		(connect_pads
			(clearance 0)
		)
		(min_thickness 0.25)
		(keepout
			(tracks not_allowed)
			(vias allowed)
			(pads allowed)
			(copperpour not_allowed)
			(footprints allowed)
		)
		(placement
			(enabled no)
			(sheetname "")
		)
		(fill yes
			(thermal_gap 0.5)
			(thermal_bridge_width 0.5)
			(island_removal_mode 0)
		)
		(polygon
			(pts
				(arc
					(start 149.938486 -389.585962)
					(mid 150.050735 -389.721409)
					(end 150.219156 -389.772144)
				)
				(arc
					(start 150.219156 -389.772144)
					(mid 150.434682 -389.68287)
					(end 150.523956 -389.467344)
				)
				(arc
					(start 150.523956 -389.467344)
					(mid 150.514122 -389.390291)
					(end 150.485094 -389.318246)
				)
				(arc
					(start 150.106126 -388.671562)
					(mid 149.687613 -388.499187)
					(end 149.55901 -388.933182)
				)
			)
		)
	)
	(zone
		(layers "In1.Cu" "In3.Cu")
		(hatch none 0.5)
		(connect_pads
			(clearance 0)
		)
		(min_thickness 0.25)
		(keepout
			(tracks not_allowed)
			(vias allowed)
			(pads allowed)
			(copperpour not_allowed)
			(footprints allowed)
		)
		(placement
			(enabled no)
			(sheetname "")
		)
		(fill yes
			(thermal_gap 0.5)
			(thermal_bridge_width 0.5)
			(island_removal_mode 0)
		)
		(polygon
			(pts
				(arc
					(start 158.338266 -389.585962)
					(mid 158.450515 -389.721409)
					(end 158.618936 -389.772144)
				)
				(arc
					(start 158.618936 -389.772144)
					(mid 158.834462 -389.68287)
					(end 158.923736 -389.467344)
				)
				(arc
					(start 158.923736 -389.467344)
					(mid 158.913902 -389.390291)
					(end 158.884874 -389.318246)
				)
				(arc
					(start 158.505906 -388.671562)
					(mid 158.087393 -388.499187)
					(end 157.95879 -388.933182)
				)
			)
		)
	)
	(zone
		(layers "In1.Cu" "In3.Cu")
		(hatch none 0.5)
		(connect_pads
			(clearance 0)
		)
		(min_thickness 0.25)
		(keepout
			(tracks not_allowed)
			(vias allowed)
			(pads allowed)
			(copperpour not_allowed)
			(footprints allowed)
		)
		(placement
			(enabled no)
			(sheetname "")
		)
		(fill yes
			(thermal_gap 0.5)
			(thermal_bridge_width 0.5)
			(island_removal_mode 0)
		)
		(polygon
			(pts
				(arc
					(start 306.310538 -397.967962)
					(mid 306.422787 -398.103409)
					(end 306.591208 -398.154144)
				)
				(arc
					(start 306.591208 -398.154144)
					(mid 306.806734 -398.06487)
					(end 306.896008 -397.849344)
				)
				(arc
					(start 306.896008 -397.849344)
					(mid 306.886174 -397.772291)
					(end 306.857146 -397.700246)
				)
				(arc
					(start 306.478178 -397.053562)
					(mid 306.059665 -396.881187)
					(end 305.931062 -397.315182)
				)
			)
		)
	)
	(zone
		(layers "In1.Cu" "In3.Cu")
		(hatch none 0.5)
		(connect_pads
			(clearance 0)
		)
		(min_thickness 0.25)
		(keepout
			(tracks not_allowed)
			(vias allowed)
			(pads allowed)
			(copperpour not_allowed)
			(footprints allowed)
		)
		(placement
			(enabled no)
			(sheetname "")
		)
		(fill yes
			(thermal_gap 0.5)
			(thermal_bridge_width 0.5)
			(island_removal_mode 0)
		)
		(polygon
			(pts
				(arc
					(start 165.538404 -389.585962)
					(mid 165.650653 -389.721409)
					(end 165.819074 -389.772144)
				)
				(arc
					(start 165.819074 -389.772144)
					(mid 166.0346 -389.68287)
					(end 166.123874 -389.467344)
				)
				(arc
					(start 166.123874 -389.467344)
					(mid 166.11404 -389.390291)
					(end 166.085012 -389.318246)
				)
				(arc
					(start 165.706044 -388.671562)
					(mid 165.287531 -388.499187)
					(end 165.158928 -388.933182)
				)
			)
		)
	)
	(zone
		(layers "In1.Cu" "In3.Cu" "In5.Cu" "In7.Cu" "In8.Cu" "In9.Cu")
		(hatch none 0.5)
		(connect_pads
			(clearance 0)
		)
		(min_thickness 0.25)
		(keepout
			(tracks not_allowed)
			(vias allowed)
			(pads allowed)
			(copperpour not_allowed)
			(footprints allowed)
		)
		(placement
			(enabled no)
			(sheetname "")
		)
		(fill yes
			(thermal_gap 0.5)
			(thermal_bridge_width 0.5)
			(island_removal_mode 0)
		)
		(polygon
			(pts
				(arc
					(start 129.41046 -389.585962)
					(mid 129.522709 -389.721409)
					(end 129.69113 -389.772144)
				)
				(arc
					(start 129.69113 -389.772144)
					(mid 129.906656 -389.68287)
					(end 129.99593 -389.467344)
				)
				(arc
					(start 129.99593 -389.467344)
					(mid 129.986096 -389.390291)
					(end 129.957068 -389.318246)
				)
				(arc
					(start 129.5781 -388.671562)
					(mid 129.159587 -388.499187)
					(end 129.030984 -388.933182)
				)
			)
		)
	)
	(zone
		(layers "In1.Cu" "In3.Cu" "In5.Cu" "In7.Cu" "In8.Cu" "In9.Cu")
		(hatch none 0.5)
		(connect_pads
			(clearance 0)
		)
		(min_thickness 0.25)
		(keepout
			(tracks not_allowed)
			(vias allowed)
			(pads allowed)
			(copperpour not_allowed)
			(footprints allowed)
		)
		(placement
			(enabled no)
			(sheetname "")
		)
		(fill yes
			(thermal_gap 0.5)
			(thermal_bridge_width 0.5)
			(island_removal_mode 0)
		)
		(polygon
			(pts
				(arc
					(start 118.610634 -389.585962)
					(mid 118.722883 -389.721409)
					(end 118.891304 -389.772144)
				)
				(arc
					(start 118.891304 -389.772144)
					(mid 119.10683 -389.68287)
					(end 119.196104 -389.467344)
				)
				(arc
					(start 119.196104 -389.467344)
					(mid 119.18627 -389.390291)
					(end 119.157242 -389.318246)
				)
				(arc
					(start 118.778274 -388.671562)
					(mid 118.359761 -388.499187)
					(end 118.231158 -388.933182)
				)
			)
		)
	)
	(zone
		(layers "In1.Cu" "In3.Cu" "In5.Cu" "In7.Cu" "In8.Cu" "In9.Cu")
		(hatch none 0.5)
		(connect_pads
			(clearance 0)
		)
		(min_thickness 0.25)
		(keepout
			(tracks not_allowed)
			(vias allowed)
			(pads allowed)
			(copperpour not_allowed)
			(footprints allowed)
		)
		(placement
			(enabled no)
			(sheetname "")
		)
		(fill yes
			(thermal_gap 0.5)
			(thermal_bridge_width 0.5)
			(island_removal_mode 0)
		)
		(polygon
			(pts
				(arc
					(start 116.210588 -389.585962)
					(mid 116.322837 -389.721409)
					(end 116.491258 -389.772144)
				)
				(arc
					(start 116.491258 -389.772144)
					(mid 116.706784 -389.68287)
					(end 116.796058 -389.467344)
				)
				(arc
					(start 116.796058 -389.467344)
					(mid 116.786224 -389.390291)
					(end 116.757196 -389.318246)
				)
				(arc
					(start 116.378228 -388.671562)
					(mid 115.959715 -388.499187)
					(end 115.831112 -388.933182)
				)
			)
		)
	)
	(zone
		(layers "In1.Cu" "In3.Cu" "In5.Cu" "In7.Cu" "In8.Cu" "In9.Cu")
		(hatch none 0.5)
		(connect_pads
			(clearance 0)
		)
		(min_thickness 0.25)
		(keepout
			(tracks not_allowed)
			(vias allowed)
			(pads allowed)
			(copperpour not_allowed)
			(footprints allowed)
		)
		(placement
			(enabled no)
			(sheetname "")
		)
		(fill yes
			(thermal_gap 0.5)
			(thermal_bridge_width 0.5)
			(island_removal_mode 0)
		)
		(polygon
			(pts
				(arc
					(start 121.01068 -389.585962)
					(mid 121.122929 -389.721409)
					(end 121.29135 -389.772144)
				)
				(arc
					(start 121.29135 -389.772144)
					(mid 121.506876 -389.68287)
					(end 121.59615 -389.467344)
				)
				(arc
					(start 121.59615 -389.467344)
					(mid 121.586316 -389.390291)
					(end 121.557288 -389.318246)
				)
				(arc
					(start 121.17832 -388.671562)
					(mid 120.759807 -388.499187)
					(end 120.631204 -388.933182)
				)
			)
		)
	)
	(zone
		(layers "In1.Cu" "In3.Cu" "In5.Cu" "In7.Cu" "In8.Cu" "In9.Cu")
		(hatch none 0.5)
		(connect_pads
			(clearance 0)
		)
		(min_thickness 0.25)
		(keepout
			(tracks not_allowed)
			(vias allowed)
			(pads allowed)
			(copperpour not_allowed)
			(footprints allowed)
		)
		(placement
			(enabled no)
			(sheetname "")
		)
		(fill yes
			(thermal_gap 0.5)
			(thermal_bridge_width 0.5)
			(island_removal_mode 0)
		)
		(polygon
			(pts
				(arc
					(start 49.110646 -389.585962)
					(mid 49.222895 -389.721409)
					(end 49.391316 -389.772144)
				)
				(arc
					(start 49.391316 -389.772144)
					(mid 49.606842 -389.68287)
					(end 49.696116 -389.467344)
				)
				(arc
					(start 49.696116 -389.467344)
					(mid 49.686282 -389.390291)
					(end 49.657254 -389.318246)
				)
				(arc
					(start 49.278286 -388.671562)
					(mid 48.859773 -388.499187)
					(end 48.73117 -388.933182)
				)
			)
		)
	)
	(zone
		(layers "In1.Cu" "In3.Cu" "In5.Cu" "In7.Cu" "In8.Cu" "In9.Cu")
		(hatch none 0.5)
		(connect_pads
			(clearance 0)
		)
		(min_thickness 0.25)
		(keepout
			(tracks not_allowed)
			(vias allowed)
			(pads allowed)
			(copperpour not_allowed)
			(footprints allowed)
		)
		(placement
			(enabled no)
			(sheetname "")
		)
		(fill yes
			(thermal_gap 0.5)
			(thermal_bridge_width 0.5)
			(island_removal_mode 0)
		)
		(polygon
			(pts
				(arc
					(start 389.010652 -397.967962)
					(mid 389.122901 -398.103409)
					(end 389.291322 -398.154144)
				)
				(arc
					(start 389.291322 -398.154144)
					(mid 389.506848 -398.06487)
					(end 389.596122 -397.849344)
				)
				(arc
					(start 389.596122 -397.849344)
					(mid 389.586288 -397.772291)
					(end 389.55726 -397.700246)
				)
				(arc
					(start 389.178292 -397.053562)
					(mid 388.759779 -396.881187)
					(end 388.631176 -397.315182)
				)
			)
		)
	)
	(zone
		(layers "In1.Cu" "In3.Cu" "In5.Cu" "In7.Cu" "In8.Cu" "In9.Cu")
		(hatch none 0.5)
		(connect_pads
			(clearance 0)
		)
		(min_thickness 0.25)
		(keepout
			(tracks not_allowed)
			(vias allowed)
			(pads allowed)
			(copperpour not_allowed)
			(footprints allowed)
		)
		(placement
			(enabled no)
			(sheetname "")
		)
		(fill yes
			(thermal_gap 0.5)
			(thermal_bridge_width 0.5)
			(island_removal_mode 0)
		)
		(polygon
			(pts
				(arc
					(start 57.51068 -389.585962)
					(mid 57.622929 -389.721409)
					(end 57.79135 -389.772144)
				)
				(arc
					(start 57.79135 -389.772144)
					(mid 58.006876 -389.68287)
					(end 58.09615 -389.467344)
				)
				(arc
					(start 58.09615 -389.467344)
					(mid 58.086316 -389.390291)
					(end 58.057288 -389.318246)
				)
				(arc
					(start 57.67832 -388.671562)
					(mid 57.259807 -388.499187)
					(end 57.131204 -388.933182)
				)
			)
		)
	)
	(zone
		(layers "In1.Cu" "In3.Cu" "In5.Cu" "In7.Cu" "In8.Cu" "In9.Cu")
		(hatch none 0.5)
		(connect_pads
			(clearance 0)
		)
		(min_thickness 0.25)
		(keepout
			(tracks not_allowed)
			(vias allowed)
			(pads allowed)
			(copperpour not_allowed)
			(footprints allowed)
		)
		(placement
			(enabled no)
			(sheetname "")
		)
		(fill yes
			(thermal_gap 0.5)
			(thermal_bridge_width 0.5)
			(island_removal_mode 0)
		)
		(polygon
			(pts
				(arc
					(start 50.310542 -389.585962)
					(mid 50.422791 -389.721409)
					(end 50.591212 -389.772144)
				)
				(arc
					(start 50.591212 -389.772144)
					(mid 50.806738 -389.68287)
					(end 50.896012 -389.467344)
				)
				(arc
					(start 50.896012 -389.467344)
					(mid 50.886178 -389.390291)
					(end 50.85715 -389.318246)
				)
				(arc
					(start 50.478182 -388.671562)
					(mid 50.059669 -388.499187)
					(end 49.931066 -388.933182)
				)
			)
		)
	)
	(zone
		(layers "In1.Cu" "In3.Cu" "In5.Cu" "In7.Cu" "In8.Cu" "In9.Cu")
		(hatch none 0.5)
		(connect_pads
			(clearance 0)
		)
		(min_thickness 0.25)
		(keepout
			(tracks not_allowed)
			(vias allowed)
			(pads allowed)
			(copperpour not_allowed)
			(footprints allowed)
		)
		(placement
			(enabled no)
			(sheetname "")
		)
		(fill yes
			(thermal_gap 0.5)
			(thermal_bridge_width 0.5)
			(island_removal_mode 0)
		)
		(polygon
			(pts
				(arc
					(start 53.910738 -389.585962)
					(mid 54.022987 -389.721409)
					(end 54.191408 -389.772144)
				)
				(arc
					(start 54.191408 -389.772144)
					(mid 54.406934 -389.68287)
					(end 54.496208 -389.467344)
				)
				(arc
					(start 54.496208 -389.467344)
					(mid 54.486374 -389.390291)
					(end 54.457346 -389.318246)
				)
				(arc
					(start 54.078378 -388.671562)
					(mid 53.659865 -388.499187)
					(end 53.531262 -388.933182)
				)
			)
		)
	)
	(zone
		(layers "In1.Cu" "In3.Cu" "In5.Cu" "In7.Cu" "In8.Cu" "In9.Cu")
		(hatch none 0.5)
		(connect_pads
			(clearance 0)
		)
		(min_thickness 0.25)
		(keepout
			(tracks not_allowed)
			(vias allowed)
			(pads allowed)
			(copperpour not_allowed)
			(footprints allowed)
		)
		(placement
			(enabled no)
			(sheetname "")
		)
		(fill yes
			(thermal_gap 0.5)
			(thermal_bridge_width 0.5)
			(island_removal_mode 0)
		)
		(polygon
			(pts
				(arc
					(start 124.610622 -389.585962)
					(mid 124.722871 -389.721409)
					(end 124.891292 -389.772144)
				)
				(arc
					(start 124.891292 -389.772144)
					(mid 125.106818 -389.68287)
					(end 125.196092 -389.467344)
				)
				(arc
					(start 125.196092 -389.467344)
					(mid 125.186258 -389.390291)
					(end 125.15723 -389.318246)
				)
				(arc
					(start 124.778262 -388.671562)
					(mid 124.359749 -388.499187)
					(end 124.231146 -388.933182)
				)
			)
		)
	)
	(zone
		(layers "In1.Cu" "In3.Cu" "In5.Cu" "In7.Cu" "In8.Cu" "In9.Cu")
		(hatch none 0.5)
		(connect_pads
			(clearance 0)
		)
		(min_thickness 0.25)
		(keepout
			(tracks not_allowed)
			(vias allowed)
			(pads allowed)
			(copperpour not_allowed)
			(footprints allowed)
		)
		(placement
			(enabled no)
			(sheetname "")
		)
		(fill yes
			(thermal_gap 0.5)
			(thermal_bridge_width 0.5)
			(island_removal_mode 0)
		)
		(polygon
			(pts
				(arc
					(start 122.210576 -389.585962)
					(mid 122.322825 -389.721409)
					(end 122.491246 -389.772144)
				)
				(arc
					(start 122.491246 -389.772144)
					(mid 122.706772 -389.68287)
					(end 122.796046 -389.467344)
				)
				(arc
					(start 122.796046 -389.467344)
					(mid 122.786212 -389.390291)
					(end 122.757184 -389.318246)
				)
				(arc
					(start 122.378216 -388.671562)
					(mid 121.959703 -388.499187)
					(end 121.8311 -388.933182)
				)
			)
		)
	)
	(zone
		(layers "In1.Cu" "In3.Cu" "In5.Cu" "In7.Cu" "In8.Cu" "In9.Cu")
		(hatch none 0.5)
		(connect_pads
			(clearance 0)
		)
		(min_thickness 0.25)
		(keepout
			(tracks not_allowed)
			(vias allowed)
			(pads allowed)
			(copperpour not_allowed)
			(footprints allowed)
		)
		(placement
			(enabled no)
			(sheetname "")
		)
		(fill yes
			(thermal_gap 0.5)
			(thermal_bridge_width 0.5)
			(island_removal_mode 0)
		)
		(polygon
			(pts
				(arc
					(start 375.810526 -397.967962)
					(mid 375.922775 -398.103409)
					(end 376.091196 -398.154144)
				)
				(arc
					(start 376.091196 -398.154144)
					(mid 376.306722 -398.06487)
					(end 376.395996 -397.849344)
				)
				(arc
					(start 376.395996 -397.849344)
					(mid 376.386162 -397.772291)
					(end 376.357134 -397.700246)
				)
				(arc
					(start 375.978166 -397.053562)
					(mid 375.559653 -396.881187)
					(end 375.43105 -397.315182)
				)
			)
		)
	)
	(zone
		(layers "In1.Cu" "In3.Cu" "In5.Cu" "In7.Cu" "In8.Cu" "In9.Cu")
		(hatch none 0.5)
		(connect_pads
			(clearance 0)
		)
		(min_thickness 0.25)
		(keepout
			(tracks not_allowed)
			(vias allowed)
			(pads allowed)
			(copperpour not_allowed)
			(footprints allowed)
		)
		(placement
			(enabled no)
			(sheetname "")
		)
		(fill yes
			(thermal_gap 0.5)
			(thermal_bridge_width 0.5)
			(island_removal_mode 0)
		)
		(polygon
			(pts
				(arc
					(start 338.838032 -397.967962)
					(mid 338.950281 -398.103409)
					(end 339.118702 -398.154144)
				)
				(arc
					(start 339.118702 -398.154144)
					(mid 339.334228 -398.06487)
					(end 339.423502 -397.849344)
				)
				(arc
					(start 339.423502 -397.849344)
					(mid 339.413668 -397.772291)
					(end 339.38464 -397.700246)
				)
				(arc
					(start 339.005672 -397.053562)
					(mid 338.587159 -396.881187)
					(end 338.458556 -397.315182)
				)
			)
		)
	)
	(zone
		(layers "In1.Cu" "In3.Cu" "In5.Cu" "In7.Cu" "In8.Cu" "In9.Cu")
		(hatch none 0.5)
		(connect_pads
			(clearance 0)
		)
		(min_thickness 0.25)
		(keepout
			(tracks not_allowed)
			(vias allowed)
			(pads allowed)
			(copperpour not_allowed)
			(footprints allowed)
		)
		(placement
			(enabled no)
			(sheetname "")
		)
		(fill yes
			(thermal_gap 0.5)
			(thermal_bridge_width 0.5)
			(island_removal_mode 0)
		)
		(polygon
			(pts
				(arc
					(start 55.110634 -389.585962)
					(mid 55.222883 -389.721409)
					(end 55.391304 -389.772144)
				)
				(arc
					(start 55.391304 -389.772144)
					(mid 55.60683 -389.68287)
					(end 55.696104 -389.467344)
				)
				(arc
					(start 55.696104 -389.467344)
					(mid 55.68627 -389.390291)
					(end 55.657242 -389.318246)
				)
				(arc
					(start 55.278274 -388.671562)
					(mid 54.859761 -388.499187)
					(end 54.731158 -388.933182)
				)
			)
		)
	)
	(zone
		(layers "In1.Cu" "In3.Cu" "In5.Cu" "In7.Cu" "In8.Cu" "In9.Cu")
		(hatch none 0.5)
		(connect_pads
			(clearance 0)
		)
		(min_thickness 0.25)
		(keepout
			(tracks not_allowed)
			(vias allowed)
			(pads allowed)
			(copperpour not_allowed)
			(footprints allowed)
		)
		(placement
			(enabled no)
			(sheetname "")
		)
		(fill yes
			(thermal_gap 0.5)
			(thermal_bridge_width 0.5)
			(island_removal_mode 0)
		)
		(polygon
			(pts
				(arc
					(start 348.438216 -397.967962)
					(mid 348.550465 -398.103409)
					(end 348.718886 -398.154144)
				)
				(arc
					(start 348.718886 -398.154144)
					(mid 348.934412 -398.06487)
					(end 349.023686 -397.849344)
				)
				(arc
					(start 349.023686 -397.849344)
					(mid 349.013852 -397.772291)
					(end 348.984824 -397.700246)
				)
				(arc
					(start 348.605856 -397.053562)
					(mid 348.187343 -396.881187)
					(end 348.05874 -397.315182)
				)
			)
		)
	)
	(zone
		(layers "In1.Cu" "In3.Cu" "In5.Cu" "In7.Cu" "In8.Cu" "In9.Cu")
		(hatch none 0.5)
		(connect_pads
			(clearance 0)
		)
		(min_thickness 0.25)
		(keepout
			(tracks not_allowed)
			(vias allowed)
			(pads allowed)
			(copperpour not_allowed)
			(footprints allowed)
		)
		(placement
			(enabled no)
			(sheetname "")
		)
		(fill yes
			(thermal_gap 0.5)
			(thermal_bridge_width 0.5)
			(island_removal_mode 0)
		)
		(polygon
			(pts
				(arc
					(start 52.710588 -389.585962)
					(mid 52.822837 -389.721409)
					(end 52.991258 -389.772144)
				)
				(arc
					(start 52.991258 -389.772144)
					(mid 53.206784 -389.68287)
					(end 53.296058 -389.467344)
				)
				(arc
					(start 53.296058 -389.467344)
					(mid 53.286224 -389.390291)
					(end 53.257196 -389.318246)
				)
				(arc
					(start 52.878228 -388.671562)
					(mid 52.459715 -388.499187)
					(end 52.331112 -388.933182)
				)
			)
		)
	)
	(zone
		(layers "In1.Cu" "In3.Cu" "In5.Cu" "In7.Cu" "In8.Cu" "In9.Cu")
		(hatch none 0.5)
		(connect_pads
			(clearance 0)
		)
		(min_thickness 0.25)
		(keepout
			(tracks not_allowed)
			(vias allowed)
			(pads allowed)
			(copperpour not_allowed)
			(footprints allowed)
		)
		(placement
			(enabled no)
			(sheetname "")
		)
		(fill yes
			(thermal_gap 0.5)
			(thermal_bridge_width 0.5)
			(island_removal_mode 0)
		)
		(polygon
			(pts
				(arc
					(start 373.41048 -397.967962)
					(mid 373.522729 -398.103409)
					(end 373.69115 -398.154144)
				)
				(arc
					(start 373.69115 -398.154144)
					(mid 373.906676 -398.06487)
					(end 373.99595 -397.849344)
				)
				(arc
					(start 373.99595 -397.849344)
					(mid 373.986116 -397.772291)
					(end 373.957088 -397.700246)
				)
				(arc
					(start 373.57812 -397.053562)
					(mid 373.159607 -396.881187)
					(end 373.031004 -397.315182)
				)
			)
		)
	)
	(zone
		(layers "In1.Cu" "In3.Cu" "In5.Cu" "In7.Cu" "In8.Cu" "In9.Cu")
		(hatch none 0.5)
		(connect_pads
			(clearance 0)
		)
		(min_thickness 0.25)
		(keepout
			(tracks not_allowed)
			(vias allowed)
			(pads allowed)
			(copperpour not_allowed)
			(footprints allowed)
		)
		(placement
			(enabled no)
			(sheetname "")
		)
		(fill yes
			(thermal_gap 0.5)
			(thermal_bridge_width 0.5)
			(island_removal_mode 0)
		)
		(polygon
			(pts
				(arc
					(start 115.010692 -389.585962)
					(mid 115.122941 -389.721409)
					(end 115.291362 -389.772144)
				)
				(arc
					(start 115.291362 -389.772144)
					(mid 115.506888 -389.68287)
					(end 115.596162 -389.467344)
				)
				(arc
					(start 115.596162 -389.467344)
					(mid 115.586328 -389.390291)
					(end 115.5573 -389.318246)
				)
				(arc
					(start 115.178332 -388.671562)
					(mid 114.759819 -388.499187)
					(end 114.631216 -388.933182)
				)
			)
		)
	)
	(zone
		(layers "In1.Cu" "In3.Cu" "In5.Cu" "In7.Cu" "In8.Cu" "In9.Cu")
		(hatch none 0.5)
		(connect_pads
			(clearance 0)
		)
		(min_thickness 0.25)
		(keepout
			(tracks not_allowed)
			(vias allowed)
			(pads allowed)
			(copperpour not_allowed)
			(footprints allowed)
		)
		(placement
			(enabled no)
			(sheetname "")
		)
		(fill yes
			(thermal_gap 0.5)
			(thermal_bridge_width 0.5)
			(island_removal_mode 0)
		)
		(polygon
			(pts
				(arc
					(start 347.238066 -397.967962)
					(mid 347.350315 -398.103409)
					(end 347.518736 -398.154144)
				)
				(arc
					(start 347.518736 -398.154144)
					(mid 347.734262 -398.06487)
					(end 347.823536 -397.849344)
				)
				(arc
					(start 347.823536 -397.849344)
					(mid 347.813702 -397.772291)
					(end 347.784674 -397.700246)
				)
				(arc
					(start 347.405706 -397.053562)
					(mid 346.987193 -396.881187)
					(end 346.85859 -397.315182)
				)
			)
		)
	)
	(zone
		(layers "In1.Cu" "In3.Cu" "In5.Cu" "In7.Cu" "In8.Cu" "In9.Cu")
		(hatch none 0.5)
		(connect_pads
			(clearance 0)
		)
		(min_thickness 0.25)
		(keepout
			(tracks not_allowed)
			(vias allowed)
			(pads allowed)
			(copperpour not_allowed)
			(footprints allowed)
		)
		(placement
			(enabled no)
			(sheetname "")
		)
		(fill yes
			(thermal_gap 0.5)
			(thermal_bridge_width 0.5)
			(island_removal_mode 0)
		)
		(polygon
			(pts
				(arc
					(start 386.610606 -397.967962)
					(mid 386.722855 -398.103409)
					(end 386.891276 -398.154144)
				)
				(arc
					(start 386.891276 -398.154144)
					(mid 387.106802 -398.06487)
					(end 387.196076 -397.849344)
				)
				(arc
					(start 387.196076 -397.849344)
					(mid 387.186242 -397.772291)
					(end 387.157214 -397.700246)
				)
				(arc
					(start 386.778246 -397.053562)
					(mid 386.359733 -396.881187)
					(end 386.23113 -397.315182)
				)
			)
		)
	)
	(zone
		(layers "In1.Cu" "In3.Cu" "In5.Cu" "In7.Cu" "In8.Cu" "In9.Cu")
		(hatch none 0.5)
		(connect_pads
			(clearance 0)
		)
		(min_thickness 0.25)
		(keepout
			(tracks not_allowed)
			(vias allowed)
			(pads allowed)
			(copperpour not_allowed)
			(footprints allowed)
		)
		(placement
			(enabled no)
			(sheetname "")
		)
		(fill yes
			(thermal_gap 0.5)
			(thermal_bridge_width 0.5)
			(island_removal_mode 0)
		)
		(polygon
			(pts
				(arc
					(start 350.838008 -397.967962)
					(mid 350.950257 -398.103409)
					(end 351.118678 -398.154144)
				)
				(arc
					(start 351.118678 -398.154144)
					(mid 351.334204 -398.06487)
					(end 351.423478 -397.849344)
				)
				(arc
					(start 351.423478 -397.849344)
					(mid 351.413644 -397.772291)
					(end 351.384616 -397.700246)
				)
				(arc
					(start 351.005648 -397.053562)
					(mid 350.587135 -396.881187)
					(end 350.458532 -397.315182)
				)
			)
		)
	)
	(zone
		(layers "In1.Cu" "In3.Cu" "In5.Cu" "In7.Cu" "In8.Cu" "In9.Cu")
		(hatch none 0.5)
		(connect_pads
			(clearance 0)
		)
		(min_thickness 0.25)
		(keepout
			(tracks not_allowed)
			(vias allowed)
			(pads allowed)
			(copperpour not_allowed)
			(footprints allowed)
		)
		(placement
			(enabled no)
			(sheetname "")
		)
		(fill yes
			(thermal_gap 0.5)
			(thermal_bridge_width 0.5)
			(island_removal_mode 0)
		)
		(polygon
			(pts
				(arc
					(start 65.910714 -389.585962)
					(mid 66.022963 -389.721409)
					(end 66.191384 -389.772144)
				)
				(arc
					(start 66.191384 -389.772144)
					(mid 66.40691 -389.68287)
					(end 66.496184 -389.467344)
				)
				(arc
					(start 66.496184 -389.467344)
					(mid 66.48635 -389.390291)
					(end 66.457322 -389.318246)
				)
				(arc
					(start 66.078354 -388.671562)
					(mid 65.659841 -388.499187)
					(end 65.531238 -388.933182)
				)
			)
		)
	)
	(zone
		(layers "In1.Cu" "In3.Cu" "In5.Cu" "In7.Cu" "In8.Cu" "In9.Cu")
		(hatch none 0.5)
		(connect_pads
			(clearance 0)
		)
		(min_thickness 0.25)
		(keepout
			(tracks not_allowed)
			(vias allowed)
			(pads allowed)
			(copperpour not_allowed)
			(footprints allowed)
		)
		(placement
			(enabled no)
			(sheetname "")
		)
		(fill yes
			(thermal_gap 0.5)
			(thermal_bridge_width 0.5)
			(island_removal_mode 0)
		)
		(polygon
			(pts
				(arc
					(start 340.038182 -397.967962)
					(mid 340.150431 -398.103409)
					(end 340.318852 -398.154144)
				)
				(arc
					(start 340.318852 -398.154144)
					(mid 340.534378 -398.06487)
					(end 340.623652 -397.849344)
				)
				(arc
					(start 340.623652 -397.849344)
					(mid 340.613818 -397.772291)
					(end 340.58479 -397.700246)
				)
				(arc
					(start 340.205822 -397.053562)
					(mid 339.787309 -396.881187)
					(end 339.658706 -397.315182)
				)
			)
		)
	)
	(zone
		(layers "In1.Cu" "In3.Cu" "In5.Cu" "In7.Cu" "In8.Cu" "In9.Cu")
		(hatch none 0.5)
		(connect_pads
			(clearance 0)
		)
		(min_thickness 0.25)
		(keepout
			(tracks not_allowed)
			(vias allowed)
			(pads allowed)
			(copperpour not_allowed)
			(footprints allowed)
		)
		(placement
			(enabled no)
			(sheetname "")
		)
		(fill yes
			(thermal_gap 0.5)
			(thermal_bridge_width 0.5)
			(island_removal_mode 0)
		)
		(polygon
			(pts
				(arc
					(start 62.310518 -389.585962)
					(mid 62.422767 -389.721409)
					(end 62.591188 -389.772144)
				)
				(arc
					(start 62.591188 -389.772144)
					(mid 62.806714 -389.68287)
					(end 62.895988 -389.467344)
				)
				(arc
					(start 62.895988 -389.467344)
					(mid 62.886154 -389.390291)
					(end 62.857126 -389.318246)
				)
				(arc
					(start 62.478158 -388.671562)
					(mid 62.059645 -388.499187)
					(end 61.931042 -388.933182)
				)
			)
		)
	)
	(zone
		(layers "In1.Cu" "In3.Cu" "In5.Cu" "In7.Cu" "In8.Cu" "In9.Cu")
		(hatch none 0.5)
		(connect_pads
			(clearance 0)
		)
		(min_thickness 0.25)
		(keepout
			(tracks not_allowed)
			(vias allowed)
			(pads allowed)
			(copperpour not_allowed)
			(footprints allowed)
		)
		(placement
			(enabled no)
			(sheetname "")
		)
		(fill yes
			(thermal_gap 0.5)
			(thermal_bridge_width 0.5)
			(island_removal_mode 0)
		)
		(polygon
			(pts
				(arc
					(start 63.510668 -389.585962)
					(mid 63.622917 -389.721409)
					(end 63.791338 -389.772144)
				)
				(arc
					(start 63.791338 -389.772144)
					(mid 64.006864 -389.68287)
					(end 64.096138 -389.467344)
				)
				(arc
					(start 64.096138 -389.467344)
					(mid 64.086304 -389.390291)
					(end 64.057276 -389.318246)
				)
				(arc
					(start 63.678308 -388.671562)
					(mid 63.259795 -388.499187)
					(end 63.131192 -388.933182)
				)
			)
		)
	)
	(zone
		(layers "In1.Cu" "In3.Cu" "In5.Cu" "In7.Cu" "In8.Cu" "In9.Cu")
		(hatch none 0.5)
		(connect_pads
			(clearance 0)
		)
		(min_thickness 0.25)
		(keepout
			(tracks not_allowed)
			(vias allowed)
			(pads allowed)
			(copperpour not_allowed)
			(footprints allowed)
		)
		(placement
			(enabled no)
			(sheetname "")
		)
		(fill yes
			(thermal_gap 0.5)
			(thermal_bridge_width 0.5)
			(island_removal_mode 0)
		)
		(polygon
			(pts
				(arc
					(start 51.510692 -389.585962)
					(mid 51.622941 -389.721409)
					(end 51.791362 -389.772144)
				)
				(arc
					(start 51.791362 -389.772144)
					(mid 52.006888 -389.68287)
					(end 52.096162 -389.467344)
				)
				(arc
					(start 52.096162 -389.467344)
					(mid 52.086328 -389.390291)
					(end 52.0573 -389.318246)
				)
				(arc
					(start 51.678332 -388.671562)
					(mid 51.259819 -388.499187)
					(end 51.131216 -388.933182)
				)
			)
		)
	)
	(zone
		(layers "In1.Cu" "In3.Cu" "In5.Cu" "In7.Cu" "In8.Cu" "In9.Cu")
		(hatch none 0.5)
		(connect_pads
			(clearance 0)
		)
		(min_thickness 0.25)
		(keepout
			(tracks not_allowed)
			(vias allowed)
			(pads allowed)
			(copperpour not_allowed)
			(footprints allowed)
		)
		(placement
			(enabled no)
			(sheetname "")
		)
		(fill yes
			(thermal_gap 0.5)
			(thermal_bridge_width 0.5)
			(island_removal_mode 0)
		)
		(polygon
			(pts
				(arc
					(start 342.438228 -397.967962)
					(mid 342.550477 -398.103409)
					(end 342.718898 -398.154144)
				)
				(arc
					(start 342.718898 -398.154144)
					(mid 342.934424 -398.06487)
					(end 343.023698 -397.849344)
				)
				(arc
					(start 343.023698 -397.849344)
					(mid 343.013864 -397.772291)
					(end 342.984836 -397.700246)
				)
				(arc
					(start 342.605868 -397.053562)
					(mid 342.187355 -396.881187)
					(end 342.058752 -397.315182)
				)
			)
		)
	)
	(zone
		(layers "In1.Cu" "In3.Cu" "In5.Cu" "In7.Cu" "In8.Cu" "In9.Cu")
		(hatch none 0.5)
		(connect_pads
			(clearance 0)
		)
		(min_thickness 0.25)
		(keepout
			(tracks not_allowed)
			(vias allowed)
			(pads allowed)
			(copperpour not_allowed)
			(footprints allowed)
		)
		(placement
			(enabled no)
			(sheetname "")
		)
		(fill yes
			(thermal_gap 0.5)
			(thermal_bridge_width 0.5)
			(island_removal_mode 0)
		)
		(polygon
			(pts
				(arc
					(start 133.010656 -389.585962)
					(mid 133.122905 -389.721409)
					(end 133.291326 -389.772144)
				)
				(arc
					(start 133.291326 -389.772144)
					(mid 133.506852 -389.68287)
					(end 133.596126 -389.467344)
				)
				(arc
					(start 133.596126 -389.467344)
					(mid 133.586292 -389.390291)
					(end 133.557264 -389.318246)
				)
				(arc
					(start 133.178296 -388.671562)
					(mid 132.759783 -388.499187)
					(end 132.63118 -388.933182)
				)
			)
		)
	)
	(zone
		(layers "In1.Cu" "In3.Cu" "In5.Cu" "In7.Cu" "In8.Cu" "In9.Cu")
		(hatch none 0.5)
		(connect_pads
			(clearance 0)
		)
		(min_thickness 0.25)
		(keepout
			(tracks not_allowed)
			(vias allowed)
			(pads allowed)
			(copperpour not_allowed)
			(footprints allowed)
		)
		(placement
			(enabled no)
			(sheetname "")
		)
		(fill yes
			(thermal_gap 0.5)
			(thermal_bridge_width 0.5)
			(island_removal_mode 0)
		)
		(polygon
			(pts
				(arc
					(start 336.43824 -397.967962)
					(mid 336.550489 -398.103409)
					(end 336.71891 -398.154144)
				)
				(arc
					(start 336.71891 -398.154144)
					(mid 336.934436 -398.06487)
					(end 337.02371 -397.849344)
				)
				(arc
					(start 337.02371 -397.849344)
					(mid 337.013876 -397.772291)
					(end 336.984848 -397.700246)
				)
				(arc
					(start 336.60588 -397.053562)
					(mid 336.187367 -396.881187)
					(end 336.058764 -397.315182)
				)
			)
		)
	)
	(zone
		(layers "In1.Cu" "In3.Cu" "In5.Cu" "In7.Cu" "In8.Cu" "In9.Cu")
		(hatch none 0.5)
		(connect_pads
			(clearance 0)
		)
		(min_thickness 0.25)
		(keepout
			(tracks not_allowed)
			(vias allowed)
			(pads allowed)
			(copperpour not_allowed)
			(footprints allowed)
		)
		(placement
			(enabled no)
			(sheetname "")
		)
		(fill yes
			(thermal_gap 0.5)
			(thermal_bridge_width 0.5)
			(island_removal_mode 0)
		)
		(polygon
			(pts
				(arc
					(start 56.31053 -389.585962)
					(mid 56.422779 -389.721409)
					(end 56.5912 -389.772144)
				)
				(arc
					(start 56.5912 -389.772144)
					(mid 56.806726 -389.68287)
					(end 56.896 -389.467344)
				)
				(arc
					(start 56.896 -389.467344)
					(mid 56.886166 -389.390291)
					(end 56.857138 -389.318246)
				)
				(arc
					(start 56.47817 -388.671562)
					(mid 56.059657 -388.499187)
					(end 55.931054 -388.933182)
				)
			)
		)
	)
	(zone
		(layers "In1.Cu" "In3.Cu" "In5.Cu" "In7.Cu" "In8.Cu" "In9.Cu")
		(hatch none 0.5)
		(connect_pads
			(clearance 0)
		)
		(min_thickness 0.25)
		(keepout
			(tracks not_allowed)
			(vias allowed)
			(pads allowed)
			(copperpour not_allowed)
			(footprints allowed)
		)
		(placement
			(enabled no)
			(sheetname "")
		)
		(fill yes
			(thermal_gap 0.5)
			(thermal_bridge_width 0.5)
			(island_removal_mode 0)
		)
		(polygon
			(pts
				(arc
					(start 352.038158 -397.967962)
					(mid 352.150407 -398.103409)
					(end 352.318828 -398.154144)
				)
				(arc
					(start 352.318828 -398.154144)
					(mid 352.534354 -398.06487)
					(end 352.623628 -397.849344)
				)
				(arc
					(start 352.623628 -397.849344)
					(mid 352.613794 -397.772291)
					(end 352.584766 -397.700246)
				)
				(arc
					(start 352.205798 -397.053562)
					(mid 351.787285 -396.881187)
					(end 351.658682 -397.315182)
				)
			)
		)
	)
	(zone
		(layers "In1.Cu" "In3.Cu" "In5.Cu" "In7.Cu" "In8.Cu" "In9.Cu")
		(hatch none 0.5)
		(connect_pads
			(clearance 0)
		)
		(min_thickness 0.25)
		(keepout
			(tracks not_allowed)
			(vias allowed)
			(pads allowed)
			(copperpour not_allowed)
			(footprints allowed)
		)
		(placement
			(enabled no)
			(sheetname "")
		)
		(fill yes
			(thermal_gap 0.5)
			(thermal_bridge_width 0.5)
			(island_removal_mode 0)
		)
		(polygon
			(pts
				(arc
					(start 341.238078 -397.967962)
					(mid 341.350327 -398.103409)
					(end 341.518748 -398.154144)
				)
				(arc
					(start 341.518748 -398.154144)
					(mid 341.734274 -398.06487)
					(end 341.823548 -397.849344)
				)
				(arc
					(start 341.823548 -397.849344)
					(mid 341.813714 -397.772291)
					(end 341.784686 -397.700246)
				)
				(arc
					(start 341.405718 -397.053562)
					(mid 340.987205 -396.881187)
					(end 340.858602 -397.315182)
				)
			)
		)
	)
	(zone
		(layers "In1.Cu" "In3.Cu" "In5.Cu" "In7.Cu" "In8.Cu" "In9.Cu")
		(hatch none 0.5)
		(connect_pads
			(clearance 0)
		)
		(min_thickness 0.25)
		(keepout
			(tracks not_allowed)
			(vias allowed)
			(pads allowed)
			(copperpour not_allowed)
			(footprints allowed)
		)
		(placement
			(enabled no)
			(sheetname "")
		)
		(fill yes
			(thermal_gap 0.5)
			(thermal_bridge_width 0.5)
			(island_removal_mode 0)
		)
		(polygon
			(pts
				(arc
					(start 381.810514 -397.967962)
					(mid 381.922763 -398.103409)
					(end 382.091184 -398.154144)
				)
				(arc
					(start 382.091184 -398.154144)
					(mid 382.30671 -398.06487)
					(end 382.395984 -397.849344)
				)
				(arc
					(start 382.395984 -397.849344)
					(mid 382.38615 -397.772291)
					(end 382.357122 -397.700246)
				)
				(arc
					(start 381.978154 -397.053562)
					(mid 381.559641 -396.881187)
					(end 381.431038 -397.315182)
				)
			)
		)
	)
	(zone
		(layers "In1.Cu" "In3.Cu" "In5.Cu" "In7.Cu" "In8.Cu" "In9.Cu")
		(hatch none 0.5)
		(connect_pads
			(clearance 0)
		)
		(min_thickness 0.25)
		(keepout
			(tracks not_allowed)
			(vias allowed)
			(pads allowed)
			(copperpour not_allowed)
			(footprints allowed)
		)
		(placement
			(enabled no)
			(sheetname "")
		)
		(fill yes
			(thermal_gap 0.5)
			(thermal_bridge_width 0.5)
			(island_removal_mode 0)
		)
		(polygon
			(pts
				(arc
					(start 371.010688 -397.967962)
					(mid 371.122937 -398.103409)
					(end 371.291358 -398.154144)
				)
				(arc
					(start 371.291358 -398.154144)
					(mid 371.506884 -398.06487)
					(end 371.596158 -397.849344)
				)
				(arc
					(start 371.596158 -397.849344)
					(mid 371.586324 -397.772291)
					(end 371.557296 -397.700246)
				)
				(arc
					(start 371.178328 -397.053562)
					(mid 370.759815 -396.881187)
					(end 370.631212 -397.315182)
				)
			)
		)
	)
	(zone
		(layers "In1.Cu" "In3.Cu" "In5.Cu" "In7.Cu" "In8.Cu" "In9.Cu")
		(hatch none 0.5)
		(connect_pads
			(clearance 0)
		)
		(min_thickness 0.25)
		(keepout
			(tracks not_allowed)
			(vias allowed)
			(pads allowed)
			(copperpour not_allowed)
			(footprints allowed)
		)
		(placement
			(enabled no)
			(sheetname "")
		)
		(fill yes
			(thermal_gap 0.5)
			(thermal_bridge_width 0.5)
			(island_removal_mode 0)
		)
		(polygon
			(pts
				(arc
					(start 378.210572 -397.967962)
					(mid 378.322821 -398.103409)
					(end 378.491242 -398.154144)
				)
				(arc
					(start 378.491242 -398.154144)
					(mid 378.706768 -398.06487)
					(end 378.796042 -397.849344)
				)
				(arc
					(start 378.796042 -397.849344)
					(mid 378.786208 -397.772291)
					(end 378.75718 -397.700246)
				)
				(arc
					(start 378.378212 -397.053562)
					(mid 377.959699 -396.881187)
					(end 377.831096 -397.315182)
				)
			)
		)
	)
	(zone
		(layers "In1.Cu" "In3.Cu" "In5.Cu" "In7.Cu" "In8.Cu" "In9.Cu")
		(hatch none 0.5)
		(connect_pads
			(clearance 0)
		)
		(min_thickness 0.25)
		(keepout
			(tracks not_allowed)
			(vias allowed)
			(pads allowed)
			(copperpour not_allowed)
			(footprints allowed)
		)
		(placement
			(enabled no)
			(sheetname "")
		)
		(fill yes
			(thermal_gap 0.5)
			(thermal_bridge_width 0.5)
			(island_removal_mode 0)
		)
		(polygon
			(pts
				(arc
					(start 59.910726 -389.585962)
					(mid 60.022975 -389.721409)
					(end 60.191396 -389.772144)
				)
				(arc
					(start 60.191396 -389.772144)
					(mid 60.406922 -389.68287)
					(end 60.496196 -389.467344)
				)
				(arc
					(start 60.496196 -389.467344)
					(mid 60.486362 -389.390291)
					(end 60.457334 -389.318246)
				)
				(arc
					(start 60.078366 -388.671562)
					(mid 59.659853 -388.499187)
					(end 59.53125 -388.933182)
				)
			)
		)
	)
	(zone
		(layers "In1.Cu" "In3.Cu" "In5.Cu" "In7.Cu" "In8.Cu" "In9.Cu")
		(hatch none 0.5)
		(connect_pads
			(clearance 0)
		)
		(min_thickness 0.25)
		(keepout
			(tracks not_allowed)
			(vias allowed)
			(pads allowed)
			(copperpour not_allowed)
			(footprints allowed)
		)
		(placement
			(enabled no)
			(sheetname "")
		)
		(fill yes
			(thermal_gap 0.5)
			(thermal_bridge_width 0.5)
			(island_removal_mode 0)
		)
		(polygon
			(pts
				(arc
					(start 344.83802 -397.967962)
					(mid 344.950269 -398.103409)
					(end 345.11869 -398.154144)
				)
				(arc
					(start 345.11869 -398.154144)
					(mid 345.334216 -398.06487)
					(end 345.42349 -397.849344)
				)
				(arc
					(start 345.42349 -397.849344)
					(mid 345.413656 -397.772291)
					(end 345.384628 -397.700246)
				)
				(arc
					(start 345.00566 -397.053562)
					(mid 344.587147 -396.881187)
					(end 344.458544 -397.315182)
				)
			)
		)
	)
	(zone
		(layers "In1.Cu" "In3.Cu" "In5.Cu" "In7.Cu" "In8.Cu" "In9.Cu")
		(hatch none 0.5)
		(connect_pads
			(clearance 0)
		)
		(min_thickness 0.25)
		(keepout
			(tracks not_allowed)
			(vias allowed)
			(pads allowed)
			(copperpour not_allowed)
			(footprints allowed)
		)
		(placement
			(enabled no)
			(sheetname "")
		)
		(fill yes
			(thermal_gap 0.5)
			(thermal_bridge_width 0.5)
			(island_removal_mode 0)
		)
		(polygon
			(pts
				(arc
					(start 379.410468 -397.967962)
					(mid 379.522717 -398.103409)
					(end 379.691138 -398.154144)
				)
				(arc
					(start 379.691138 -398.154144)
					(mid 379.906664 -398.06487)
					(end 379.995938 -397.849344)
				)
				(arc
					(start 379.995938 -397.849344)
					(mid 379.986104 -397.772291)
					(end 379.957076 -397.700246)
				)
				(arc
					(start 379.578108 -397.053562)
					(mid 379.159595 -396.881187)
					(end 379.030992 -397.315182)
				)
			)
		)
	)
	(zone
		(layers "In1.Cu" "In3.Cu" "In5.Cu" "In7.Cu" "In8.Cu" "In9.Cu")
		(hatch none 0.5)
		(connect_pads
			(clearance 0)
		)
		(min_thickness 0.25)
		(keepout
			(tracks not_allowed)
			(vias allowed)
			(pads allowed)
			(copperpour not_allowed)
			(footprints allowed)
		)
		(placement
			(enabled no)
			(sheetname "")
		)
		(fill yes
			(thermal_gap 0.5)
			(thermal_bridge_width 0.5)
			(island_removal_mode 0)
		)
		(polygon
			(pts
				(arc
					(start 119.81053 -389.585962)
					(mid 119.922779 -389.721409)
					(end 120.0912 -389.772144)
				)
				(arc
					(start 120.0912 -389.772144)
					(mid 120.306726 -389.68287)
					(end 120.396 -389.467344)
				)
				(arc
					(start 120.396 -389.467344)
					(mid 120.386166 -389.390291)
					(end 120.357138 -389.318246)
				)
				(arc
					(start 119.97817 -388.671562)
					(mid 119.559657 -388.499187)
					(end 119.431054 -388.933182)
				)
			)
		)
	)
	(zone
		(layers "In1.Cu" "In3.Cu" "In5.Cu" "In7.Cu" "In8.Cu" "In9.Cu")
		(hatch none 0.5)
		(connect_pads
			(clearance 0)
		)
		(min_thickness 0.25)
		(keepout
			(tracks not_allowed)
			(vias allowed)
			(pads allowed)
			(copperpour not_allowed)
			(footprints allowed)
		)
		(placement
			(enabled no)
			(sheetname "")
		)
		(fill yes
			(thermal_gap 0.5)
			(thermal_bridge_width 0.5)
			(island_removal_mode 0)
		)
		(polygon
			(pts
				(arc
					(start 377.010676 -397.967962)
					(mid 377.122925 -398.103409)
					(end 377.291346 -398.154144)
				)
				(arc
					(start 377.291346 -398.154144)
					(mid 377.506872 -398.06487)
					(end 377.596146 -397.849344)
				)
				(arc
					(start 377.596146 -397.849344)
					(mid 377.586312 -397.772291)
					(end 377.557284 -397.700246)
				)
				(arc
					(start 377.178316 -397.053562)
					(mid 376.759803 -396.881187)
					(end 376.6312 -397.315182)
				)
			)
		)
	)
	(zone
		(layers "In1.Cu" "In3.Cu" "In5.Cu" "In7.Cu" "In8.Cu" "In9.Cu")
		(hatch none 0.5)
		(connect_pads
			(clearance 0)
		)
		(min_thickness 0.25)
		(keepout
			(tracks not_allowed)
			(vias allowed)
			(pads allowed)
			(copperpour not_allowed)
			(footprints allowed)
		)
		(placement
			(enabled no)
			(sheetname "")
		)
		(fill yes
			(thermal_gap 0.5)
			(thermal_bridge_width 0.5)
			(island_removal_mode 0)
		)
		(polygon
			(pts
				(arc
					(start 384.21056 -397.967962)
					(mid 384.322809 -398.103409)
					(end 384.49123 -398.154144)
				)
				(arc
					(start 384.49123 -398.154144)
					(mid 384.706756 -398.06487)
					(end 384.79603 -397.849344)
				)
				(arc
					(start 384.79603 -397.849344)
					(mid 384.786196 -397.772291)
					(end 384.757168 -397.700246)
				)
				(arc
					(start 384.3782 -397.053562)
					(mid 383.959687 -396.881187)
					(end 383.831084 -397.315182)
				)
			)
		)
	)
	(zone
		(layers "In1.Cu" "In3.Cu" "In5.Cu" "In7.Cu" "In8.Cu" "In9.Cu")
		(hatch none 0.5)
		(connect_pads
			(clearance 0)
		)
		(min_thickness 0.25)
		(keepout
			(tracks not_allowed)
			(vias allowed)
			(pads allowed)
			(copperpour not_allowed)
			(footprints allowed)
		)
		(placement
			(enabled no)
			(sheetname "")
		)
		(fill yes
			(thermal_gap 0.5)
			(thermal_bridge_width 0.5)
			(island_removal_mode 0)
		)
		(polygon
			(pts
				(arc
					(start 343.638124 -397.967962)
					(mid 343.750373 -398.103409)
					(end 343.918794 -398.154144)
				)
				(arc
					(start 343.918794 -398.154144)
					(mid 344.13432 -398.06487)
					(end 344.223594 -397.849344)
				)
				(arc
					(start 344.223594 -397.849344)
					(mid 344.21376 -397.772291)
					(end 344.184732 -397.700246)
				)
				(arc
					(start 343.805764 -397.053562)
					(mid 343.387251 -396.881187)
					(end 343.258648 -397.315182)
				)
			)
		)
	)
	(zone
		(layers "In1.Cu" "In3.Cu" "In5.Cu" "In7.Cu" "In8.Cu" "In9.Cu")
		(hatch none 0.5)
		(connect_pads
			(clearance 0)
		)
		(min_thickness 0.25)
		(keepout
			(tracks not_allowed)
			(vias allowed)
			(pads allowed)
			(copperpour not_allowed)
			(footprints allowed)
		)
		(placement
			(enabled no)
			(sheetname "")
		)
		(fill yes
			(thermal_gap 0.5)
			(thermal_bridge_width 0.5)
			(island_removal_mode 0)
		)
		(polygon
			(pts
				(arc
					(start 61.110622 -389.585962)
					(mid 61.222871 -389.721409)
					(end 61.391292 -389.772144)
				)
				(arc
					(start 61.391292 -389.772144)
					(mid 61.606818 -389.68287)
					(end 61.696092 -389.467344)
				)
				(arc
					(start 61.696092 -389.467344)
					(mid 61.686258 -389.390291)
					(end 61.65723 -389.318246)
				)
				(arc
					(start 61.278262 -388.671562)
					(mid 60.859749 -388.499187)
					(end 60.731146 -388.933182)
				)
			)
		)
	)
	(zone
		(layers "In1.Cu" "In3.Cu" "In5.Cu" "In7.Cu" "In8.Cu" "In9.Cu")
		(hatch none 0.5)
		(connect_pads
			(clearance 0)
		)
		(min_thickness 0.25)
		(keepout
			(tracks not_allowed)
			(vias allowed)
			(pads allowed)
			(copperpour not_allowed)
			(footprints allowed)
		)
		(placement
			(enabled no)
			(sheetname "")
		)
		(fill yes
			(thermal_gap 0.5)
			(thermal_bridge_width 0.5)
			(island_removal_mode 0)
		)
		(polygon
			(pts
				(arc
					(start 387.810502 -397.967962)
					(mid 387.922751 -398.103409)
					(end 388.091172 -398.154144)
				)
				(arc
					(start 388.091172 -398.154144)
					(mid 388.306698 -398.06487)
					(end 388.395972 -397.849344)
				)
				(arc
					(start 388.395972 -397.849344)
					(mid 388.386138 -397.772291)
					(end 388.35711 -397.700246)
				)
				(arc
					(start 387.978142 -397.053562)
					(mid 387.559629 -396.881187)
					(end 387.431026 -397.315182)
				)
			)
		)
	)
	(zone
		(layers "In1.Cu" "In3.Cu" "In5.Cu" "In7.Cu" "In8.Cu" "In9.Cu")
		(hatch none 0.5)
		(connect_pads
			(clearance 0)
		)
		(min_thickness 0.25)
		(keepout
			(tracks not_allowed)
			(vias allowed)
			(pads allowed)
			(copperpour not_allowed)
			(footprints allowed)
		)
		(placement
			(enabled no)
			(sheetname "")
		)
		(fill yes
			(thermal_gap 0.5)
			(thermal_bridge_width 0.5)
			(island_removal_mode 0)
		)
		(polygon
			(pts
				(arc
					(start 58.710576 -389.585962)
					(mid 58.822825 -389.721409)
					(end 58.991246 -389.772144)
				)
				(arc
					(start 58.991246 -389.772144)
					(mid 59.206772 -389.68287)
					(end 59.296046 -389.467344)
				)
				(arc
					(start 59.296046 -389.467344)
					(mid 59.286212 -389.390291)
					(end 59.257184 -389.318246)
				)
				(arc
					(start 58.878216 -388.671562)
					(mid 58.459703 -388.499187)
					(end 58.3311 -388.933182)
				)
			)
		)
	)
	(zone
		(layers "In1.Cu" "In3.Cu" "In5.Cu" "In7.Cu" "In8.Cu" "In9.Cu")
		(hatch none 0.5)
		(connect_pads
			(clearance 0)
		)
		(min_thickness 0.25)
		(keepout
			(tracks not_allowed)
			(vias allowed)
			(pads allowed)
			(copperpour not_allowed)
			(footprints allowed)
		)
		(placement
			(enabled no)
			(sheetname "")
		)
		(fill yes
			(thermal_gap 0.5)
			(thermal_bridge_width 0.5)
			(island_removal_mode 0)
		)
		(polygon
			(pts
				(arc
					(start 374.61063 -397.967962)
					(mid 374.722879 -398.103409)
					(end 374.8913 -398.154144)
				)
				(arc
					(start 374.8913 -398.154144)
					(mid 375.106826 -398.06487)
					(end 375.1961 -397.849344)
				)
				(arc
					(start 375.1961 -397.849344)
					(mid 375.186266 -397.772291)
					(end 375.157238 -397.700246)
				)
				(arc
					(start 374.77827 -397.053562)
					(mid 374.359757 -396.881187)
					(end 374.231154 -397.315182)
				)
			)
		)
	)
	(zone
		(layers "In1.Cu" "In3.Cu" "In5.Cu" "In7.Cu" "In8.Cu" "In9.Cu")
		(hatch none 0.5)
		(connect_pads
			(clearance 0)
		)
		(min_thickness 0.25)
		(keepout
			(tracks not_allowed)
			(vias allowed)
			(pads allowed)
			(copperpour not_allowed)
			(footprints allowed)
		)
		(placement
			(enabled no)
			(sheetname "")
		)
		(fill yes
			(thermal_gap 0.5)
			(thermal_bridge_width 0.5)
			(island_removal_mode 0)
		)
		(polygon
			(pts
				(arc
					(start 346.03817 -397.967962)
					(mid 346.150419 -398.103409)
					(end 346.31884 -398.154144)
				)
				(arc
					(start 346.31884 -398.154144)
					(mid 346.534366 -398.06487)
					(end 346.62364 -397.849344)
				)
				(arc
					(start 346.62364 -397.849344)
					(mid 346.613806 -397.772291)
					(end 346.584778 -397.700246)
				)
				(arc
					(start 346.20581 -397.053562)
					(mid 345.787297 -396.881187)
					(end 345.658694 -397.315182)
				)
			)
		)
	)
	(zone
		(layers "In1.Cu" "In3.Cu" "In5.Cu" "In7.Cu" "In8.Cu" "In9.Cu")
		(hatch none 0.5)
		(connect_pads
			(clearance 0)
		)
		(min_thickness 0.25)
		(keepout
			(tracks not_allowed)
			(vias allowed)
			(pads allowed)
			(copperpour not_allowed)
			(footprints allowed)
		)
		(placement
			(enabled no)
			(sheetname "")
		)
		(fill yes
			(thermal_gap 0.5)
			(thermal_bridge_width 0.5)
			(island_removal_mode 0)
		)
		(polygon
			(pts
				(arc
					(start 47.91075 -389.585962)
					(mid 48.022999 -389.721409)
					(end 48.19142 -389.772144)
				)
				(arc
					(start 48.19142 -389.772144)
					(mid 48.406946 -389.68287)
					(end 48.49622 -389.467344)
				)
				(arc
					(start 48.49622 -389.467344)
					(mid 48.486386 -389.390291)
					(end 48.457358 -389.318246)
				)
				(arc
					(start 48.07839 -388.671562)
					(mid 47.659877 -388.499187)
					(end 47.531274 -388.933182)
				)
			)
		)
	)
	(zone
		(layers "In1.Cu" "In3.Cu" "In5.Cu" "In7.Cu" "In8.Cu" "In9.Cu")
		(hatch none 0.5)
		(connect_pads
			(clearance 0)
		)
		(min_thickness 0.25)
		(keepout
			(tracks not_allowed)
			(vias allowed)
			(pads allowed)
			(copperpour not_allowed)
			(footprints allowed)
		)
		(placement
			(enabled no)
			(sheetname "")
		)
		(fill yes
			(thermal_gap 0.5)
			(thermal_bridge_width 0.5)
			(island_removal_mode 0)
		)
		(polygon
			(pts
				(arc
					(start 127.010668 -389.585962)
					(mid 127.122917 -389.721409)
					(end 127.291338 -389.772144)
				)
				(arc
					(start 127.291338 -389.772144)
					(mid 127.506864 -389.68287)
					(end 127.596138 -389.467344)
				)
				(arc
					(start 127.596138 -389.467344)
					(mid 127.586304 -389.390291)
					(end 127.557276 -389.318246)
				)
				(arc
					(start 127.178308 -388.671562)
					(mid 126.759795 -388.499187)
					(end 126.631192 -388.933182)
				)
			)
		)
	)
	(zone
		(layers "In1.Cu" "In3.Cu" "In5.Cu" "In7.Cu" "In8.Cu" "In9.Cu")
		(hatch none 0.5)
		(connect_pads
			(clearance 0)
		)
		(min_thickness 0.25)
		(keepout
			(tracks not_allowed)
			(vias allowed)
			(pads allowed)
			(copperpour not_allowed)
			(footprints allowed)
		)
		(placement
			(enabled no)
			(sheetname "")
		)
		(fill yes
			(thermal_gap 0.5)
			(thermal_bridge_width 0.5)
			(island_removal_mode 0)
		)
		(polygon
			(pts
				(arc
					(start 128.210564 -389.585962)
					(mid 128.322813 -389.721409)
					(end 128.491234 -389.772144)
				)
				(arc
					(start 128.491234 -389.772144)
					(mid 128.70676 -389.68287)
					(end 128.796034 -389.467344)
				)
				(arc
					(start 128.796034 -389.467344)
					(mid 128.7862 -389.390291)
					(end 128.757172 -389.318246)
				)
				(arc
					(start 128.378204 -388.671562)
					(mid 127.959691 -388.499187)
					(end 127.831088 -388.933182)
				)
			)
		)
	)
	(zone
		(layers "In1.Cu" "In3.Cu" "In5.Cu" "In7.Cu" "In8.Cu" "In9.Cu")
		(hatch none 0.5)
		(connect_pads
			(clearance 0)
		)
		(min_thickness 0.25)
		(keepout
			(tracks not_allowed)
			(vias allowed)
			(pads allowed)
			(copperpour not_allowed)
			(footprints allowed)
		)
		(placement
			(enabled no)
			(sheetname "")
		)
		(fill yes
			(thermal_gap 0.5)
			(thermal_bridge_width 0.5)
			(island_removal_mode 0)
		)
		(polygon
			(pts
				(arc
					(start 123.410472 -389.585962)
					(mid 123.522721 -389.721409)
					(end 123.691142 -389.772144)
				)
				(arc
					(start 123.691142 -389.772144)
					(mid 123.906668 -389.68287)
					(end 123.995942 -389.467344)
				)
				(arc
					(start 123.995942 -389.467344)
					(mid 123.986108 -389.390291)
					(end 123.95708 -389.318246)
				)
				(arc
					(start 123.578112 -388.671562)
					(mid 123.159599 -388.499187)
					(end 123.030996 -388.933182)
				)
			)
		)
	)
	(zone
		(layers "In1.Cu" "In3.Cu" "In5.Cu" "In7.Cu" "In8.Cu" "In9.Cu")
		(hatch none 0.5)
		(connect_pads
			(clearance 0)
		)
		(min_thickness 0.25)
		(keepout
			(tracks not_allowed)
			(vias allowed)
			(pads allowed)
			(copperpour not_allowed)
			(footprints allowed)
		)
		(placement
			(enabled no)
			(sheetname "")
		)
		(fill yes
			(thermal_gap 0.5)
			(thermal_bridge_width 0.5)
			(island_removal_mode 0)
		)
		(polygon
			(pts
				(arc
					(start 130.61061 -389.585962)
					(mid 130.722859 -389.721409)
					(end 130.89128 -389.772144)
				)
				(arc
					(start 130.89128 -389.772144)
					(mid 131.106806 -389.68287)
					(end 131.19608 -389.467344)
				)
				(arc
					(start 131.19608 -389.467344)
					(mid 131.186246 -389.390291)
					(end 131.157218 -389.318246)
				)
				(arc
					(start 130.77825 -388.671562)
					(mid 130.359737 -388.499187)
					(end 130.231134 -388.933182)
				)
			)
		)
	)
	(zone
		(layers "In1.Cu" "In3.Cu" "In5.Cu" "In7.Cu" "In8.Cu" "In9.Cu")
		(hatch none 0.5)
		(connect_pads
			(clearance 0)
		)
		(min_thickness 0.25)
		(keepout
			(tracks not_allowed)
			(vias allowed)
			(pads allowed)
			(copperpour not_allowed)
			(footprints allowed)
		)
		(placement
			(enabled no)
			(sheetname "")
		)
		(fill yes
			(thermal_gap 0.5)
			(thermal_bridge_width 0.5)
			(island_removal_mode 0)
		)
		(polygon
			(pts
				(arc
					(start 131.810506 -389.585962)
					(mid 131.922755 -389.721409)
					(end 132.091176 -389.772144)
				)
				(arc
					(start 132.091176 -389.772144)
					(mid 132.306702 -389.68287)
					(end 132.395976 -389.467344)
				)
				(arc
					(start 132.395976 -389.467344)
					(mid 132.386142 -389.390291)
					(end 132.357114 -389.318246)
				)
				(arc
					(start 131.978146 -388.671562)
					(mid 131.559633 -388.499187)
					(end 131.43103 -388.933182)
				)
			)
		)
	)
	(zone
		(layers "In1.Cu" "In3.Cu" "In5.Cu" "In7.Cu" "In8.Cu" "In9.Cu")
		(hatch none 0.5)
		(connect_pads
			(clearance 0)
		)
		(min_thickness 0.25)
		(keepout
			(tracks not_allowed)
			(vias allowed)
			(pads allowed)
			(copperpour not_allowed)
			(footprints allowed)
		)
		(placement
			(enabled no)
			(sheetname "")
		)
		(fill yes
			(thermal_gap 0.5)
			(thermal_bridge_width 0.5)
			(island_removal_mode 0)
		)
		(polygon
			(pts
				(arc
					(start 125.810518 -389.585962)
					(mid 125.922767 -389.721409)
					(end 126.091188 -389.772144)
				)
				(arc
					(start 126.091188 -389.772144)
					(mid 126.306714 -389.68287)
					(end 126.395988 -389.467344)
				)
				(arc
					(start 126.395988 -389.467344)
					(mid 126.386154 -389.390291)
					(end 126.357126 -389.318246)
				)
				(arc
					(start 125.978158 -388.671562)
					(mid 125.559645 -388.499187)
					(end 125.431042 -388.933182)
				)
			)
		)
	)
	(zone
		(layers "In1.Cu" "In3.Cu" "In5.Cu" "In7.Cu" "In8.Cu" "In9.Cu")
		(hatch none 0.5)
		(connect_pads
			(clearance 0)
		)
		(min_thickness 0.25)
		(keepout
			(tracks not_allowed)
			(vias allowed)
			(pads allowed)
			(copperpour not_allowed)
			(footprints allowed)
		)
		(placement
			(enabled no)
			(sheetname "")
		)
		(fill yes
			(thermal_gap 0.5)
			(thermal_bridge_width 0.5)
			(island_removal_mode 0)
		)
		(polygon
			(pts
				(arc
					(start 64.710564 -389.585962)
					(mid 64.822813 -389.721409)
					(end 64.991234 -389.772144)
				)
				(arc
					(start 64.991234 -389.772144)
					(mid 65.20676 -389.68287)
					(end 65.296034 -389.467344)
				)
				(arc
					(start 65.296034 -389.467344)
					(mid 65.2862 -389.390291)
					(end 65.257172 -389.318246)
				)
				(arc
					(start 64.878204 -388.671562)
					(mid 64.459691 -388.499187)
					(end 64.331088 -388.933182)
				)
			)
		)
	)
	(zone
		(layers "In1.Cu" "In3.Cu" "In5.Cu" "In7.Cu" "In8.Cu" "In9.Cu")
		(hatch none 0.5)
		(connect_pads
			(clearance 0)
		)
		(min_thickness 0.25)
		(keepout
			(tracks not_allowed)
			(vias allowed)
			(pads allowed)
			(copperpour not_allowed)
			(footprints allowed)
		)
		(placement
			(enabled no)
			(sheetname "")
		)
		(fill yes
			(thermal_gap 0.5)
			(thermal_bridge_width 0.5)
			(island_removal_mode 0)
		)
		(polygon
			(pts
				(arc
					(start 383.010664 -397.967962)
					(mid 383.122913 -398.103409)
					(end 383.291334 -398.154144)
				)
				(arc
					(start 383.291334 -398.154144)
					(mid 383.50686 -398.06487)
					(end 383.596134 -397.849344)
				)
				(arc
					(start 383.596134 -397.849344)
					(mid 383.5863 -397.772291)
					(end 383.557272 -397.700246)
				)
				(arc
					(start 383.178304 -397.053562)
					(mid 382.759791 -396.881187)
					(end 382.631188 -397.315182)
				)
			)
		)
	)
	(zone
		(layers "In1.Cu" "In3.Cu" "In5.Cu" "In7.Cu" "In8.Cu" "In9.Cu")
		(hatch none 0.5)
		(connect_pads
			(clearance 0)
		)
		(min_thickness 0.25)
		(keepout
			(tracks not_allowed)
			(vias allowed)
			(pads allowed)
			(copperpour not_allowed)
			(footprints allowed)
		)
		(placement
			(enabled no)
			(sheetname "")
		)
		(fill yes
			(thermal_gap 0.5)
			(thermal_bridge_width 0.5)
			(island_removal_mode 0)
		)
		(polygon
			(pts
				(arc
					(start 117.410484 -389.585962)
					(mid 117.522733 -389.721409)
					(end 117.691154 -389.772144)
				)
				(arc
					(start 117.691154 -389.772144)
					(mid 117.90668 -389.68287)
					(end 117.995954 -389.467344)
				)
				(arc
					(start 117.995954 -389.467344)
					(mid 117.98612 -389.390291)
					(end 117.957092 -389.318246)
				)
				(arc
					(start 117.578124 -388.671562)
					(mid 117.159611 -388.499187)
					(end 117.031008 -388.933182)
				)
			)
		)
	)
	(zone
		(layers "In1.Cu" "In3.Cu" "In5.Cu" "In7.Cu" "In8.Cu" "In9.Cu")
		(hatch none 0.5)
		(connect_pads
			(clearance 0)
		)
		(min_thickness 0.25)
		(keepout
			(tracks not_allowed)
			(vias allowed)
			(pads allowed)
			(copperpour not_allowed)
			(footprints allowed)
		)
		(placement
			(enabled no)
			(sheetname "")
		)
		(fill yes
			(thermal_gap 0.5)
			(thermal_bridge_width 0.5)
			(island_removal_mode 0)
		)
		(polygon
			(pts
				(arc
					(start 372.210584 -397.967962)
					(mid 372.322833 -398.103409)
					(end 372.491254 -398.154144)
				)
				(arc
					(start 372.491254 -398.154144)
					(mid 372.70678 -398.06487)
					(end 372.796054 -397.849344)
				)
				(arc
					(start 372.796054 -397.849344)
					(mid 372.78622 -397.772291)
					(end 372.757192 -397.700246)
				)
				(arc
					(start 372.378224 -397.053562)
					(mid 371.959711 -396.881187)
					(end 371.831108 -397.315182)
				)
			)
		)
	)
	(zone
		(layers "In1.Cu" "In3.Cu" "In5.Cu" "In7.Cu" "In8.Cu" "In9.Cu")
		(hatch none 0.5)
		(connect_pads
			(clearance 0)
		)
		(min_thickness 0.25)
		(keepout
			(tracks not_allowed)
			(vias allowed)
			(pads allowed)
			(copperpour not_allowed)
			(footprints allowed)
		)
		(placement
			(enabled no)
			(sheetname "")
		)
		(fill yes
			(thermal_gap 0.5)
			(thermal_bridge_width 0.5)
			(island_removal_mode 0)
		)
		(polygon
			(pts
				(arc
					(start 337.638136 -397.967962)
					(mid 337.750385 -398.103409)
					(end 337.918806 -398.154144)
				)
				(arc
					(start 337.918806 -398.154144)
					(mid 338.134332 -398.06487)
					(end 338.223606 -397.849344)
				)
				(arc
					(start 338.223606 -397.849344)
					(mid 338.213772 -397.772291)
					(end 338.184744 -397.700246)
				)
				(arc
					(start 337.805776 -397.053562)
					(mid 337.387263 -396.881187)
					(end 337.25866 -397.315182)
				)
			)
		)
	)
	(zone
		(layers "In1.Cu" "In3.Cu" "In5.Cu" "In7.Cu" "In8.Cu" "In9.Cu")
		(hatch none 0.5)
		(connect_pads
			(clearance 0)
		)
		(min_thickness 0.25)
		(keepout
			(tracks not_allowed)
			(vias allowed)
			(pads allowed)
			(copperpour not_allowed)
			(footprints allowed)
		)
		(placement
			(enabled no)
			(sheetname "")
		)
		(fill yes
			(thermal_gap 0.5)
			(thermal_bridge_width 0.5)
			(island_removal_mode 0)
		)
		(polygon
			(pts
				(arc
					(start 354.438204 -397.967962)
					(mid 354.550453 -398.103409)
					(end 354.718874 -398.154144)
				)
				(arc
					(start 354.718874 -398.154144)
					(mid 354.9344 -398.06487)
					(end 355.023674 -397.849344)
				)
				(arc
					(start 355.023674 -397.849344)
					(mid 355.01384 -397.772291)
					(end 354.984812 -397.700246)
				)
				(arc
					(start 354.605844 -397.053562)
					(mid 354.187331 -396.881187)
					(end 354.058728 -397.315182)
				)
			)
		)
	)
	(zone
		(layers "In1.Cu" "In3.Cu" "In5.Cu" "In7.Cu" "In8.Cu" "In9.Cu")
		(hatch none 0.5)
		(connect_pads
			(clearance 0)
		)
		(min_thickness 0.25)
		(keepout
			(tracks not_allowed)
			(vias allowed)
			(pads allowed)
			(copperpour not_allowed)
			(footprints allowed)
		)
		(placement
			(enabled no)
			(sheetname "")
		)
		(fill yes
			(thermal_gap 0.5)
			(thermal_bridge_width 0.5)
			(island_removal_mode 0)
		)
		(polygon
			(pts
				(arc
					(start 380.610618 -397.967962)
					(mid 380.722867 -398.103409)
					(end 380.891288 -398.154144)
				)
				(arc
					(start 380.891288 -398.154144)
					(mid 381.106814 -398.06487)
					(end 381.196088 -397.849344)
				)
				(arc
					(start 381.196088 -397.849344)
					(mid 381.186254 -397.772291)
					(end 381.157226 -397.700246)
				)
				(arc
					(start 380.778258 -397.053562)
					(mid 380.359745 -396.881187)
					(end 380.231142 -397.315182)
				)
			)
		)
	)
	(zone
		(layers "In1.Cu" "In3.Cu" "In5.Cu" "In7.Cu" "In8.Cu" "In9.Cu")
		(hatch none 0.5)
		(connect_pads
			(clearance 0)
		)
		(min_thickness 0.25)
		(keepout
			(tracks not_allowed)
			(vias allowed)
			(pads allowed)
			(copperpour not_allowed)
			(footprints allowed)
		)
		(placement
			(enabled no)
			(sheetname "")
		)
		(fill yes
			(thermal_gap 0.5)
			(thermal_bridge_width 0.5)
			(island_removal_mode 0)
		)
		(polygon
			(pts
				(arc
					(start 349.638112 -397.967962)
					(mid 349.750361 -398.103409)
					(end 349.918782 -398.154144)
				)
				(arc
					(start 349.918782 -398.154144)
					(mid 350.134308 -398.06487)
					(end 350.223582 -397.849344)
				)
				(arc
					(start 350.223582 -397.849344)
					(mid 350.213748 -397.772291)
					(end 350.18472 -397.700246)
				)
				(arc
					(start 349.805752 -397.053562)
					(mid 349.387239 -396.881187)
					(end 349.258636 -397.315182)
				)
			)
		)
	)
	(zone
		(layers "In1.Cu" "In3.Cu" "In5.Cu" "In7.Cu" "In8.Cu" "In9.Cu")
		(hatch none 0.5)
		(connect_pads
			(clearance 0)
		)
		(min_thickness 0.25)
		(keepout
			(tracks not_allowed)
			(vias allowed)
			(pads allowed)
			(copperpour not_allowed)
			(footprints allowed)
		)
		(placement
			(enabled no)
			(sheetname "")
		)
		(fill yes
			(thermal_gap 0.5)
			(thermal_bridge_width 0.5)
			(island_removal_mode 0)
		)
		(polygon
			(pts
				(arc
					(start 385.410456 -397.967962)
					(mid 385.522705 -398.103409)
					(end 385.691126 -398.154144)
				)
				(arc
					(start 385.691126 -398.154144)
					(mid 385.906652 -398.06487)
					(end 385.995926 -397.849344)
				)
				(arc
					(start 385.995926 -397.849344)
					(mid 385.986092 -397.772291)
					(end 385.957064 -397.700246)
				)
				(arc
					(start 385.578096 -397.053562)
					(mid 385.159583 -396.881187)
					(end 385.03098 -397.315182)
				)
			)
		)
	)
	(zone
		(layers "In1.Cu" "In3.Cu" "In5.Cu" "In7.Cu" "In8.Cu" "In9.Cu")
		(hatch none 0.5)
		(connect_pads
			(clearance 0)
		)
		(min_thickness 0.25)
		(keepout
			(tracks not_allowed)
			(vias allowed)
			(pads allowed)
			(copperpour not_allowed)
			(footprints allowed)
		)
		(placement
			(enabled no)
			(sheetname "")
		)
		(fill yes
			(thermal_gap 0.5)
			(thermal_bridge_width 0.5)
			(island_removal_mode 0)
		)
		(polygon
			(pts
				(arc
					(start 353.238054 -397.967962)
					(mid 353.350303 -398.103409)
					(end 353.518724 -398.154144)
				)
				(arc
					(start 353.518724 -398.154144)
					(mid 353.73425 -398.06487)
					(end 353.823524 -397.849344)
				)
				(arc
					(start 353.823524 -397.849344)
					(mid 353.81369 -397.772291)
					(end 353.784662 -397.700246)
				)
				(arc
					(start 353.405694 -397.053562)
					(mid 352.987181 -396.881187)
					(end 352.858578 -397.315182)
				)
			)
		)
	)
	(zone
		(layers "In1.Cu" "In3.Cu" "In5.Cu" "In7.Cu" "In8.Cu" "In9.Cu" "In10.Cu")
		(hatch none 0.5)
		(connect_pads
			(clearance 0)
		)
		(min_thickness 0.25)
		(keepout
			(tracks not_allowed)
			(vias allowed)
			(pads allowed)
			(copperpour not_allowed)
			(footprints allowed)
		)
		(placement
			(enabled no)
			(sheetname "")
		)
		(fill yes
			(thermal_gap 0.5)
			(thermal_bridge_width 0.5)
			(island_removal_mode 0)
		)
		(polygon
			(pts
				(arc
					(start 371.81155 -401.674838)
					(mid 372.11635 -401.979638)
					(end 372.42115 -401.674838)
				)
				(arc
					(start 372.42115 -400.811238)
					(mid 372.11635 -400.506438)
					(end 371.81155 -400.811238)
				)
			)
		)
	)
	(zone
		(layers "In1.Cu" "In3.Cu" "In5.Cu" "In7.Cu" "In8.Cu" "In9.Cu" "In10.Cu")
		(hatch none 0.5)
		(connect_pads
			(clearance 0)
		)
		(min_thickness 0.25)
		(keepout
			(tracks not_allowed)
			(vias allowed)
			(pads allowed)
			(copperpour not_allowed)
			(footprints allowed)
		)
		(placement
			(enabled no)
			(sheetname "")
		)
		(fill yes
			(thermal_gap 0.5)
			(thermal_bridge_width 0.5)
			(island_removal_mode 0)
		)
		(polygon
			(pts
				(arc
					(start 96.038416 -389.585962)
					(mid 96.150665 -389.721409)
					(end 96.319086 -389.772144)
				)
				(arc
					(start 96.319086 -389.772144)
					(mid 96.534612 -389.68287)
					(end 96.623886 -389.467344)
				)
				(arc
					(start 96.623886 -389.467344)
					(mid 96.614052 -389.390291)
					(end 96.585024 -389.318246)
				)
				(arc
					(start 96.206056 -388.671562)
					(mid 95.787543 -388.499187)
					(end 95.65894 -388.933182)
				)
			)
		)
	)
	(zone
		(layers "In1.Cu" "In3.Cu" "In5.Cu" "In7.Cu" "In8.Cu" "In9.Cu" "In10.Cu")
		(hatch none 0.5)
		(connect_pads
			(clearance 0)
		)
		(min_thickness 0.25)
		(keepout
			(tracks not_allowed)
			(vias allowed)
			(pads allowed)
			(copperpour not_allowed)
			(footprints allowed)
		)
		(placement
			(enabled no)
			(sheetname "")
		)
		(fill yes
			(thermal_gap 0.5)
			(thermal_bridge_width 0.5)
			(island_removal_mode 0)
		)
		(polygon
			(pts
				(arc
					(start 382.611884 -401.674838)
					(mid 382.916684 -401.979638)
					(end 383.221484 -401.674838)
				)
				(arc
					(start 383.221484 -400.811238)
					(mid 382.916684 -400.506438)
					(end 382.611884 -400.811238)
				)
			)
		)
	)
	(zone
		(layers "In1.Cu" "In3.Cu" "In5.Cu" "In7.Cu" "In8.Cu" "In9.Cu" "In10.Cu")
		(hatch none 0.5)
		(connect_pads
			(clearance 0)
		)
		(min_thickness 0.25)
		(keepout
			(tracks not_allowed)
			(vias allowed)
			(pads allowed)
			(copperpour not_allowed)
			(footprints allowed)
		)
		(placement
			(enabled no)
			(sheetname "")
		)
		(fill yes
			(thermal_gap 0.5)
			(thermal_bridge_width 0.5)
			(island_removal_mode 0)
		)
		(polygon
			(pts
				(arc
					(start 90.038428 -389.585962)
					(mid 90.150677 -389.721409)
					(end 90.319098 -389.772144)
				)
				(arc
					(start 90.319098 -389.772144)
					(mid 90.534624 -389.68287)
					(end 90.623898 -389.467344)
				)
				(arc
					(start 90.623898 -389.467344)
					(mid 90.614064 -389.390291)
					(end 90.585036 -389.318246)
				)
				(arc
					(start 90.206068 -388.671562)
					(mid 89.787555 -388.499187)
					(end 89.658952 -388.933182)
				)
			)
		)
	)
	(zone
		(layers "In1.Cu" "In3.Cu" "In5.Cu" "In7.Cu" "In8.Cu" "In9.Cu" "In10.Cu")
		(hatch none 0.5)
		(connect_pads
			(clearance 0)
		)
		(min_thickness 0.25)
		(keepout
			(tracks not_allowed)
			(vias allowed)
			(pads allowed)
			(copperpour not_allowed)
			(footprints allowed)
		)
		(placement
			(enabled no)
			(sheetname "")
		)
		(fill yes
			(thermal_gap 0.5)
			(thermal_bridge_width 0.5)
			(island_removal_mode 0)
		)
		(polygon
			(pts
				(arc
					(start 88.838278 -389.585962)
					(mid 88.950527 -389.721409)
					(end 89.118948 -389.772144)
				)
				(arc
					(start 89.118948 -389.772144)
					(mid 89.334474 -389.68287)
					(end 89.423748 -389.467344)
				)
				(arc
					(start 89.423748 -389.467344)
					(mid 89.413914 -389.390291)
					(end 89.384886 -389.318246)
				)
				(arc
					(start 89.005918 -388.671562)
					(mid 88.587405 -388.499187)
					(end 88.458802 -388.933182)
				)
			)
		)
	)
	(zone
		(layers "In1.Cu" "In3.Cu" "In5.Cu" "In7.Cu" "In8.Cu" "In9.Cu" "In10.Cu")
		(hatch none 0.5)
		(connect_pads
			(clearance 0)
		)
		(min_thickness 0.25)
		(keepout
			(tracks not_allowed)
			(vias allowed)
			(pads allowed)
			(copperpour not_allowed)
			(footprints allowed)
		)
		(placement
			(enabled no)
			(sheetname "")
		)
		(fill yes
			(thermal_gap 0.5)
			(thermal_bridge_width 0.5)
			(island_removal_mode 0)
		)
		(polygon
			(pts
				(arc
					(start 81.638394 -389.585962)
					(mid 81.750643 -389.721409)
					(end 81.919064 -389.772144)
				)
				(arc
					(start 81.919064 -389.772144)
					(mid 82.13459 -389.68287)
					(end 82.223864 -389.467344)
				)
				(arc
					(start 82.223864 -389.467344)
					(mid 82.21403 -389.390291)
					(end 82.185002 -389.318246)
				)
				(arc
					(start 81.806034 -388.671562)
					(mid 81.387521 -388.499187)
					(end 81.258918 -388.933182)
				)
			)
		)
	)
	(zone
		(layers "In1.Cu" "In3.Cu" "In5.Cu" "In7.Cu" "In8.Cu" "In9.Cu" "In10.Cu")
		(hatch none 0.5)
		(connect_pads
			(clearance 0)
		)
		(min_thickness 0.25)
		(keepout
			(tracks not_allowed)
			(vias allowed)
			(pads allowed)
			(copperpour not_allowed)
			(footprints allowed)
		)
		(placement
			(enabled no)
			(sheetname "")
		)
		(fill yes
			(thermal_gap 0.5)
			(thermal_bridge_width 0.5)
			(island_removal_mode 0)
		)
		(polygon
			(pts
				(arc
					(start 385.011676 -401.674838)
					(mid 385.316476 -401.979638)
					(end 385.621276 -401.674838)
				)
				(arc
					(start 385.621276 -400.811238)
					(mid 385.316476 -400.506438)
					(end 385.011676 -400.811238)
				)
			)
		)
	)
	(zone
		(layers "In1.Cu" "In3.Cu" "In5.Cu" "In7.Cu" "In8.Cu" "In9.Cu" "In10.Cu")
		(hatch none 0.5)
		(connect_pads
			(clearance 0)
		)
		(min_thickness 0.25)
		(keepout
			(tracks not_allowed)
			(vias allowed)
			(pads allowed)
			(copperpour not_allowed)
			(footprints allowed)
		)
		(placement
			(enabled no)
			(sheetname "")
		)
		(fill yes
			(thermal_gap 0.5)
			(thermal_bridge_width 0.5)
			(island_removal_mode 0)
		)
		(polygon
			(pts
				(arc
					(start 84.03844 -389.585962)
					(mid 84.150689 -389.721409)
					(end 84.31911 -389.772144)
				)
				(arc
					(start 84.31911 -389.772144)
					(mid 84.534636 -389.68287)
					(end 84.62391 -389.467344)
				)
				(arc
					(start 84.62391 -389.467344)
					(mid 84.614076 -389.390291)
					(end 84.585048 -389.318246)
				)
				(arc
					(start 84.20608 -388.671562)
					(mid 83.787567 -388.499187)
					(end 83.658964 -388.933182)
				)
			)
		)
	)
	(zone
		(layers "In1.Cu" "In3.Cu" "In5.Cu" "In7.Cu" "In8.Cu" "In9.Cu" "In10.Cu")
		(hatch none 0.5)
		(connect_pads
			(clearance 0)
		)
		(min_thickness 0.25)
		(keepout
			(tracks not_allowed)
			(vias allowed)
			(pads allowed)
			(copperpour not_allowed)
			(footprints allowed)
		)
		(placement
			(enabled no)
			(sheetname "")
		)
		(fill yes
			(thermal_gap 0.5)
			(thermal_bridge_width 0.5)
			(island_removal_mode 0)
		)
		(polygon
			(pts
				(arc
					(start 85.238336 -389.585962)
					(mid 85.350585 -389.721409)
					(end 85.519006 -389.772144)
				)
				(arc
					(start 85.519006 -389.772144)
					(mid 85.734532 -389.68287)
					(end 85.823806 -389.467344)
				)
				(arc
					(start 85.823806 -389.467344)
					(mid 85.813972 -389.390291)
					(end 85.784944 -389.318246)
				)
				(arc
					(start 85.405976 -388.671562)
					(mid 84.987463 -388.499187)
					(end 84.85886 -388.933182)
				)
			)
		)
	)
	(zone
		(layers "In1.Cu" "In3.Cu" "In5.Cu" "In7.Cu" "In8.Cu" "In9.Cu" "In10.Cu")
		(hatch none 0.5)
		(connect_pads
			(clearance 0)
		)
		(min_thickness 0.25)
		(keepout
			(tracks not_allowed)
			(vias allowed)
			(pads allowed)
			(copperpour not_allowed)
			(footprints allowed)
		)
		(placement
			(enabled no)
			(sheetname "")
		)
		(fill yes
			(thermal_gap 0.5)
			(thermal_bridge_width 0.5)
			(island_removal_mode 0)
		)
		(polygon
			(pts
				(arc
					(start 381.411734 -401.674838)
					(mid 381.716534 -401.979638)
					(end 382.021334 -401.674838)
				)
				(arc
					(start 382.021334 -400.811238)
					(mid 381.716534 -400.506438)
					(end 381.411734 -400.811238)
				)
			)
		)
	)
	(zone
		(layers "In1.Cu" "In3.Cu" "In5.Cu" "In7.Cu" "In8.Cu" "In9.Cu" "In10.Cu")
		(hatch none 0.5)
		(connect_pads
			(clearance 0)
		)
		(min_thickness 0.25)
		(keepout
			(tracks not_allowed)
			(vias allowed)
			(pads allowed)
			(copperpour not_allowed)
			(footprints allowed)
		)
		(placement
			(enabled no)
			(sheetname "")
		)
		(fill yes
			(thermal_gap 0.5)
			(thermal_bridge_width 0.5)
			(island_removal_mode 0)
		)
		(polygon
			(pts
				(arc
					(start 344.863928 -394.552424)
					(mid 344.973899 -394.653478)
					(end 345.11869 -394.690092)
				)
				(arc
					(start 345.11869 -394.690092)
					(mid 345.334216 -394.600818)
					(end 345.42349 -394.385292)
				)
				(arc
					(start 345.42349 -394.385292)
					(mid 345.413153 -394.306553)
					(end 345.38285 -394.233146)
				)
				(arc
					(start 344.99042 -393.554204)
					(mid 344.878023 -393.432587)
					(end 344.71864 -393.38758)
				)
				(arc
					(start 344.71864 -393.38758)
					(mid 344.503114 -393.476854)
					(end 344.41384 -393.69238)
				)
				(arc
					(start 344.41384 -393.69238)
					(mid 344.423418 -393.768442)
					(end 344.451686 -393.8397)
				)
				(xy 344.848942 -394.527024) (xy 344.861134 -394.54836) (xy 344.863674 -394.552678)
			)
		)
	)
	(zone
		(layers "In1.Cu" "In3.Cu" "In5.Cu" "In7.Cu" "In8.Cu" "In9.Cu" "In10.Cu")
		(hatch none 0.5)
		(connect_pads
			(clearance 0)
		)
		(min_thickness 0.25)
		(keepout
			(tracks not_allowed)
			(vias allowed)
			(pads allowed)
			(copperpour not_allowed)
			(footprints allowed)
		)
		(placement
			(enabled no)
			(sheetname "")
		)
		(fill yes
			(thermal_gap 0.5)
			(thermal_bridge_width 0.5)
			(island_removal_mode 0)
		)
		(polygon
			(pts
				(arc
					(start 346.839286 -401.674838)
					(mid 347.144086 -401.979638)
					(end 347.448886 -401.674838)
				)
				(arc
					(start 347.448886 -400.811238)
					(mid 347.144086 -400.506438)
					(end 346.839286 -400.811238)
				)
			)
		)
	)
	(zone
		(layers "In1.Cu" "In3.Cu" "In5.Cu" "In7.Cu" "In8.Cu" "In9.Cu" "In10.Cu")
		(hatch none 0.5)
		(connect_pads
			(clearance 0)
		)
		(min_thickness 0.25)
		(keepout
			(tracks not_allowed)
			(vias allowed)
			(pads allowed)
			(copperpour not_allowed)
			(footprints allowed)
		)
		(placement
			(enabled no)
			(sheetname "")
		)
		(fill yes
			(thermal_gap 0.5)
			(thermal_bridge_width 0.5)
			(island_removal_mode 0)
		)
		(polygon
			(pts
				(arc
					(start 351.639124 -401.674838)
					(mid 351.943924 -401.979638)
					(end 352.248724 -401.674838)
				)
				(arc
					(start 352.248724 -400.811238)
					(mid 351.943924 -400.506438)
					(end 351.639124 -400.811238)
				)
			)
		)
	)
	(zone
		(layers "In1.Cu" "In3.Cu" "In5.Cu" "In7.Cu" "In8.Cu" "In9.Cu" "In10.Cu")
		(hatch none 0.5)
		(connect_pads
			(clearance 0)
		)
		(min_thickness 0.25)
		(keepout
			(tracks not_allowed)
			(vias allowed)
			(pads allowed)
			(copperpour not_allowed)
			(footprints allowed)
		)
		(placement
			(enabled no)
			(sheetname "")
		)
		(fill yes
			(thermal_gap 0.5)
			(thermal_bridge_width 0.5)
			(island_removal_mode 0)
		)
		(polygon
			(pts
				(arc
					(start 348.039436 -401.674838)
					(mid 348.344236 -401.979638)
					(end 348.649036 -401.674838)
				)
				(arc
					(start 348.649036 -400.811238)
					(mid 348.344236 -400.506438)
					(end 348.039436 -400.811238)
				)
			)
		)
	)
	(zone
		(layers "In1.Cu" "In3.Cu" "In5.Cu" "In7.Cu" "In8.Cu" "In9.Cu" "In10.Cu")
		(hatch none 0.5)
		(connect_pads
			(clearance 0)
		)
		(min_thickness 0.25)
		(keepout
			(tracks not_allowed)
			(vias allowed)
			(pads allowed)
			(copperpour not_allowed)
			(footprints allowed)
		)
		(placement
			(enabled no)
			(sheetname "")
		)
		(fill yes
			(thermal_gap 0.5)
			(thermal_bridge_width 0.5)
			(island_removal_mode 0)
		)
		(polygon
			(pts
				(arc
					(start 340.839298 -401.674838)
					(mid 341.144098 -401.979638)
					(end 341.448898 -401.674838)
				)
				(arc
					(start 341.448898 -400.811238)
					(mid 341.144098 -400.506438)
					(end 340.839298 -400.811238)
				)
			)
		)
	)
	(zone
		(layers "In1.Cu" "In3.Cu" "In5.Cu" "In7.Cu" "In8.Cu" "In9.Cu" "In10.Cu")
		(hatch none 0.5)
		(connect_pads
			(clearance 0)
		)
		(min_thickness 0.25)
		(keepout
			(tracks not_allowed)
			(vias allowed)
			(pads allowed)
			(copperpour not_allowed)
			(footprints allowed)
		)
		(placement
			(enabled no)
			(sheetname "")
		)
		(fill yes
			(thermal_gap 0.5)
			(thermal_bridge_width 0.5)
			(island_removal_mode 0)
		)
		(polygon
			(pts
				(arc
					(start 98.438462 -389.585962)
					(mid 98.550711 -389.721409)
					(end 98.719132 -389.772144)
				)
				(arc
					(start 98.719132 -389.772144)
					(mid 98.934658 -389.68287)
					(end 99.023932 -389.467344)
				)
				(arc
					(start 99.023932 -389.467344)
					(mid 99.014098 -389.390291)
					(end 98.98507 -389.318246)
				)
				(arc
					(start 98.606102 -388.671562)
					(mid 98.187589 -388.499187)
					(end 98.058986 -388.933182)
				)
			)
		)
	)
	(zone
		(layers "In1.Cu" "In3.Cu" "In5.Cu" "In7.Cu" "In8.Cu" "In9.Cu" "In10.Cu")
		(hatch none 0.5)
		(connect_pads
			(clearance 0)
		)
		(min_thickness 0.25)
		(keepout
			(tracks not_allowed)
			(vias allowed)
			(pads allowed)
			(copperpour not_allowed)
			(footprints allowed)
		)
		(placement
			(enabled no)
			(sheetname "")
		)
		(fill yes
			(thermal_gap 0.5)
			(thermal_bridge_width 0.5)
			(island_removal_mode 0)
		)
		(polygon
			(pts
				(arc
					(start 92.438474 -389.585962)
					(mid 92.550723 -389.721409)
					(end 92.719144 -389.772144)
				)
				(arc
					(start 92.719144 -389.772144)
					(mid 92.93467 -389.68287)
					(end 93.023944 -389.467344)
				)
				(arc
					(start 93.023944 -389.467344)
					(mid 93.01411 -389.390291)
					(end 92.985082 -389.318246)
				)
				(arc
					(start 92.606114 -388.671562)
					(mid 92.187601 -388.499187)
					(end 92.058998 -388.933182)
				)
			)
		)
	)
	(zone
		(layers "In1.Cu" "In3.Cu" "In5.Cu" "In7.Cu" "In8.Cu" "In9.Cu" "In10.Cu")
		(hatch none 0.5)
		(connect_pads
			(clearance 0)
		)
		(min_thickness 0.25)
		(keepout
			(tracks not_allowed)
			(vias allowed)
			(pads allowed)
			(copperpour not_allowed)
			(footprints allowed)
		)
		(placement
			(enabled no)
			(sheetname "")
		)
		(fill yes
			(thermal_gap 0.5)
			(thermal_bridge_width 0.5)
			(island_removal_mode 0)
		)
		(polygon
			(pts
				(arc
					(start 132.611622 -393.292838)
					(mid 132.916422 -393.597638)
					(end 133.221222 -393.292838)
				)
				(arc
					(start 133.221222 -392.429238)
					(mid 132.916422 -392.124438)
					(end 132.611622 -392.429238)
				)
			)
		)
	)
	(zone
		(layers "In1.Cu" "In3.Cu" "In5.Cu" "In7.Cu" "In8.Cu" "In9.Cu" "In10.Cu")
		(hatch none 0.5)
		(connect_pads
			(clearance 0)
		)
		(min_thickness 0.25)
		(keepout
			(tracks not_allowed)
			(vias allowed)
			(pads allowed)
			(copperpour not_allowed)
			(footprints allowed)
		)
		(placement
			(enabled no)
			(sheetname "")
		)
		(fill yes
			(thermal_gap 0.5)
			(thermal_bridge_width 0.5)
			(island_removal_mode 0)
		)
		(polygon
			(pts
				(arc
					(start 93.63837 -389.585962)
					(mid 93.750619 -389.721409)
					(end 93.91904 -389.772144)
				)
				(arc
					(start 93.91904 -389.772144)
					(mid 94.134566 -389.68287)
					(end 94.22384 -389.467344)
				)
				(arc
					(start 94.22384 -389.467344)
					(mid 94.214006 -389.390291)
					(end 94.184978 -389.318246)
				)
				(arc
					(start 93.80601 -388.671562)
					(mid 93.387497 -388.499187)
					(end 93.258894 -388.933182)
				)
			)
		)
	)
	(zone
		(layers "In1.Cu" "In3.Cu" "In5.Cu" "In7.Cu" "In8.Cu" "In9.Cu" "In10.Cu")
		(hatch none 0.5)
		(connect_pads
			(clearance 0)
		)
		(min_thickness 0.25)
		(keepout
			(tracks not_allowed)
			(vias allowed)
			(pads allowed)
			(copperpour not_allowed)
			(footprints allowed)
		)
		(placement
			(enabled no)
			(sheetname "")
		)
		(fill yes
			(thermal_gap 0.5)
			(thermal_bridge_width 0.5)
			(island_removal_mode 0)
		)
		(polygon
			(pts
				(arc
					(start 342.039194 -401.674838)
					(mid 342.343994 -401.979638)
					(end 342.648794 -401.674838)
				)
				(arc
					(start 342.648794 -400.811238)
					(mid 342.343994 -400.506438)
					(end 342.039194 -400.811238)
				)
			)
		)
	)
	(zone
		(layers "In1.Cu" "In3.Cu" "In5.Cu" "In7.Cu" "In8.Cu" "In9.Cu" "In10.Cu")
		(hatch none 0.5)
		(connect_pads
			(clearance 0)
		)
		(min_thickness 0.25)
		(keepout
			(tracks not_allowed)
			(vias allowed)
			(pads allowed)
			(copperpour not_allowed)
			(footprints allowed)
		)
		(placement
			(enabled no)
			(sheetname "")
		)
		(fill yes
			(thermal_gap 0.5)
			(thermal_bridge_width 0.5)
			(island_removal_mode 0)
		)
		(polygon
			(pts
				(arc
					(start 373.0117 -401.674838)
					(mid 373.3165 -401.979638)
					(end 373.6213 -401.674838)
				)
				(arc
					(start 373.6213 -400.811238)
					(mid 373.3165 -400.506438)
					(end 373.0117 -400.811238)
				)
			)
		)
	)
	(zone
		(layers "In1.Cu" "In3.Cu" "In5.Cu" "In7.Cu" "In8.Cu" "In9.Cu" "In10.Cu")
		(hatch none 0.5)
		(connect_pads
			(clearance 0)
		)
		(min_thickness 0.25)
		(keepout
			(tracks not_allowed)
			(vias allowed)
			(pads allowed)
			(copperpour not_allowed)
			(footprints allowed)
		)
		(placement
			(enabled no)
			(sheetname "")
		)
		(fill yes
			(thermal_gap 0.5)
			(thermal_bridge_width 0.5)
			(island_removal_mode 0)
		)
		(polygon
			(pts
				(arc
					(start 118.2116 -393.292838)
					(mid 118.5164 -393.597638)
					(end 118.8212 -393.292838)
				)
				(arc
					(start 118.8212 -392.429238)
					(mid 118.5164 -392.124438)
					(end 118.2116 -392.429238)
				)
			)
		)
	)
	(zone
		(layers "In1.Cu" "In3.Cu" "In5.Cu" "In7.Cu" "In8.Cu" "In9.Cu" "In10.Cu")
		(hatch none 0.5)
		(connect_pads
			(clearance 0)
		)
		(min_thickness 0.25)
		(keepout
			(tracks not_allowed)
			(vias allowed)
			(pads allowed)
			(copperpour not_allowed)
			(footprints allowed)
		)
		(placement
			(enabled no)
			(sheetname "")
		)
		(fill yes
			(thermal_gap 0.5)
			(thermal_bridge_width 0.5)
			(island_removal_mode 0)
		)
		(polygon
			(pts
				(arc
					(start 379.011688 -401.674838)
					(mid 379.316488 -401.979638)
					(end 379.621288 -401.674838)
				)
				(arc
					(start 379.621288 -400.811238)
					(mid 379.316488 -400.506438)
					(end 379.011688 -400.811238)
				)
			)
		)
	)
	(zone
		(layers "In1.Cu" "In3.Cu" "In5.Cu" "In7.Cu" "In8.Cu" "In9.Cu" "In10.Cu")
		(hatch none 0.5)
		(connect_pads
			(clearance 0)
		)
		(min_thickness 0.25)
		(keepout
			(tracks not_allowed)
			(vias allowed)
			(pads allowed)
			(copperpour not_allowed)
			(footprints allowed)
		)
		(placement
			(enabled no)
			(sheetname "")
		)
		(fill yes
			(thermal_gap 0.5)
			(thermal_bridge_width 0.5)
			(island_removal_mode 0)
		)
		(polygon
			(pts
				(arc
					(start 350.439228 -401.674838)
					(mid 350.744028 -401.979638)
					(end 351.048828 -401.674838)
				)
				(arc
					(start 351.048828 -400.811238)
					(mid 350.744028 -400.506438)
					(end 350.439228 -400.811238)
				)
			)
		)
	)
	(zone
		(layers "In1.Cu" "In3.Cu" "In5.Cu" "In7.Cu" "In8.Cu" "In9.Cu" "In10.Cu")
		(hatch none 0.5)
		(connect_pads
			(clearance 0)
		)
		(min_thickness 0.25)
		(keepout
			(tracks not_allowed)
			(vias allowed)
			(pads allowed)
			(copperpour not_allowed)
			(footprints allowed)
		)
		(placement
			(enabled no)
			(sheetname "")
		)
		(fill yes
			(thermal_gap 0.5)
			(thermal_bridge_width 0.5)
			(island_removal_mode 0)
		)
		(polygon
			(pts
				(arc
					(start 117.011704 -393.292838)
					(mid 117.316504 -393.597638)
					(end 117.621304 -393.292838)
				)
				(arc
					(start 117.621304 -392.429238)
					(mid 117.316504 -392.124438)
					(end 117.011704 -392.429238)
				)
			)
		)
	)
	(zone
		(layers "In1.Cu" "In3.Cu" "In5.Cu" "In7.Cu" "In8.Cu" "In9.Cu" "In10.Cu")
		(hatch none 0.5)
		(connect_pads
			(clearance 0)
		)
		(min_thickness 0.25)
		(keepout
			(tracks not_allowed)
			(vias allowed)
			(pads allowed)
			(copperpour not_allowed)
			(footprints allowed)
		)
		(placement
			(enabled no)
			(sheetname "")
		)
		(fill yes
			(thermal_gap 0.5)
			(thermal_bridge_width 0.5)
			(island_removal_mode 0)
		)
		(polygon
			(pts
				(arc
					(start 386.211572 -401.674838)
					(mid 386.516372 -401.979638)
					(end 386.821172 -401.674838)
				)
				(arc
					(start 386.821172 -400.811238)
					(mid 386.516372 -400.506438)
					(end 386.211572 -400.811238)
				)
			)
		)
	)
	(zone
		(layers "In1.Cu" "In3.Cu" "In5.Cu" "In7.Cu" "In8.Cu" "In9.Cu" "In10.Cu")
		(hatch none 0.5)
		(connect_pads
			(clearance 0)
		)
		(min_thickness 0.25)
		(keepout
			(tracks not_allowed)
			(vias allowed)
			(pads allowed)
			(copperpour not_allowed)
			(footprints allowed)
		)
		(placement
			(enabled no)
			(sheetname "")
		)
		(fill yes
			(thermal_gap 0.5)
			(thermal_bridge_width 0.5)
			(island_removal_mode 0)
		)
		(polygon
			(pts
				(arc
					(start 374.211596 -401.674838)
					(mid 374.516396 -401.979638)
					(end 374.821196 -401.674838)
				)
				(arc
					(start 374.821196 -400.811238)
					(mid 374.516396 -400.506438)
					(end 374.211596 -400.811238)
				)
			)
		)
	)
	(zone
		(layers "In1.Cu" "In3.Cu" "In5.Cu" "In7.Cu" "In8.Cu" "In9.Cu" "In10.Cu")
		(hatch none 0.5)
		(connect_pads
			(clearance 0)
		)
		(min_thickness 0.25)
		(keepout
			(tracks not_allowed)
			(vias allowed)
			(pads allowed)
			(copperpour not_allowed)
			(footprints allowed)
		)
		(placement
			(enabled no)
			(sheetname "")
		)
		(fill yes
			(thermal_gap 0.5)
			(thermal_bridge_width 0.5)
			(island_removal_mode 0)
		)
		(polygon
			(pts
				(arc
					(start 337.239102 -401.674838)
					(mid 337.543902 -401.979638)
					(end 337.848702 -401.674838)
				)
				(arc
					(start 337.848702 -400.811238)
					(mid 337.543902 -400.506438)
					(end 337.239102 -400.811238)
				)
			)
		)
	)
	(zone
		(layers "In1.Cu" "In3.Cu" "In5.Cu" "In7.Cu" "In8.Cu" "In9.Cu" "In10.Cu")
		(hatch none 0.5)
		(connect_pads
			(clearance 0)
		)
		(min_thickness 0.25)
		(keepout
			(tracks not_allowed)
			(vias allowed)
			(pads allowed)
			(copperpour not_allowed)
			(footprints allowed)
		)
		(placement
			(enabled no)
			(sheetname "")
		)
		(fill yes
			(thermal_gap 0.5)
			(thermal_bridge_width 0.5)
			(island_removal_mode 0)
		)
		(polygon
			(pts
				(arc
					(start 336.039206 -401.674838)
					(mid 336.344006 -401.979638)
					(end 336.648806 -401.674838)
				)
				(arc
					(start 336.648806 -400.811238)
					(mid 336.344006 -400.506438)
					(end 336.039206 -400.811238)
				)
			)
		)
	)
	(zone
		(layers "In1.Cu" "In3.Cu" "In5.Cu" "In7.Cu" "In8.Cu" "In9.Cu" "In10.Cu")
		(hatch none 0.5)
		(connect_pads
			(clearance 0)
		)
		(min_thickness 0.25)
		(keepout
			(tracks not_allowed)
			(vias allowed)
			(pads allowed)
			(copperpour not_allowed)
			(footprints allowed)
		)
		(placement
			(enabled no)
			(sheetname "")
		)
		(fill yes
			(thermal_gap 0.5)
			(thermal_bridge_width 0.5)
			(island_removal_mode 0)
		)
		(polygon
			(pts
				(arc
					(start 120.611646 -393.292838)
					(mid 120.916446 -393.597638)
					(end 121.221246 -393.292838)
				)
				(arc
					(start 121.221246 -392.429238)
					(mid 120.916446 -392.124438)
					(end 120.611646 -392.429238)
				)
			)
		)
	)
	(zone
		(layers "In1.Cu" "In3.Cu" "In5.Cu" "In7.Cu" "In8.Cu" "In9.Cu" "In10.Cu")
		(hatch none 0.5)
		(connect_pads
			(clearance 0)
		)
		(min_thickness 0.25)
		(keepout
			(tracks not_allowed)
			(vias allowed)
			(pads allowed)
			(copperpour not_allowed)
			(footprints allowed)
		)
		(placement
			(enabled no)
			(sheetname "")
		)
		(fill yes
			(thermal_gap 0.5)
			(thermal_bridge_width 0.5)
			(island_removal_mode 0)
		)
		(polygon
			(pts
				(arc
					(start 80.438498 -389.585962)
					(mid 80.550747 -389.721409)
					(end 80.719168 -389.772144)
				)
				(arc
					(start 80.719168 -389.772144)
					(mid 80.934694 -389.68287)
					(end 81.023968 -389.467344)
				)
				(arc
					(start 81.023968 -389.467344)
					(mid 81.014134 -389.390291)
					(end 80.985106 -389.318246)
				)
				(arc
					(start 80.606138 -388.671562)
					(mid 80.187625 -388.499187)
					(end 80.059022 -388.933182)
				)
			)
		)
	)
	(zone
		(layers "In1.Cu" "In3.Cu" "In5.Cu" "In7.Cu" "In8.Cu" "In9.Cu" "In10.Cu")
		(hatch none 0.5)
		(connect_pads
			(clearance 0)
		)
		(min_thickness 0.25)
		(keepout
			(tracks not_allowed)
			(vias allowed)
			(pads allowed)
			(copperpour not_allowed)
			(footprints allowed)
		)
		(placement
			(enabled no)
			(sheetname "")
		)
		(fill yes
			(thermal_gap 0.5)
			(thermal_bridge_width 0.5)
			(island_removal_mode 0)
		)
		(polygon
			(pts
				(arc
					(start 338.86394 -394.552424)
					(mid 338.973911 -394.653478)
					(end 339.118702 -394.690092)
				)
				(arc
					(start 339.118702 -394.690092)
					(mid 339.334228 -394.600818)
					(end 339.423502 -394.385292)
				)
				(arc
					(start 339.423502 -394.385292)
					(mid 339.413165 -394.306553)
					(end 339.382862 -394.233146)
				)
				(arc
					(start 338.990432 -393.554204)
					(mid 338.878035 -393.432587)
					(end 338.718652 -393.38758)
				)
				(arc
					(start 338.718652 -393.38758)
					(mid 338.503126 -393.476854)
					(end 338.413852 -393.69238)
				)
				(arc
					(start 338.413852 -393.69238)
					(mid 338.42343 -393.768442)
					(end 338.451698 -393.8397)
				)
				(xy 338.848954 -394.527024) (xy 338.861146 -394.54836) (xy 338.863686 -394.552678)
			)
		)
	)
	(zone
		(layers "In1.Cu" "In3.Cu" "In5.Cu" "In7.Cu" "In8.Cu" "In9.Cu" "In10.Cu")
		(hatch none 0.5)
		(connect_pads
			(clearance 0)
		)
		(min_thickness 0.25)
		(keepout
			(tracks not_allowed)
			(vias allowed)
			(pads allowed)
			(copperpour not_allowed)
			(footprints allowed)
		)
		(placement
			(enabled no)
			(sheetname "")
		)
		(fill yes
			(thermal_gap 0.5)
			(thermal_bridge_width 0.5)
			(island_removal_mode 0)
		)
		(polygon
			(pts
				(arc
					(start 354.03917 -401.674838)
					(mid 354.34397 -401.979638)
					(end 354.64877 -401.674838)
				)
				(arc
					(start 354.64877 -400.811238)
					(mid 354.34397 -400.506438)
					(end 354.03917 -400.811238)
				)
			)
		)
	)
	(zone
		(layers "In1.Cu" "In3.Cu" "In5.Cu" "In7.Cu" "In8.Cu" "In9.Cu" "In10.Cu")
		(hatch none 0.5)
		(connect_pads
			(clearance 0)
		)
		(min_thickness 0.25)
		(keepout
			(tracks not_allowed)
			(vias allowed)
			(pads allowed)
			(copperpour not_allowed)
			(footprints allowed)
		)
		(placement
			(enabled no)
			(sheetname "")
		)
		(fill yes
			(thermal_gap 0.5)
			(thermal_bridge_width 0.5)
			(island_removal_mode 0)
		)
		(polygon
			(pts
				(arc
					(start 380.211838 -401.674838)
					(mid 380.516638 -401.979638)
					(end 380.821438 -401.674838)
				)
				(arc
					(start 380.821438 -400.811238)
					(mid 380.516638 -400.506438)
					(end 380.211838 -400.811238)
				)
			)
		)
	)
	(zone
		(layers "In1.Cu" "In3.Cu" "In5.Cu" "In7.Cu" "In8.Cu" "In9.Cu" "In10.Cu")
		(hatch none 0.5)
		(connect_pads
			(clearance 0)
		)
		(min_thickness 0.25)
		(keepout
			(tracks not_allowed)
			(vias allowed)
			(pads allowed)
			(copperpour not_allowed)
			(footprints allowed)
		)
		(placement
			(enabled no)
			(sheetname "")
		)
		(fill yes
			(thermal_gap 0.5)
			(thermal_bridge_width 0.5)
			(island_removal_mode 0)
		)
		(polygon
			(pts
				(arc
					(start 375.411746 -401.674838)
					(mid 375.716546 -401.979638)
					(end 376.021346 -401.674838)
				)
				(arc
					(start 376.021346 -400.811238)
					(mid 375.716546 -400.506438)
					(end 375.411746 -400.811238)
				)
			)
		)
	)
	(zone
		(layers "In1.Cu" "In3.Cu" "In5.Cu" "In7.Cu" "In8.Cu" "In9.Cu" "In10.Cu")
		(hatch none 0.5)
		(connect_pads
			(clearance 0)
		)
		(min_thickness 0.25)
		(keepout
			(tracks not_allowed)
			(vias allowed)
			(pads allowed)
			(copperpour not_allowed)
			(footprints allowed)
		)
		(placement
			(enabled no)
			(sheetname "")
		)
		(fill yes
			(thermal_gap 0.5)
			(thermal_bridge_width 0.5)
			(island_removal_mode 0)
		)
		(polygon
			(pts
				(arc
					(start 115.811554 -393.292838)
					(mid 116.116354 -393.597638)
					(end 116.421154 -393.292838)
				)
				(arc
					(start 116.421154 -392.429238)
					(mid 116.116354 -392.124438)
					(end 115.811554 -392.429238)
				)
			)
		)
	)
	(zone
		(layers "In1.Cu" "In3.Cu" "In5.Cu" "In7.Cu" "In8.Cu" "In9.Cu" "In10.Cu")
		(hatch none 0.5)
		(connect_pads
			(clearance 0)
		)
		(min_thickness 0.25)
		(keepout
			(tracks not_allowed)
			(vias allowed)
			(pads allowed)
			(copperpour not_allowed)
			(footprints allowed)
		)
		(placement
			(enabled no)
			(sheetname "")
		)
		(fill yes
			(thermal_gap 0.5)
			(thermal_bridge_width 0.5)
			(island_removal_mode 0)
		)
		(polygon
			(pts
				(arc
					(start 114.611658 -393.292838)
					(mid 114.916458 -393.597638)
					(end 115.221258 -393.292838)
				)
				(arc
					(start 115.221258 -392.429238)
					(mid 114.916458 -392.124438)
					(end 114.611658 -392.429238)
				)
			)
		)
	)
	(zone
		(layers "In1.Cu" "In3.Cu" "In5.Cu" "In7.Cu" "In8.Cu" "In9.Cu" "In10.Cu")
		(hatch none 0.5)
		(connect_pads
			(clearance 0)
		)
		(min_thickness 0.25)
		(keepout
			(tracks not_allowed)
			(vias allowed)
			(pads allowed)
			(copperpour not_allowed)
			(footprints allowed)
		)
		(placement
			(enabled no)
			(sheetname "")
		)
		(fill yes
			(thermal_gap 0.5)
			(thermal_bridge_width 0.5)
			(island_removal_mode 0)
		)
		(polygon
			(pts
				(arc
					(start 97.238312 -389.585962)
					(mid 97.350561 -389.721409)
					(end 97.518982 -389.772144)
				)
				(arc
					(start 97.518982 -389.772144)
					(mid 97.734508 -389.68287)
					(end 97.823782 -389.467344)
				)
				(arc
					(start 97.823782 -389.467344)
					(mid 97.813948 -389.390291)
					(end 97.78492 -389.318246)
				)
				(arc
					(start 97.405952 -388.671562)
					(mid 96.987439 -388.499187)
					(end 96.858836 -388.933182)
				)
			)
		)
	)
	(zone
		(layers "In1.Cu" "In3.Cu" "In5.Cu" "In7.Cu" "In8.Cu" "In9.Cu" "In10.Cu")
		(hatch none 0.5)
		(connect_pads
			(clearance 0)
		)
		(min_thickness 0.25)
		(keepout
			(tracks not_allowed)
			(vias allowed)
			(pads allowed)
			(copperpour not_allowed)
			(footprints allowed)
		)
		(placement
			(enabled no)
			(sheetname "")
		)
		(fill yes
			(thermal_gap 0.5)
			(thermal_bridge_width 0.5)
			(island_removal_mode 0)
		)
		(polygon
			(pts
				(arc
					(start 127.811784 -393.292838)
					(mid 128.116584 -393.597638)
					(end 128.421384 -393.292838)
				)
				(arc
					(start 128.421384 -392.429238)
					(mid 128.116584 -392.124438)
					(end 127.811784 -392.429238)
				)
			)
		)
	)
	(zone
		(layers "In1.Cu" "In3.Cu" "In5.Cu" "In7.Cu" "In8.Cu" "In9.Cu" "In10.Cu")
		(hatch none 0.5)
		(connect_pads
			(clearance 0)
		)
		(min_thickness 0.25)
		(keepout
			(tracks not_allowed)
			(vias allowed)
			(pads allowed)
			(copperpour not_allowed)
			(footprints allowed)
		)
		(placement
			(enabled no)
			(sheetname "")
		)
		(fill yes
			(thermal_gap 0.5)
			(thermal_bridge_width 0.5)
			(island_removal_mode 0)
		)
		(polygon
			(pts
				(arc
					(start 91.238324 -389.585962)
					(mid 91.350573 -389.721409)
					(end 91.518994 -389.772144)
				)
				(arc
					(start 91.518994 -389.772144)
					(mid 91.73452 -389.68287)
					(end 91.823794 -389.467344)
				)
				(arc
					(start 91.823794 -389.467344)
					(mid 91.81396 -389.390291)
					(end 91.784932 -389.318246)
				)
				(arc
					(start 91.405964 -388.671562)
					(mid 90.987451 -388.499187)
					(end 90.858848 -388.933182)
				)
			)
		)
	)
	(zone
		(layers "In1.Cu" "In3.Cu" "In5.Cu" "In7.Cu" "In8.Cu" "In9.Cu" "In10.Cu")
		(hatch none 0.5)
		(connect_pads
			(clearance 0)
		)
		(min_thickness 0.25)
		(keepout
			(tracks not_allowed)
			(vias allowed)
			(pads allowed)
			(copperpour not_allowed)
			(footprints allowed)
		)
		(placement
			(enabled no)
			(sheetname "")
		)
		(fill yes
			(thermal_gap 0.5)
			(thermal_bridge_width 0.5)
			(island_removal_mode 0)
		)
		(polygon
			(pts
				(arc
					(start 376.611642 -401.674838)
					(mid 376.916442 -401.979638)
					(end 377.221242 -401.674838)
				)
				(arc
					(start 377.221242 -400.811238)
					(mid 376.916442 -400.506438)
					(end 376.611642 -400.811238)
				)
			)
		)
	)
	(zone
		(layers "In1.Cu" "In3.Cu" "In5.Cu" "In7.Cu" "In8.Cu" "In9.Cu" "In10.Cu")
		(hatch none 0.5)
		(connect_pads
			(clearance 0)
		)
		(min_thickness 0.25)
		(keepout
			(tracks not_allowed)
			(vias allowed)
			(pads allowed)
			(copperpour not_allowed)
			(footprints allowed)
		)
		(placement
			(enabled no)
			(sheetname "")
		)
		(fill yes
			(thermal_gap 0.5)
			(thermal_bridge_width 0.5)
			(island_removal_mode 0)
		)
		(polygon
			(pts
				(arc
					(start 344.43924 -401.674838)
					(mid 344.74404 -401.979638)
					(end 345.04884 -401.674838)
				)
				(arc
					(start 345.04884 -400.811238)
					(mid 344.74404 -400.506438)
					(end 344.43924 -400.811238)
				)
			)
		)
	)
	(zone
		(layers "In1.Cu" "In3.Cu" "In5.Cu" "In7.Cu" "In8.Cu" "In9.Cu" "In10.Cu")
		(hatch none 0.5)
		(connect_pads
			(clearance 0)
		)
		(min_thickness 0.25)
		(keepout
			(tracks not_allowed)
			(vias allowed)
			(pads allowed)
			(copperpour not_allowed)
			(footprints allowed)
		)
		(placement
			(enabled no)
			(sheetname "")
		)
		(fill yes
			(thermal_gap 0.5)
			(thermal_bridge_width 0.5)
			(island_removal_mode 0)
		)
		(polygon
			(pts
				(arc
					(start 87.638382 -389.585962)
					(mid 87.750631 -389.721409)
					(end 87.919052 -389.772144)
				)
				(arc
					(start 87.919052 -389.772144)
					(mid 88.134578 -389.68287)
					(end 88.223852 -389.467344)
				)
				(arc
					(start 88.223852 -389.467344)
					(mid 88.214018 -389.390291)
					(end 88.18499 -389.318246)
				)
				(arc
					(start 87.806022 -388.671562)
					(mid 87.387509 -388.499187)
					(end 87.258906 -388.933182)
				)
			)
		)
	)
	(zone
		(layers "In1.Cu" "In3.Cu" "In5.Cu" "In7.Cu" "In8.Cu" "In9.Cu" "In10.Cu")
		(hatch none 0.5)
		(connect_pads
			(clearance 0)
		)
		(min_thickness 0.25)
		(keepout
			(tracks not_allowed)
			(vias allowed)
			(pads allowed)
			(copperpour not_allowed)
			(footprints allowed)
		)
		(placement
			(enabled no)
			(sheetname "")
		)
		(fill yes
			(thermal_gap 0.5)
			(thermal_bridge_width 0.5)
			(island_removal_mode 0)
		)
		(polygon
			(pts
				(arc
					(start 353.263962 -394.552424)
					(mid 353.373933 -394.653478)
					(end 353.518724 -394.690092)
				)
				(arc
					(start 353.518724 -394.690092)
					(mid 353.73425 -394.600818)
					(end 353.823524 -394.385292)
				)
				(arc
					(start 353.823524 -394.385292)
					(mid 353.813187 -394.306553)
					(end 353.782884 -394.233146)
				)
				(arc
					(start 353.390454 -393.554204)
					(mid 353.278057 -393.432587)
					(end 353.118674 -393.38758)
				)
				(arc
					(start 353.118674 -393.38758)
					(mid 352.903148 -393.476854)
					(end 352.813874 -393.69238)
				)
				(arc
					(start 352.813874 -393.69238)
					(mid 352.823452 -393.768442)
					(end 352.85172 -393.8397)
				)
				(xy 353.248976 -394.527024) (xy 353.261168 -394.54836) (xy 353.263708 -394.552678)
			)
		)
	)
	(zone
		(layers "In1.Cu" "In3.Cu" "In5.Cu" "In7.Cu" "In8.Cu" "In9.Cu" "In10.Cu")
		(hatch none 0.5)
		(connect_pads
			(clearance 0)
		)
		(min_thickness 0.25)
		(keepout
			(tracks not_allowed)
			(vias allowed)
			(pads allowed)
			(copperpour not_allowed)
			(footprints allowed)
		)
		(placement
			(enabled no)
			(sheetname "")
		)
		(fill yes
			(thermal_gap 0.5)
			(thermal_bridge_width 0.5)
			(island_removal_mode 0)
		)
		(polygon
			(pts
				(arc
					(start 130.211576 -393.292838)
					(mid 130.516376 -393.597638)
					(end 130.821176 -393.292838)
				)
				(arc
					(start 130.821176 -392.429238)
					(mid 130.516376 -392.124438)
					(end 130.211576 -392.429238)
				)
			)
		)
	)
	(zone
		(layers "In1.Cu" "In3.Cu" "In5.Cu" "In7.Cu" "In8.Cu" "In9.Cu" "In10.Cu")
		(hatch none 0.5)
		(connect_pads
			(clearance 0)
		)
		(min_thickness 0.25)
		(keepout
			(tracks not_allowed)
			(vias allowed)
			(pads allowed)
			(copperpour not_allowed)
			(footprints allowed)
		)
		(placement
			(enabled no)
			(sheetname "")
		)
		(fill yes
			(thermal_gap 0.5)
			(thermal_bridge_width 0.5)
			(island_removal_mode 0)
		)
		(polygon
			(pts
				(arc
					(start 123.011692 -393.292838)
					(mid 123.316492 -393.597638)
					(end 123.621292 -393.292838)
				)
				(arc
					(start 123.621292 -392.429238)
					(mid 123.316492 -392.124438)
					(end 123.011692 -392.429238)
				)
			)
		)
	)
	(zone
		(layers "In1.Cu" "In3.Cu" "In5.Cu" "In7.Cu" "In8.Cu" "In9.Cu" "In10.Cu")
		(hatch none 0.5)
		(connect_pads
			(clearance 0)
		)
		(min_thickness 0.25)
		(keepout
			(tracks not_allowed)
			(vias allowed)
			(pads allowed)
			(copperpour not_allowed)
			(footprints allowed)
		)
		(placement
			(enabled no)
			(sheetname "")
		)
		(fill yes
			(thermal_gap 0.5)
			(thermal_bridge_width 0.5)
			(island_removal_mode 0)
		)
		(polygon
			(pts
				(arc
					(start 121.811796 -393.292838)
					(mid 122.116596 -393.597638)
					(end 122.421396 -393.292838)
				)
				(arc
					(start 122.421396 -392.429238)
					(mid 122.116596 -392.124438)
					(end 121.811796 -392.429238)
				)
			)
		)
	)
	(zone
		(layers "In1.Cu" "In3.Cu" "In5.Cu" "In7.Cu" "In8.Cu" "In9.Cu" "In10.Cu")
		(hatch none 0.5)
		(connect_pads
			(clearance 0)
		)
		(min_thickness 0.25)
		(keepout
			(tracks not_allowed)
			(vias allowed)
			(pads allowed)
			(copperpour not_allowed)
			(footprints allowed)
		)
		(placement
			(enabled no)
			(sheetname "")
		)
		(fill yes
			(thermal_gap 0.5)
			(thermal_bridge_width 0.5)
			(island_removal_mode 0)
		)
		(polygon
			(pts
				(arc
					(start 131.411726 -393.292838)
					(mid 131.716526 -393.597638)
					(end 132.021326 -393.292838)
				)
				(arc
					(start 132.021326 -392.429238)
					(mid 131.716526 -392.124438)
					(end 131.411726 -392.429238)
				)
			)
		)
	)
	(zone
		(layers "In1.Cu" "In3.Cu" "In5.Cu" "In7.Cu" "In8.Cu" "In9.Cu" "In10.Cu")
		(hatch none 0.5)
		(connect_pads
			(clearance 0)
		)
		(min_thickness 0.25)
		(keepout
			(tracks not_allowed)
			(vias allowed)
			(pads allowed)
			(copperpour not_allowed)
			(footprints allowed)
		)
		(placement
			(enabled no)
			(sheetname "")
		)
		(fill yes
			(thermal_gap 0.5)
			(thermal_bridge_width 0.5)
			(island_removal_mode 0)
		)
		(polygon
			(pts
				(arc
					(start 86.438486 -389.585962)
					(mid 86.550735 -389.721409)
					(end 86.719156 -389.772144)
				)
				(arc
					(start 86.719156 -389.772144)
					(mid 86.934682 -389.68287)
					(end 87.023956 -389.467344)
				)
				(arc
					(start 87.023956 -389.467344)
					(mid 87.014122 -389.390291)
					(end 86.985094 -389.318246)
				)
				(arc
					(start 86.606126 -388.671562)
					(mid 86.187613 -388.499187)
					(end 86.05901 -388.933182)
				)
			)
		)
	)
	(zone
		(layers "In1.Cu" "In3.Cu" "In5.Cu" "In7.Cu" "In8.Cu" "In9.Cu" "In10.Cu")
		(hatch none 0.5)
		(connect_pads
			(clearance 0)
		)
		(min_thickness 0.25)
		(keepout
			(tracks not_allowed)
			(vias allowed)
			(pads allowed)
			(copperpour not_allowed)
			(footprints allowed)
		)
		(placement
			(enabled no)
			(sheetname "")
		)
		(fill yes
			(thermal_gap 0.5)
			(thermal_bridge_width 0.5)
			(island_removal_mode 0)
		)
		(polygon
			(pts
				(arc
					(start 119.41175 -393.292838)
					(mid 119.71655 -393.597638)
					(end 120.02135 -393.292838)
				)
				(arc
					(start 120.02135 -392.429238)
					(mid 119.71655 -392.124438)
					(end 119.41175 -392.429238)
				)
			)
		)
	)
	(zone
		(layers "In1.Cu" "In3.Cu" "In5.Cu" "In7.Cu" "In8.Cu" "In9.Cu" "In10.Cu")
		(hatch none 0.5)
		(connect_pads
			(clearance 0)
		)
		(min_thickness 0.25)
		(keepout
			(tracks not_allowed)
			(vias allowed)
			(pads allowed)
			(copperpour not_allowed)
			(footprints allowed)
		)
		(placement
			(enabled no)
			(sheetname "")
		)
		(fill yes
			(thermal_gap 0.5)
			(thermal_bridge_width 0.5)
			(island_removal_mode 0)
		)
		(polygon
			(pts
				(arc
					(start 339.639148 -401.674838)
					(mid 339.943948 -401.979638)
					(end 340.248748 -401.674838)
				)
				(arc
					(start 340.248748 -400.811238)
					(mid 339.943948 -400.506438)
					(end 339.639148 -400.811238)
				)
			)
		)
	)
	(zone
		(layers "In1.Cu" "In3.Cu" "In5.Cu" "In7.Cu" "In8.Cu" "In9.Cu" "In10.Cu")
		(hatch none 0.5)
		(connect_pads
			(clearance 0)
		)
		(min_thickness 0.25)
		(keepout
			(tracks not_allowed)
			(vias allowed)
			(pads allowed)
			(copperpour not_allowed)
			(footprints allowed)
		)
		(placement
			(enabled no)
			(sheetname "")
		)
		(fill yes
			(thermal_gap 0.5)
			(thermal_bridge_width 0.5)
			(island_removal_mode 0)
		)
		(polygon
			(pts
				(arc
					(start 126.611888 -393.292838)
					(mid 126.916688 -393.597638)
					(end 127.221488 -393.292838)
				)
				(arc
					(start 127.221488 -392.429238)
					(mid 126.916688 -392.124438)
					(end 126.611888 -392.429238)
				)
			)
		)
	)
	(zone
		(layers "In1.Cu" "In3.Cu" "In5.Cu" "In7.Cu" "In8.Cu" "In9.Cu" "In10.Cu")
		(hatch none 0.5)
		(connect_pads
			(clearance 0)
		)
		(min_thickness 0.25)
		(keepout
			(tracks not_allowed)
			(vias allowed)
			(pads allowed)
			(copperpour not_allowed)
			(footprints allowed)
		)
		(placement
			(enabled no)
			(sheetname "")
		)
		(fill yes
			(thermal_gap 0.5)
			(thermal_bridge_width 0.5)
			(island_removal_mode 0)
		)
		(polygon
			(pts
				(arc
					(start 350.863916 -394.552424)
					(mid 350.973887 -394.653478)
					(end 351.118678 -394.690092)
				)
				(arc
					(start 351.118678 -394.690092)
					(mid 351.334204 -394.600818)
					(end 351.423478 -394.385292)
				)
				(arc
					(start 351.423478 -394.385292)
					(mid 351.413141 -394.306553)
					(end 351.382838 -394.233146)
				)
				(arc
					(start 350.990408 -393.554204)
					(mid 350.878011 -393.432587)
					(end 350.718628 -393.38758)
				)
				(arc
					(start 350.718628 -393.38758)
					(mid 350.503102 -393.476854)
					(end 350.413828 -393.69238)
				)
				(arc
					(start 350.413828 -393.69238)
					(mid 350.423406 -393.768442)
					(end 350.451674 -393.8397)
				)
				(xy 350.84893 -394.527024) (xy 350.861122 -394.54836) (xy 350.863662 -394.552678)
			)
		)
	)
	(zone
		(layers "In1.Cu" "In3.Cu" "In5.Cu" "In7.Cu" "In8.Cu" "In9.Cu" "In10.Cu")
		(hatch none 0.5)
		(connect_pads
			(clearance 0)
		)
		(min_thickness 0.25)
		(keepout
			(tracks not_allowed)
			(vias allowed)
			(pads allowed)
			(copperpour not_allowed)
			(footprints allowed)
		)
		(placement
			(enabled no)
			(sheetname "")
		)
		(fill yes
			(thermal_gap 0.5)
			(thermal_bridge_width 0.5)
			(island_removal_mode 0)
		)
		(polygon
			(pts
				(arc
					(start 377.811792 -401.674838)
					(mid 378.116592 -401.979638)
					(end 378.421392 -401.674838)
				)
				(arc
					(start 378.421392 -400.811238)
					(mid 378.116592 -400.506438)
					(end 377.811792 -400.811238)
				)
			)
		)
	)
	(zone
		(layers "In1.Cu" "In3.Cu" "In5.Cu" "In7.Cu" "In8.Cu" "In9.Cu" "In10.Cu")
		(hatch none 0.5)
		(connect_pads
			(clearance 0)
		)
		(min_thickness 0.25)
		(keepout
			(tracks not_allowed)
			(vias allowed)
			(pads allowed)
			(copperpour not_allowed)
			(footprints allowed)
		)
		(placement
			(enabled no)
			(sheetname "")
		)
		(fill yes
			(thermal_gap 0.5)
			(thermal_bridge_width 0.5)
			(island_removal_mode 0)
		)
		(polygon
			(pts
				(arc
					(start 387.411722 -401.674838)
					(mid 387.716522 -401.979638)
					(end 388.021322 -401.674838)
				)
				(arc
					(start 388.021322 -400.811238)
					(mid 387.716522 -400.506438)
					(end 387.411722 -400.811238)
				)
			)
		)
	)
	(zone
		(layers "In1.Cu" "In3.Cu" "In5.Cu" "In7.Cu" "In8.Cu" "In9.Cu" "In10.Cu")
		(hatch none 0.5)
		(connect_pads
			(clearance 0)
		)
		(min_thickness 0.25)
		(keepout
			(tracks not_allowed)
			(vias allowed)
			(pads allowed)
			(copperpour not_allowed)
			(footprints allowed)
		)
		(placement
			(enabled no)
			(sheetname "")
		)
		(fill yes
			(thermal_gap 0.5)
			(thermal_bridge_width 0.5)
			(island_removal_mode 0)
		)
		(polygon
			(pts
				(arc
					(start 388.611618 -401.674838)
					(mid 388.916418 -401.979638)
					(end 389.221218 -401.674838)
				)
				(arc
					(start 389.221218 -400.811238)
					(mid 388.916418 -400.506438)
					(end 388.611618 -400.811238)
				)
			)
		)
	)
	(zone
		(layers "In1.Cu" "In3.Cu" "In5.Cu" "In7.Cu" "In8.Cu" "In9.Cu" "In10.Cu")
		(hatch none 0.5)
		(connect_pads
			(clearance 0)
		)
		(min_thickness 0.25)
		(keepout
			(tracks not_allowed)
			(vias allowed)
			(pads allowed)
			(copperpour not_allowed)
			(footprints allowed)
		)
		(placement
			(enabled no)
			(sheetname "")
		)
		(fill yes
			(thermal_gap 0.5)
			(thermal_bridge_width 0.5)
			(island_removal_mode 0)
		)
		(polygon
			(pts
				(arc
					(start 124.211842 -393.292838)
					(mid 124.516642 -393.597638)
					(end 124.821442 -393.292838)
				)
				(arc
					(start 124.821442 -392.429238)
					(mid 124.516642 -392.124438)
					(end 124.211842 -392.429238)
				)
			)
		)
	)
	(zone
		(layers "In1.Cu" "In3.Cu" "In5.Cu" "In7.Cu" "In8.Cu" "In9.Cu" "In10.Cu")
		(hatch none 0.5)
		(connect_pads
			(clearance 0)
		)
		(min_thickness 0.25)
		(keepout
			(tracks not_allowed)
			(vias allowed)
			(pads allowed)
			(copperpour not_allowed)
			(footprints allowed)
		)
		(placement
			(enabled no)
			(sheetname "")
		)
		(fill yes
			(thermal_gap 0.5)
			(thermal_bridge_width 0.5)
			(island_removal_mode 0)
		)
		(polygon
			(pts
				(arc
					(start 349.239332 -401.674838)
					(mid 349.544132 -401.979638)
					(end 349.848932 -401.674838)
				)
				(arc
					(start 349.848932 -400.811238)
					(mid 349.544132 -400.506438)
					(end 349.239332 -400.811238)
				)
			)
		)
	)
	(zone
		(layers "In1.Cu" "In3.Cu" "In5.Cu" "In7.Cu" "In8.Cu" "In9.Cu" "In10.Cu")
		(hatch none 0.5)
		(connect_pads
			(clearance 0)
		)
		(min_thickness 0.25)
		(keepout
			(tracks not_allowed)
			(vias allowed)
			(pads allowed)
			(copperpour not_allowed)
			(footprints allowed)
		)
		(placement
			(enabled no)
			(sheetname "")
		)
		(fill yes
			(thermal_gap 0.5)
			(thermal_bridge_width 0.5)
			(island_removal_mode 0)
		)
		(polygon
			(pts
				(arc
					(start 352.839274 -401.674838)
					(mid 353.144074 -401.979638)
					(end 353.448874 -401.674838)
				)
				(arc
					(start 353.448874 -400.811238)
					(mid 353.144074 -400.506438)
					(end 352.839274 -400.811238)
				)
			)
		)
	)
	(zone
		(layers "In1.Cu" "In3.Cu" "In5.Cu" "In7.Cu" "In8.Cu" "In9.Cu" "In10.Cu")
		(hatch none 0.5)
		(connect_pads
			(clearance 0)
		)
		(min_thickness 0.25)
		(keepout
			(tracks not_allowed)
			(vias allowed)
			(pads allowed)
			(copperpour not_allowed)
			(footprints allowed)
		)
		(placement
			(enabled no)
			(sheetname "")
		)
		(fill yes
			(thermal_gap 0.5)
			(thermal_bridge_width 0.5)
			(island_removal_mode 0)
		)
		(polygon
			(pts
				(arc
					(start 129.01168 -393.292838)
					(mid 129.31648 -393.597638)
					(end 129.62128 -393.292838)
				)
				(arc
					(start 129.62128 -392.429238)
					(mid 129.31648 -392.124438)
					(end 129.01168 -392.429238)
				)
			)
		)
	)
	(zone
		(layers "In1.Cu" "In3.Cu" "In5.Cu" "In7.Cu" "In8.Cu" "In9.Cu" "In10.Cu")
		(hatch none 0.5)
		(connect_pads
			(clearance 0)
		)
		(min_thickness 0.25)
		(keepout
			(tracks not_allowed)
			(vias allowed)
			(pads allowed)
			(copperpour not_allowed)
			(footprints allowed)
		)
		(placement
			(enabled no)
			(sheetname "")
		)
		(fill yes
			(thermal_gap 0.5)
			(thermal_bridge_width 0.5)
			(island_removal_mode 0)
		)
		(polygon
			(pts
				(arc
					(start 94.838266 -389.585962)
					(mid 94.950515 -389.721409)
					(end 95.118936 -389.772144)
				)
				(arc
					(start 95.118936 -389.772144)
					(mid 95.334462 -389.68287)
					(end 95.423736 -389.467344)
				)
				(arc
					(start 95.423736 -389.467344)
					(mid 95.413902 -389.390291)
					(end 95.384874 -389.318246)
				)
				(arc
					(start 95.005906 -388.671562)
					(mid 94.587393 -388.499187)
					(end 94.45879 -388.933182)
				)
			)
		)
	)
	(zone
		(layers "In1.Cu" "In3.Cu" "In5.Cu" "In7.Cu" "In8.Cu" "In9.Cu" "In10.Cu")
		(hatch none 0.5)
		(connect_pads
			(clearance 0)
		)
		(min_thickness 0.25)
		(keepout
			(tracks not_allowed)
			(vias allowed)
			(pads allowed)
			(copperpour not_allowed)
			(footprints allowed)
		)
		(placement
			(enabled no)
			(sheetname "")
		)
		(fill yes
			(thermal_gap 0.5)
			(thermal_bridge_width 0.5)
			(island_removal_mode 0)
		)
		(polygon
			(pts
				(arc
					(start 383.81178 -401.674838)
					(mid 384.11658 -401.979638)
					(end 384.42138 -401.674838)
				)
				(arc
					(start 384.42138 -400.811238)
					(mid 384.11658 -400.506438)
					(end 383.81178 -400.811238)
				)
			)
		)
	)
	(zone
		(layers "In1.Cu" "In3.Cu" "In5.Cu" "In7.Cu" "In8.Cu" "In9.Cu" "In10.Cu")
		(hatch none 0.5)
		(connect_pads
			(clearance 0)
		)
		(min_thickness 0.25)
		(keepout
			(tracks not_allowed)
			(vias allowed)
			(pads allowed)
			(copperpour not_allowed)
			(footprints allowed)
		)
		(placement
			(enabled no)
			(sheetname "")
		)
		(fill yes
			(thermal_gap 0.5)
			(thermal_bridge_width 0.5)
			(island_removal_mode 0)
		)
		(polygon
			(pts
				(arc
					(start 370.611654 -401.674838)
					(mid 370.916454 -401.979638)
					(end 371.221254 -401.674838)
				)
				(arc
					(start 371.221254 -400.811238)
					(mid 370.916454 -400.506438)
					(end 370.611654 -400.811238)
				)
			)
		)
	)
	(zone
		(layers "In1.Cu" "In3.Cu" "In5.Cu" "In7.Cu" "In8.Cu" "In9.Cu" "In10.Cu")
		(hatch none 0.5)
		(connect_pads
			(clearance 0)
		)
		(min_thickness 0.25)
		(keepout
			(tracks not_allowed)
			(vias allowed)
			(pads allowed)
			(copperpour not_allowed)
			(footprints allowed)
		)
		(placement
			(enabled no)
			(sheetname "")
		)
		(fill yes
			(thermal_gap 0.5)
			(thermal_bridge_width 0.5)
			(island_removal_mode 0)
		)
		(polygon
			(pts
				(arc
					(start 82.83829 -389.585962)
					(mid 82.950539 -389.721409)
					(end 83.11896 -389.772144)
				)
				(arc
					(start 83.11896 -389.772144)
					(mid 83.334486 -389.68287)
					(end 83.42376 -389.467344)
				)
				(arc
					(start 83.42376 -389.467344)
					(mid 83.413926 -389.390291)
					(end 83.384898 -389.318246)
				)
				(arc
					(start 83.00593 -388.671562)
					(mid 82.587417 -388.499187)
					(end 82.458814 -388.933182)
				)
			)
		)
	)
	(zone
		(layers "In1.Cu" "In3.Cu" "In5.Cu" "In7.Cu" "In8.Cu" "In9.Cu" "In10.Cu")
		(hatch none 0.5)
		(connect_pads
			(clearance 0)
		)
		(min_thickness 0.25)
		(keepout
			(tracks not_allowed)
			(vias allowed)
			(pads allowed)
			(copperpour not_allowed)
			(footprints allowed)
		)
		(placement
			(enabled no)
			(sheetname "")
		)
		(fill yes
			(thermal_gap 0.5)
			(thermal_bridge_width 0.5)
			(island_removal_mode 0)
		)
		(polygon
			(pts
				(arc
					(start 338.439252 -401.674838)
					(mid 338.744052 -401.979638)
					(end 339.048852 -401.674838)
				)
				(arc
					(start 339.048852 -400.811238)
					(mid 338.744052 -400.506438)
					(end 338.439252 -400.811238)
				)
			)
		)
	)
	(zone
		(layers "In1.Cu" "In3.Cu" "In5.Cu" "In7.Cu" "In8.Cu" "In9.Cu" "In10.Cu")
		(hatch none 0.5)
		(connect_pads
			(clearance 0)
		)
		(min_thickness 0.25)
		(keepout
			(tracks not_allowed)
			(vias allowed)
			(pads allowed)
			(copperpour not_allowed)
			(footprints allowed)
		)
		(placement
			(enabled no)
			(sheetname "")
		)
		(fill yes
			(thermal_gap 0.5)
			(thermal_bridge_width 0.5)
			(island_removal_mode 0)
		)
		(polygon
			(pts
				(arc
					(start 343.239344 -401.674838)
					(mid 343.544144 -401.979638)
					(end 343.848944 -401.674838)
				)
				(arc
					(start 343.848944 -400.811238)
					(mid 343.544144 -400.506438)
					(end 343.239344 -400.811238)
				)
			)
		)
	)
	(zone
		(layers "In1.Cu" "In3.Cu" "In5.Cu" "In7.Cu" "In8.Cu" "In9.Cu" "In10.Cu")
		(hatch none 0.5)
		(connect_pads
			(clearance 0)
		)
		(min_thickness 0.25)
		(keepout
			(tracks not_allowed)
			(vias allowed)
			(pads allowed)
			(copperpour not_allowed)
			(footprints allowed)
		)
		(placement
			(enabled no)
			(sheetname "")
		)
		(fill yes
			(thermal_gap 0.5)
			(thermal_bridge_width 0.5)
			(island_removal_mode 0)
		)
		(polygon
			(pts
				(arc
					(start 345.63939 -401.674838)
					(mid 345.94419 -401.979638)
					(end 346.24899 -401.674838)
				)
				(arc
					(start 346.24899 -400.811238)
					(mid 345.94419 -400.506438)
					(end 345.63939 -400.811238)
				)
			)
		)
	)
	(zone
		(layers "In1.Cu" "In3.Cu" "In5.Cu" "In7.Cu" "In8.Cu" "In9.Cu" "In10.Cu")
		(hatch none 0.5)
		(connect_pads
			(clearance 0)
		)
		(min_thickness 0.25)
		(keepout
			(tracks not_allowed)
			(vias allowed)
			(pads allowed)
			(copperpour not_allowed)
			(footprints allowed)
		)
		(placement
			(enabled no)
			(sheetname "")
		)
		(fill yes
			(thermal_gap 0.5)
			(thermal_bridge_width 0.5)
			(island_removal_mode 0)
		)
		(polygon
			(pts
				(arc
					(start 125.411738 -393.292838)
					(mid 125.716538 -393.597638)
					(end 126.021338 -393.292838)
				)
				(arc
					(start 126.021338 -392.429238)
					(mid 125.716538 -392.124438)
					(end 125.411738 -392.429238)
				)
			)
		)
	)
	(zone
		(layers "In1.Cu" "In3.Cu" "In5.Cu" "In7.Cu" "In8.Cu" "In9.Cu" "In10.Cu"
			"In12.Cu"
		)
		(hatch none 0.5)
		(connect_pads
			(clearance 0)
		)
		(min_thickness 0.25)
		(keepout
			(tracks not_allowed)
			(vias allowed)
			(pads allowed)
			(copperpour not_allowed)
			(footprints allowed)
		)
		(placement
			(enabled no)
			(sheetname "")
		)
		(fill yes
			(thermal_gap 0.5)
			(thermal_bridge_width 0.5)
			(island_removal_mode 0)
		)
		(polygon
			(pts
				(arc
					(start 305.911504 -401.674838)
					(mid 306.216304 -401.979638)
					(end 306.521104 -401.674838)
				)
				(arc
					(start 306.521104 -400.811238)
					(mid 306.216304 -400.506438)
					(end 305.911504 -400.811238)
				)
			)
		)
	)
	(zone
		(layers "In1.Cu" "In3.Cu" "In5.Cu" "In7.Cu" "In8.Cu" "In9.Cu" "In10.Cu"
			"In12.Cu"
		)
		(hatch none 0.5)
		(connect_pads
			(clearance 0)
		)
		(min_thickness 0.25)
		(keepout
			(tracks not_allowed)
			(vias allowed)
			(pads allowed)
			(copperpour not_allowed)
			(footprints allowed)
		)
		(placement
			(enabled no)
			(sheetname "")
		)
		(fill yes
			(thermal_gap 0.5)
			(thermal_bridge_width 0.5)
			(island_removal_mode 0)
		)
		(polygon
			(pts
				(arc
					(start 165.13937 -393.292838)
					(mid 165.44417 -393.597638)
					(end 165.74897 -393.292838)
				)
				(arc
					(start 165.74897 -392.429238)
					(mid 165.44417 -392.124438)
					(end 165.13937 -392.429238)
				)
			)
		)
	)
	(zone
		(layers "In1.Cu" "In3.Cu" "In5.Cu" "In7.Cu" "In8.Cu" "In9.Cu" "In10.Cu"
			"In12.Cu"
		)
		(hatch none 0.5)
		(connect_pads
			(clearance 0)
		)
		(min_thickness 0.25)
		(keepout
			(tracks not_allowed)
			(vias allowed)
			(pads allowed)
			(copperpour not_allowed)
			(footprints allowed)
		)
		(placement
			(enabled no)
			(sheetname "")
		)
		(fill yes
			(thermal_gap 0.5)
			(thermal_bridge_width 0.5)
			(island_removal_mode 0)
		)
		(polygon
			(pts
				(arc
					(start 155.53944 -393.292838)
					(mid 155.84424 -393.597638)
					(end 156.14904 -393.292838)
				)
				(arc
					(start 156.14904 -392.429238)
					(mid 155.84424 -392.124438)
					(end 155.53944 -392.429238)
				)
			)
		)
	)
	(zone
		(layers "In1.Cu" "In3.Cu" "In5.Cu" "In7.Cu" "In8.Cu" "In9.Cu" "In10.Cu"
			"In12.Cu"
		)
		(hatch none 0.5)
		(connect_pads
			(clearance 0)
		)
		(min_thickness 0.25)
		(keepout
			(tracks not_allowed)
			(vias allowed)
			(pads allowed)
			(copperpour not_allowed)
			(footprints allowed)
		)
		(placement
			(enabled no)
			(sheetname "")
		)
		(fill yes
			(thermal_gap 0.5)
			(thermal_bridge_width 0.5)
			(island_removal_mode 0)
		)
		(polygon
			(pts
				(arc
					(start 80.039464 -393.292838)
					(mid 80.344264 -393.597638)
					(end 80.649064 -393.292838)
				)
				(arc
					(start 80.649064 -392.429238)
					(mid 80.344264 -392.124438)
					(end 80.039464 -392.429238)
				)
			)
		)
	)
	(zone
		(layers "In1.Cu" "In3.Cu" "In5.Cu" "In7.Cu" "In8.Cu" "In9.Cu" "In10.Cu"
			"In12.Cu"
		)
		(hatch none 0.5)
		(connect_pads
			(clearance 0)
		)
		(min_thickness 0.25)
		(keepout
			(tracks not_allowed)
			(vias allowed)
			(pads allowed)
			(copperpour not_allowed)
			(footprints allowed)
		)
		(placement
			(enabled no)
			(sheetname "")
		)
		(fill yes
			(thermal_gap 0.5)
			(thermal_bridge_width 0.5)
			(island_removal_mode 0)
		)
		(polygon
			(pts
				(arc
					(start 312.33618 -394.552424)
					(mid 312.446151 -394.653478)
					(end 312.590942 -394.690092)
				)
				(arc
					(start 312.590942 -394.690092)
					(mid 312.806468 -394.600818)
					(end 312.895742 -394.385292)
				)
				(arc
					(start 312.895742 -394.385292)
					(mid 312.885405 -394.306553)
					(end 312.855102 -394.233146)
				)
				(arc
					(start 312.462672 -393.554204)
					(mid 312.350275 -393.432587)
					(end 312.190892 -393.38758)
				)
				(arc
					(start 312.190892 -393.38758)
					(mid 311.975366 -393.476854)
					(end 311.886092 -393.69238)
				)
				(arc
					(start 311.886092 -393.69238)
					(mid 311.89567 -393.768442)
					(end 311.923938 -393.8397)
				)
				(xy 312.321194 -394.527024) (xy 312.333386 -394.54836) (xy 312.335926 -394.552678)
			)
		)
	)
	(zone
		(layers "In1.Cu" "In3.Cu" "In5.Cu" "In7.Cu" "In8.Cu" "In9.Cu" "In10.Cu"
			"In12.Cu"
		)
		(hatch none 0.5)
		(connect_pads
			(clearance 0)
		)
		(min_thickness 0.25)
		(keepout
			(tracks not_allowed)
			(vias allowed)
			(pads allowed)
			(copperpour not_allowed)
			(footprints allowed)
		)
		(placement
			(enabled no)
			(sheetname "")
		)
		(fill yes
			(thermal_gap 0.5)
			(thermal_bridge_width 0.5)
			(island_removal_mode 0)
		)
		(polygon
			(pts
				(arc
					(start 306.336192 -394.552424)
					(mid 306.446163 -394.653478)
					(end 306.590954 -394.690092)
				)
				(arc
					(start 306.590954 -394.690092)
					(mid 306.80648 -394.600818)
					(end 306.895754 -394.385292)
				)
				(arc
					(start 306.895754 -394.385292)
					(mid 306.885417 -394.306553)
					(end 306.855114 -394.233146)
				)
				(arc
					(start 306.462684 -393.554204)
					(mid 306.350287 -393.432587)
					(end 306.190904 -393.38758)
				)
				(arc
					(start 306.190904 -393.38758)
					(mid 305.975378 -393.476854)
					(end 305.886104 -393.69238)
				)
				(arc
					(start 305.886104 -393.69238)
					(mid 305.895682 -393.768442)
					(end 305.92395 -393.8397)
				)
				(xy 306.321206 -394.527024) (xy 306.333398 -394.54836) (xy 306.335938 -394.552678)
			)
		)
	)
	(zone
		(layers "In1.Cu" "In3.Cu" "In5.Cu" "In7.Cu" "In8.Cu" "In9.Cu" "In10.Cu"
			"In12.Cu"
		)
		(hatch none 0.5)
		(connect_pads
			(clearance 0)
		)
		(min_thickness 0.25)
		(keepout
			(tracks not_allowed)
			(vias allowed)
			(pads allowed)
			(copperpour not_allowed)
			(footprints allowed)
		)
		(placement
			(enabled no)
			(sheetname "")
		)
		(fill yes
			(thermal_gap 0.5)
			(thermal_bridge_width 0.5)
			(island_removal_mode 0)
		)
		(polygon
			(pts
				(arc
					(start 410.33954 -401.674838)
					(mid 410.64434 -401.979638)
					(end 410.94914 -401.674838)
				)
				(arc
					(start 410.94914 -400.811238)
					(mid 410.64434 -400.506438)
					(end 410.33954 -400.811238)
				)
			)
		)
	)
	(zone
		(layers "In1.Cu" "In3.Cu" "In5.Cu" "In7.Cu" "In8.Cu" "In9.Cu" "In10.Cu"
			"In12.Cu"
		)
		(hatch none 0.5)
		(connect_pads
			(clearance 0)
		)
		(min_thickness 0.25)
		(keepout
			(tracks not_allowed)
			(vias allowed)
			(pads allowed)
			(copperpour not_allowed)
			(footprints allowed)
		)
		(placement
			(enabled no)
			(sheetname "")
		)
		(fill yes
			(thermal_gap 0.5)
			(thermal_bridge_width 0.5)
			(island_removal_mode 0)
		)
		(polygon
			(pts
				(arc
					(start 416.339528 -401.674838)
					(mid 416.644328 -401.979638)
					(end 416.949128 -401.674838)
				)
				(arc
					(start 416.949128 -400.811238)
					(mid 416.644328 -400.506438)
					(end 416.339528 -400.811238)
				)
			)
		)
	)
	(zone
		(layers "In1.Cu" "In3.Cu" "In5.Cu" "In7.Cu" "In8.Cu" "In9.Cu" "In10.Cu"
			"In12.Cu"
		)
		(hatch none 0.5)
		(connect_pads
			(clearance 0)
		)
		(min_thickness 0.25)
		(keepout
			(tracks not_allowed)
			(vias allowed)
			(pads allowed)
			(copperpour not_allowed)
			(footprints allowed)
		)
		(placement
			(enabled no)
			(sheetname "")
		)
		(fill yes
			(thermal_gap 0.5)
			(thermal_bridge_width 0.5)
			(island_removal_mode 0)
		)
		(polygon
			(pts
				(arc
					(start 311.911492 -401.674838)
					(mid 312.216292 -401.979638)
					(end 312.521092 -401.674838)
				)
				(arc
					(start 312.521092 -400.811238)
					(mid 312.216292 -400.506438)
					(end 311.911492 -400.811238)
				)
			)
		)
	)
	(zone
		(layers "In1.Cu" "In3.Cu" "In5.Cu" "In7.Cu" "In8.Cu" "In9.Cu" "In10.Cu"
			"In12.Cu"
		)
		(hatch none 0.5)
		(connect_pads
			(clearance 0)
		)
		(min_thickness 0.25)
		(keepout
			(tracks not_allowed)
			(vias allowed)
			(pads allowed)
			(copperpour not_allowed)
			(footprints allowed)
		)
		(placement
			(enabled no)
			(sheetname "")
		)
		(fill yes
			(thermal_gap 0.5)
			(thermal_bridge_width 0.5)
			(island_removal_mode 0)
		)
		(polygon
			(pts
				(arc
					(start 148.339302 -393.292838)
					(mid 148.644102 -393.597638)
					(end 148.948902 -393.292838)
				)
				(arc
					(start 148.948902 -392.429238)
					(mid 148.644102 -392.124438)
					(end 148.339302 -392.429238)
				)
			)
		)
	)
	(zone
		(layers "In1.Cu" "In3.Cu" "In5.Cu" "In7.Cu" "In8.Cu" "In9.Cu" "In10.Cu"
			"In12.Cu"
		)
		(hatch none 0.5)
		(connect_pads
			(clearance 0)
		)
		(min_thickness 0.25)
		(keepout
			(tracks not_allowed)
			(vias allowed)
			(pads allowed)
			(copperpour not_allowed)
			(footprints allowed)
		)
		(placement
			(enabled no)
			(sheetname "")
		)
		(fill yes
			(thermal_gap 0.5)
			(thermal_bridge_width 0.5)
			(island_removal_mode 0)
		)
		(polygon
			(pts
				(arc
					(start 405.539448 -401.674838)
					(mid 405.844248 -401.979638)
					(end 406.149048 -401.674838)
				)
				(arc
					(start 406.149048 -400.811238)
					(mid 405.844248 -400.506438)
					(end 405.539448 -400.811238)
				)
			)
		)
	)
	(zone
		(layers "In1.Cu" "In3.Cu" "In5.Cu" "In7.Cu" "In8.Cu" "In9.Cu" "In10.Cu"
			"In12.Cu"
		)
		(hatch none 0.5)
		(connect_pads
			(clearance 0)
		)
		(min_thickness 0.25)
		(keepout
			(tracks not_allowed)
			(vias allowed)
			(pads allowed)
			(copperpour not_allowed)
			(footprints allowed)
		)
		(placement
			(enabled no)
			(sheetname "")
		)
		(fill yes
			(thermal_gap 0.5)
			(thermal_bridge_width 0.5)
			(island_removal_mode 0)
		)
		(polygon
			(pts
				(arc
					(start 310.711596 -401.674838)
					(mid 311.016396 -401.979638)
					(end 311.321196 -401.674838)
				)
				(arc
					(start 311.321196 -400.811238)
					(mid 311.016396 -400.506438)
					(end 310.711596 -400.811238)
				)
			)
		)
	)
	(zone
		(layers "In1.Cu" "In3.Cu" "In5.Cu" "In7.Cu" "In8.Cu" "In9.Cu" "In10.Cu"
			"In12.Cu"
		)
		(hatch none 0.5)
		(connect_pads
			(clearance 0)
		)
		(min_thickness 0.25)
		(keepout
			(tracks not_allowed)
			(vias allowed)
			(pads allowed)
			(copperpour not_allowed)
			(footprints allowed)
		)
		(placement
			(enabled no)
			(sheetname "")
		)
		(fill yes
			(thermal_gap 0.5)
			(thermal_bridge_width 0.5)
			(island_removal_mode 0)
		)
		(polygon
			(pts
				(arc
					(start 421.139366 -401.674838)
					(mid 421.444166 -401.979638)
					(end 421.748966 -401.674838)
				)
				(arc
					(start 421.748966 -400.811238)
					(mid 421.444166 -400.506438)
					(end 421.139366 -400.811238)
				)
			)
		)
	)
	(zone
		(layers "In1.Cu" "In3.Cu" "In5.Cu" "In7.Cu" "In8.Cu" "In9.Cu" "In10.Cu"
			"In12.Cu"
		)
		(hatch none 0.5)
		(connect_pads
			(clearance 0)
		)
		(min_thickness 0.25)
		(keepout
			(tracks not_allowed)
			(vias allowed)
			(pads allowed)
			(copperpour not_allowed)
			(footprints allowed)
		)
		(placement
			(enabled no)
			(sheetname "")
		)
		(fill yes
			(thermal_gap 0.5)
			(thermal_bridge_width 0.5)
			(island_removal_mode 0)
		)
		(polygon
			(pts
				(arc
					(start 407.939494 -401.674838)
					(mid 408.244294 -401.979638)
					(end 408.549094 -401.674838)
				)
				(arc
					(start 408.549094 -400.811238)
					(mid 408.244294 -400.506438)
					(end 407.939494 -400.811238)
				)
			)
		)
	)
	(zone
		(layers "In1.Cu" "In3.Cu" "In5.Cu" "In7.Cu" "In8.Cu" "In9.Cu" "In10.Cu"
			"In12.Cu"
		)
		(hatch none 0.5)
		(connect_pads
			(clearance 0)
		)
		(min_thickness 0.25)
		(keepout
			(tracks not_allowed)
			(vias allowed)
			(pads allowed)
			(copperpour not_allowed)
			(footprints allowed)
		)
		(placement
			(enabled no)
			(sheetname "")
		)
		(fill yes
			(thermal_gap 0.5)
			(thermal_bridge_width 0.5)
			(island_removal_mode 0)
		)
		(polygon
			(pts
				(arc
					(start 304.711354 -401.674838)
					(mid 305.016154 -401.979638)
					(end 305.320954 -401.674838)
				)
				(arc
					(start 305.320954 -400.811238)
					(mid 305.016154 -400.506438)
					(end 304.711354 -400.811238)
				)
			)
		)
	)
	(zone
		(layers "In1.Cu" "In3.Cu" "In5.Cu" "In7.Cu" "In8.Cu" "In9.Cu" "In10.Cu"
			"In12.Cu"
		)
		(hatch none 0.5)
		(connect_pads
			(clearance 0)
		)
		(min_thickness 0.25)
		(keepout
			(tracks not_allowed)
			(vias allowed)
			(pads allowed)
			(copperpour not_allowed)
			(footprints allowed)
		)
		(placement
			(enabled no)
			(sheetname "")
		)
		(fill yes
			(thermal_gap 0.5)
			(thermal_bridge_width 0.5)
			(island_removal_mode 0)
		)
		(polygon
			(pts
				(arc
					(start 314.311538 -401.674838)
					(mid 314.616338 -401.979638)
					(end 314.921138 -401.674838)
				)
				(arc
					(start 314.921138 -400.811238)
					(mid 314.616338 -400.506438)
					(end 314.311538 -400.811238)
				)
			)
		)
	)
	(zone
		(layers "In1.Cu" "In3.Cu" "In5.Cu" "In7.Cu" "In8.Cu" "In9.Cu" "In10.Cu"
			"In12.Cu"
		)
		(hatch none 0.5)
		(connect_pads
			(clearance 0)
		)
		(min_thickness 0.25)
		(keepout
			(tracks not_allowed)
			(vias allowed)
			(pads allowed)
			(copperpour not_allowed)
			(footprints allowed)
		)
		(placement
			(enabled no)
			(sheetname "")
		)
		(fill yes
			(thermal_gap 0.5)
			(thermal_bridge_width 0.5)
			(island_removal_mode 0)
		)
		(polygon
			(pts
				(arc
					(start 307.1114 -401.674838)
					(mid 307.4162 -401.979638)
					(end 307.721 -401.674838)
				)
				(arc
					(start 307.721 -400.811238)
					(mid 307.4162 -400.506438)
					(end 307.1114 -400.811238)
				)
			)
		)
	)
	(zone
		(layers "In1.Cu" "In3.Cu" "In5.Cu" "In7.Cu" "In8.Cu" "In9.Cu" "In10.Cu"
			"In12.Cu"
		)
		(hatch none 0.5)
		(connect_pads
			(clearance 0)
		)
		(min_thickness 0.25)
		(keepout
			(tracks not_allowed)
			(vias allowed)
			(pads allowed)
			(copperpour not_allowed)
			(footprints allowed)
		)
		(placement
			(enabled no)
			(sheetname "")
		)
		(fill yes
			(thermal_gap 0.5)
			(thermal_bridge_width 0.5)
			(island_removal_mode 0)
		)
		(polygon
			(pts
				(arc
					(start 412.739586 -401.674838)
					(mid 413.044386 -401.979638)
					(end 413.349186 -401.674838)
				)
				(arc
					(start 413.349186 -400.811238)
					(mid 413.044386 -400.506438)
					(end 412.739586 -400.811238)
				)
			)
		)
	)
	(zone
		(layers "In1.Cu" "In3.Cu" "In5.Cu" "In7.Cu" "In8.Cu" "In9.Cu" "In10.Cu"
			"In12.Cu"
		)
		(hatch none 0.5)
		(connect_pads
			(clearance 0)
		)
		(min_thickness 0.25)
		(keepout
			(tracks not_allowed)
			(vias allowed)
			(pads allowed)
			(copperpour not_allowed)
			(footprints allowed)
		)
		(placement
			(enabled no)
			(sheetname "")
		)
		(fill yes
			(thermal_gap 0.5)
			(thermal_bridge_width 0.5)
			(island_removal_mode 0)
		)
		(polygon
			(pts
				(arc
					(start 93.23959 -393.292838)
					(mid 93.54439 -393.597638)
					(end 93.84919 -393.292838)
				)
				(arc
					(start 93.84919 -392.429238)
					(mid 93.54439 -392.124438)
					(end 93.23959 -392.429238)
				)
			)
		)
	)
	(zone
		(layers "In1.Cu" "In3.Cu" "In5.Cu" "In7.Cu" "In8.Cu" "In9.Cu" "In10.Cu"
			"In12.Cu"
		)
		(hatch none 0.5)
		(connect_pads
			(clearance 0)
		)
		(min_thickness 0.25)
		(keepout
			(tracks not_allowed)
			(vias allowed)
			(pads allowed)
			(copperpour not_allowed)
			(footprints allowed)
		)
		(placement
			(enabled no)
			(sheetname "")
		)
		(fill yes
			(thermal_gap 0.5)
			(thermal_bridge_width 0.5)
			(island_removal_mode 0)
		)
		(polygon
			(pts
				(arc
					(start 317.91148 -401.674838)
					(mid 318.21628 -401.979638)
					(end 318.52108 -401.674838)
				)
				(arc
					(start 318.52108 -400.811238)
					(mid 318.21628 -400.506438)
					(end 317.91148 -400.811238)
				)
			)
		)
	)
	(zone
		(layers "In1.Cu" "In3.Cu" "In5.Cu" "In7.Cu" "In8.Cu" "In9.Cu" "In10.Cu"
			"In12.Cu"
		)
		(hatch none 0.5)
		(connect_pads
			(clearance 0)
		)
		(min_thickness 0.25)
		(keepout
			(tracks not_allowed)
			(vias allowed)
			(pads allowed)
			(copperpour not_allowed)
			(footprints allowed)
		)
		(placement
			(enabled no)
			(sheetname "")
		)
		(fill yes
			(thermal_gap 0.5)
			(thermal_bridge_width 0.5)
			(island_removal_mode 0)
		)
		(polygon
			(pts
				(arc
					(start 92.039694 -393.292838)
					(mid 92.344494 -393.597638)
					(end 92.649294 -393.292838)
				)
				(arc
					(start 92.649294 -392.429238)
					(mid 92.344494 -392.124438)
					(end 92.039694 -392.429238)
				)
			)
		)
	)
	(zone
		(layers "In1.Cu" "In3.Cu" "In5.Cu" "In7.Cu" "In8.Cu" "In9.Cu" "In10.Cu"
			"In12.Cu"
		)
		(hatch none 0.5)
		(connect_pads
			(clearance 0)
		)
		(min_thickness 0.25)
		(keepout
			(tracks not_allowed)
			(vias allowed)
			(pads allowed)
			(copperpour not_allowed)
			(footprints allowed)
		)
		(placement
			(enabled no)
			(sheetname "")
		)
		(fill yes
			(thermal_gap 0.5)
			(thermal_bridge_width 0.5)
			(island_removal_mode 0)
		)
		(polygon
			(pts
				(arc
					(start 150.739348 -393.292838)
					(mid 151.044148 -393.597638)
					(end 151.348948 -393.292838)
				)
				(arc
					(start 151.348948 -392.429238)
					(mid 151.044148 -392.124438)
					(end 150.739348 -392.429238)
				)
			)
		)
	)
	(zone
		(layers "In1.Cu" "In3.Cu" "In5.Cu" "In7.Cu" "In8.Cu" "In9.Cu" "In10.Cu"
			"In12.Cu"
		)
		(hatch none 0.5)
		(connect_pads
			(clearance 0)
		)
		(min_thickness 0.25)
		(keepout
			(tracks not_allowed)
			(vias allowed)
			(pads allowed)
			(copperpour not_allowed)
			(footprints allowed)
		)
		(placement
			(enabled no)
			(sheetname "")
		)
		(fill yes
			(thermal_gap 0.5)
			(thermal_bridge_width 0.5)
			(island_removal_mode 0)
		)
		(polygon
			(pts
				(arc
					(start 81.23936 -393.292838)
					(mid 81.54416 -393.597638)
					(end 81.84896 -393.292838)
				)
				(arc
					(start 81.84896 -392.429238)
					(mid 81.54416 -392.124438)
					(end 81.23936 -392.429238)
				)
			)
		)
	)
	(zone
		(layers "In1.Cu" "In3.Cu" "In5.Cu" "In7.Cu" "In8.Cu" "In9.Cu" "In10.Cu"
			"In12.Cu"
		)
		(hatch none 0.5)
		(connect_pads
			(clearance 0)
		)
		(min_thickness 0.25)
		(keepout
			(tracks not_allowed)
			(vias allowed)
			(pads allowed)
			(copperpour not_allowed)
			(footprints allowed)
		)
		(placement
			(enabled no)
			(sheetname "")
		)
		(fill yes
			(thermal_gap 0.5)
			(thermal_bridge_width 0.5)
			(island_removal_mode 0)
		)
		(polygon
			(pts
				(arc
					(start 157.939486 -393.292838)
					(mid 158.244286 -393.597638)
					(end 158.549086 -393.292838)
				)
				(arc
					(start 158.549086 -392.429238)
					(mid 158.244286 -392.124438)
					(end 157.939486 -392.429238)
				)
			)
		)
	)
	(zone
		(layers "In1.Cu" "In3.Cu" "In5.Cu" "In7.Cu" "In8.Cu" "In9.Cu" "In10.Cu"
			"In12.Cu"
		)
		(hatch none 0.5)
		(connect_pads
			(clearance 0)
		)
		(min_thickness 0.25)
		(keepout
			(tracks not_allowed)
			(vias allowed)
			(pads allowed)
			(copperpour not_allowed)
			(footprints allowed)
		)
		(placement
			(enabled no)
			(sheetname "")
		)
		(fill yes
			(thermal_gap 0.5)
			(thermal_bridge_width 0.5)
			(island_removal_mode 0)
		)
		(polygon
			(pts
				(arc
					(start 87.239602 -393.292838)
					(mid 87.544402 -393.597638)
					(end 87.849202 -393.292838)
				)
				(arc
					(start 87.849202 -392.429238)
					(mid 87.544402 -392.124438)
					(end 87.239602 -392.429238)
				)
			)
		)
	)
	(zone
		(layers "In1.Cu" "In3.Cu" "In5.Cu" "In7.Cu" "In8.Cu" "In9.Cu" "In10.Cu"
			"In12.Cu"
		)
		(hatch none 0.5)
		(connect_pads
			(clearance 0)
		)
		(min_thickness 0.25)
		(keepout
			(tracks not_allowed)
			(vias allowed)
			(pads allowed)
			(copperpour not_allowed)
			(footprints allowed)
		)
		(placement
			(enabled no)
			(sheetname "")
		)
		(fill yes
			(thermal_gap 0.5)
			(thermal_bridge_width 0.5)
			(island_removal_mode 0)
		)
		(polygon
			(pts
				(arc
					(start 156.73959 -393.292838)
					(mid 157.04439 -393.597638)
					(end 157.34919 -393.292838)
				)
				(arc
					(start 157.34919 -392.429238)
					(mid 157.04439 -392.124438)
					(end 156.73959 -392.429238)
				)
			)
		)
	)
	(zone
		(layers "In1.Cu" "In3.Cu" "In5.Cu" "In7.Cu" "In8.Cu" "In9.Cu" "In10.Cu"
			"In12.Cu"
		)
		(hatch none 0.5)
		(connect_pads
			(clearance 0)
		)
		(min_thickness 0.25)
		(keepout
			(tracks not_allowed)
			(vias allowed)
			(pads allowed)
			(copperpour not_allowed)
			(footprints allowed)
		)
		(placement
			(enabled no)
			(sheetname "")
		)
		(fill yes
			(thermal_gap 0.5)
			(thermal_bridge_width 0.5)
			(island_removal_mode 0)
		)
		(polygon
			(pts
				(arc
					(start 147.139406 -393.292838)
					(mid 147.444206 -393.597638)
					(end 147.749006 -393.292838)
				)
				(arc
					(start 147.749006 -392.429238)
					(mid 147.444206 -392.124438)
					(end 147.139406 -392.429238)
				)
			)
		)
	)
	(zone
		(layers "In1.Cu" "In3.Cu" "In5.Cu" "In7.Cu" "In8.Cu" "In9.Cu" "In10.Cu"
			"In12.Cu"
		)
		(hatch none 0.5)
		(connect_pads
			(clearance 0)
		)
		(min_thickness 0.25)
		(keepout
			(tracks not_allowed)
			(vias allowed)
			(pads allowed)
			(copperpour not_allowed)
			(footprints allowed)
		)
		(placement
			(enabled no)
			(sheetname "")
		)
		(fill yes
			(thermal_gap 0.5)
			(thermal_bridge_width 0.5)
			(island_removal_mode 0)
		)
		(polygon
			(pts
				(arc
					(start 88.439498 -393.292838)
					(mid 88.744298 -393.597638)
					(end 89.049098 -393.292838)
				)
				(arc
					(start 89.049098 -392.429238)
					(mid 88.744298 -392.124438)
					(end 88.439498 -392.429238)
				)
			)
		)
	)
	(zone
		(layers "In1.Cu" "In3.Cu" "In5.Cu" "In7.Cu" "In8.Cu" "In9.Cu" "In10.Cu"
			"In12.Cu"
		)
		(hatch none 0.5)
		(connect_pads
			(clearance 0)
		)
		(min_thickness 0.25)
		(keepout
			(tracks not_allowed)
			(vias allowed)
			(pads allowed)
			(copperpour not_allowed)
			(footprints allowed)
		)
		(placement
			(enabled no)
			(sheetname "")
		)
		(fill yes
			(thermal_gap 0.5)
			(thermal_bridge_width 0.5)
			(island_removal_mode 0)
		)
		(polygon
			(pts
				(arc
					(start 413.939482 -401.674838)
					(mid 414.244282 -401.979638)
					(end 414.549082 -401.674838)
				)
				(arc
					(start 414.549082 -400.811238)
					(mid 414.244282 -400.506438)
					(end 413.939482 -400.811238)
				)
			)
		)
	)
	(zone
		(layers "In1.Cu" "In3.Cu" "In5.Cu" "In7.Cu" "In8.Cu" "In9.Cu" "In10.Cu"
			"In12.Cu"
		)
		(hatch none 0.5)
		(connect_pads
			(clearance 0)
		)
		(min_thickness 0.25)
		(keepout
			(tracks not_allowed)
			(vias allowed)
			(pads allowed)
			(copperpour not_allowed)
			(footprints allowed)
		)
		(placement
			(enabled no)
			(sheetname "")
		)
		(fill yes
			(thermal_gap 0.5)
			(thermal_bridge_width 0.5)
			(island_removal_mode 0)
		)
		(polygon
			(pts
				(arc
					(start 406.739344 -401.674838)
					(mid 407.044144 -401.979638)
					(end 407.348944 -401.674838)
				)
				(arc
					(start 407.348944 -400.811238)
					(mid 407.044144 -400.506438)
					(end 406.739344 -400.811238)
				)
			)
		)
	)
	(zone
		(layers "In1.Cu" "In3.Cu" "In5.Cu" "In7.Cu" "In8.Cu" "In9.Cu" "In10.Cu"
			"In12.Cu"
		)
		(hatch none 0.5)
		(connect_pads
			(clearance 0)
		)
		(min_thickness 0.25)
		(keepout
			(tracks not_allowed)
			(vias allowed)
			(pads allowed)
			(copperpour not_allowed)
			(footprints allowed)
		)
		(placement
			(enabled no)
			(sheetname "")
		)
		(fill yes
			(thermal_gap 0.5)
			(thermal_bridge_width 0.5)
			(island_removal_mode 0)
		)
		(polygon
			(pts
				(arc
					(start 418.73932 -401.674838)
					(mid 419.04412 -401.979638)
					(end 419.34892 -401.674838)
				)
				(arc
					(start 419.34892 -400.811238)
					(mid 419.04412 -400.506438)
					(end 418.73932 -400.811238)
				)
			)
		)
	)
	(zone
		(layers "In1.Cu" "In3.Cu" "In5.Cu" "In7.Cu" "In8.Cu" "In9.Cu" "In10.Cu"
			"In12.Cu"
		)
		(hatch none 0.5)
		(connect_pads
			(clearance 0)
		)
		(min_thickness 0.25)
		(keepout
			(tracks not_allowed)
			(vias allowed)
			(pads allowed)
			(copperpour not_allowed)
			(footprints allowed)
		)
		(placement
			(enabled no)
			(sheetname "")
		)
		(fill yes
			(thermal_gap 0.5)
			(thermal_bridge_width 0.5)
			(island_removal_mode 0)
		)
		(polygon
			(pts
				(arc
					(start 95.639382 -393.292838)
					(mid 95.944182 -393.597638)
					(end 96.248982 -393.292838)
				)
				(arc
					(start 96.248982 -392.429238)
					(mid 95.944182 -392.124438)
					(end 95.639382 -392.429238)
				)
			)
		)
	)
	(zone
		(layers "In1.Cu" "In3.Cu" "In5.Cu" "In7.Cu" "In8.Cu" "In9.Cu" "In10.Cu"
			"In12.Cu"
		)
		(hatch none 0.5)
		(connect_pads
			(clearance 0)
		)
		(min_thickness 0.25)
		(keepout
			(tracks not_allowed)
			(vias allowed)
			(pads allowed)
			(copperpour not_allowed)
			(footprints allowed)
		)
		(placement
			(enabled no)
			(sheetname "")
		)
		(fill yes
			(thermal_gap 0.5)
			(thermal_bridge_width 0.5)
			(island_removal_mode 0)
		)
		(polygon
			(pts
				(arc
					(start 308.31155 -401.674838)
					(mid 308.61635 -401.979638)
					(end 308.92115 -401.674838)
				)
				(arc
					(start 308.92115 -400.811238)
					(mid 308.61635 -400.506438)
					(end 308.31155 -400.811238)
				)
			)
		)
	)
	(zone
		(layers "In1.Cu" "In3.Cu" "In5.Cu" "In7.Cu" "In8.Cu" "In9.Cu" "In10.Cu"
			"In12.Cu"
		)
		(hatch none 0.5)
		(connect_pads
			(clearance 0)
		)
		(min_thickness 0.25)
		(keepout
			(tracks not_allowed)
			(vias allowed)
			(pads allowed)
			(copperpour not_allowed)
			(footprints allowed)
		)
		(placement
			(enabled no)
			(sheetname "")
		)
		(fill yes
			(thermal_gap 0.5)
			(thermal_bridge_width 0.5)
			(island_removal_mode 0)
		)
		(polygon
			(pts
				(arc
					(start 149.539452 -393.292838)
					(mid 149.844252 -393.597638)
					(end 150.149052 -393.292838)
				)
				(arc
					(start 150.149052 -392.429238)
					(mid 149.844252 -392.124438)
					(end 149.539452 -392.429238)
				)
			)
		)
	)
	(zone
		(layers "In1.Cu" "In3.Cu" "In5.Cu" "In7.Cu" "In8.Cu" "In9.Cu" "In10.Cu"
			"In12.Cu"
		)
		(hatch none 0.5)
		(connect_pads
			(clearance 0)
		)
		(min_thickness 0.25)
		(keepout
			(tracks not_allowed)
			(vias allowed)
			(pads allowed)
			(copperpour not_allowed)
			(footprints allowed)
		)
		(placement
			(enabled no)
			(sheetname "")
		)
		(fill yes
			(thermal_gap 0.5)
			(thermal_bridge_width 0.5)
			(island_removal_mode 0)
		)
		(polygon
			(pts
				(arc
					(start 84.839556 -393.292838)
					(mid 85.144356 -393.597638)
					(end 85.449156 -393.292838)
				)
				(arc
					(start 85.449156 -392.429238)
					(mid 85.144356 -392.124438)
					(end 84.839556 -392.429238)
				)
			)
		)
	)
	(zone
		(layers "In1.Cu" "In3.Cu" "In5.Cu" "In7.Cu" "In8.Cu" "In9.Cu" "In10.Cu"
			"In12.Cu"
		)
		(hatch none 0.5)
		(connect_pads
			(clearance 0)
		)
		(min_thickness 0.25)
		(keepout
			(tracks not_allowed)
			(vias allowed)
			(pads allowed)
			(copperpour not_allowed)
			(footprints allowed)
		)
		(placement
			(enabled no)
			(sheetname "")
		)
		(fill yes
			(thermal_gap 0.5)
			(thermal_bridge_width 0.5)
			(island_removal_mode 0)
		)
		(polygon
			(pts
				(arc
					(start 313.111642 -401.674838)
					(mid 313.416442 -401.979638)
					(end 313.721242 -401.674838)
				)
				(arc
					(start 313.721242 -400.811238)
					(mid 313.416442 -400.506438)
					(end 313.111642 -400.811238)
				)
			)
		)
	)
	(zone
		(layers "In1.Cu" "In3.Cu" "In5.Cu" "In7.Cu" "In8.Cu" "In9.Cu" "In10.Cu"
			"In12.Cu"
		)
		(hatch none 0.5)
		(connect_pads
			(clearance 0)
		)
		(min_thickness 0.25)
		(keepout
			(tracks not_allowed)
			(vias allowed)
			(pads allowed)
			(copperpour not_allowed)
			(footprints allowed)
		)
		(placement
			(enabled no)
			(sheetname "")
		)
		(fill yes
			(thermal_gap 0.5)
			(thermal_bridge_width 0.5)
			(island_removal_mode 0)
		)
		(polygon
			(pts
				(arc
					(start 309.511446 -401.674838)
					(mid 309.816246 -401.979638)
					(end 310.121046 -401.674838)
				)
				(arc
					(start 310.121046 -400.811238)
					(mid 309.816246 -400.506438)
					(end 309.511446 -400.811238)
				)
			)
		)
	)
	(zone
		(layers "In1.Cu" "In3.Cu" "In5.Cu" "In7.Cu" "In8.Cu" "In9.Cu" "In10.Cu"
			"In12.Cu"
		)
		(hatch none 0.5)
		(connect_pads
			(clearance 0)
		)
		(min_thickness 0.25)
		(keepout
			(tracks not_allowed)
			(vias allowed)
			(pads allowed)
			(copperpour not_allowed)
			(footprints allowed)
		)
		(placement
			(enabled no)
			(sheetname "")
		)
		(fill yes
			(thermal_gap 0.5)
			(thermal_bridge_width 0.5)
			(island_removal_mode 0)
		)
		(polygon
			(pts
				(arc
					(start 96.839532 -393.292838)
					(mid 97.144332 -393.597638)
					(end 97.449132 -393.292838)
				)
				(arc
					(start 97.449132 -392.429238)
					(mid 97.144332 -392.124438)
					(end 96.839532 -392.429238)
				)
			)
		)
	)
	(zone
		(layers "In1.Cu" "In3.Cu" "In5.Cu" "In7.Cu" "In8.Cu" "In9.Cu" "In10.Cu"
			"In12.Cu"
		)
		(hatch none 0.5)
		(connect_pads
			(clearance 0)
		)
		(min_thickness 0.25)
		(keepout
			(tracks not_allowed)
			(vias allowed)
			(pads allowed)
			(copperpour not_allowed)
			(footprints allowed)
		)
		(placement
			(enabled no)
			(sheetname "")
		)
		(fill yes
			(thermal_gap 0.5)
			(thermal_bridge_width 0.5)
			(island_removal_mode 0)
		)
		(polygon
			(pts
				(arc
					(start 89.639648 -393.292838)
					(mid 89.944448 -393.597638)
					(end 90.249248 -393.292838)
				)
				(arc
					(start 90.249248 -392.429238)
					(mid 89.944448 -392.124438)
					(end 89.639648 -392.429238)
				)
			)
		)
	)
	(zone
		(layers "In1.Cu" "In3.Cu" "In5.Cu" "In7.Cu" "In8.Cu" "In9.Cu" "In10.Cu"
			"In12.Cu"
		)
		(hatch none 0.5)
		(connect_pads
			(clearance 0)
		)
		(min_thickness 0.25)
		(keepout
			(tracks not_allowed)
			(vias allowed)
			(pads allowed)
			(copperpour not_allowed)
			(footprints allowed)
		)
		(placement
			(enabled no)
			(sheetname "")
		)
		(fill yes
			(thermal_gap 0.5)
			(thermal_bridge_width 0.5)
			(island_removal_mode 0)
		)
		(polygon
			(pts
				(arc
					(start 303.511458 -401.674838)
					(mid 303.816258 -401.979638)
					(end 304.121058 -401.674838)
				)
				(arc
					(start 304.121058 -400.811238)
					(mid 303.816258 -400.506438)
					(end 303.511458 -400.811238)
				)
			)
		)
	)
	(zone
		(layers "In1.Cu" "In3.Cu" "In5.Cu" "In7.Cu" "In8.Cu" "In9.Cu" "In10.Cu"
			"In12.Cu"
		)
		(hatch none 0.5)
		(connect_pads
			(clearance 0)
		)
		(min_thickness 0.25)
		(keepout
			(tracks not_allowed)
			(vias allowed)
			(pads allowed)
			(copperpour not_allowed)
			(footprints allowed)
		)
		(placement
			(enabled no)
			(sheetname "")
		)
		(fill yes
			(thermal_gap 0.5)
			(thermal_bridge_width 0.5)
			(island_removal_mode 0)
		)
		(polygon
			(pts
				(arc
					(start 315.511688 -401.674838)
					(mid 315.816488 -401.979638)
					(end 316.121288 -401.674838)
				)
				(arc
					(start 316.121288 -400.811238)
					(mid 315.816488 -400.506438)
					(end 315.511688 -400.811238)
				)
			)
		)
	)
	(zone
		(layers "In1.Cu" "In3.Cu" "In5.Cu" "In7.Cu" "In8.Cu" "In9.Cu" "In10.Cu"
			"In12.Cu"
		)
		(hatch none 0.5)
		(connect_pads
			(clearance 0)
		)
		(min_thickness 0.25)
		(keepout
			(tracks not_allowed)
			(vias allowed)
			(pads allowed)
			(copperpour not_allowed)
			(footprints allowed)
		)
		(placement
			(enabled no)
			(sheetname "")
		)
		(fill yes
			(thermal_gap 0.5)
			(thermal_bridge_width 0.5)
			(island_removal_mode 0)
		)
		(polygon
			(pts
				(arc
					(start 403.139402 -401.674838)
					(mid 403.444202 -401.979638)
					(end 403.749002 -401.674838)
				)
				(arc
					(start 403.749002 -400.811238)
					(mid 403.444202 -400.506438)
					(end 403.139402 -400.811238)
				)
			)
		)
	)
	(zone
		(layers "In1.Cu" "In3.Cu" "In5.Cu" "In7.Cu" "In8.Cu" "In9.Cu" "In10.Cu"
			"In12.Cu"
		)
		(hatch none 0.5)
		(connect_pads
			(clearance 0)
		)
		(min_thickness 0.25)
		(keepout
			(tracks not_allowed)
			(vias allowed)
			(pads allowed)
			(copperpour not_allowed)
			(footprints allowed)
		)
		(placement
			(enabled no)
			(sheetname "")
		)
		(fill yes
			(thermal_gap 0.5)
			(thermal_bridge_width 0.5)
			(island_removal_mode 0)
		)
		(polygon
			(pts
				(arc
					(start 159.139636 -393.292838)
					(mid 159.444436 -393.597638)
					(end 159.749236 -393.292838)
				)
				(arc
					(start 159.749236 -392.429238)
					(mid 159.444436 -392.124438)
					(end 159.139636 -392.429238)
				)
			)
		)
	)
	(zone
		(layers "In1.Cu" "In3.Cu" "In5.Cu" "In7.Cu" "In8.Cu" "In9.Cu" "In10.Cu"
			"In12.Cu"
		)
		(hatch none 0.5)
		(connect_pads
			(clearance 0)
		)
		(min_thickness 0.25)
		(keepout
			(tracks not_allowed)
			(vias allowed)
			(pads allowed)
			(copperpour not_allowed)
			(footprints allowed)
		)
		(placement
			(enabled no)
			(sheetname "")
		)
		(fill yes
			(thermal_gap 0.5)
			(thermal_bridge_width 0.5)
			(island_removal_mode 0)
		)
		(polygon
			(pts
				(arc
					(start 404.339298 -401.674838)
					(mid 404.644098 -401.979638)
					(end 404.948898 -401.674838)
				)
				(arc
					(start 404.948898 -400.811238)
					(mid 404.644098 -400.506438)
					(end 404.339298 -400.811238)
				)
			)
		)
	)
	(zone
		(layers "In1.Cu" "In3.Cu" "In5.Cu" "In7.Cu" "In8.Cu" "In9.Cu" "In10.Cu"
			"In12.Cu"
		)
		(hatch none 0.5)
		(connect_pads
			(clearance 0)
		)
		(min_thickness 0.25)
		(keepout
			(tracks not_allowed)
			(vias allowed)
			(pads allowed)
			(copperpour not_allowed)
			(footprints allowed)
		)
		(placement
			(enabled no)
			(sheetname "")
		)
		(fill yes
			(thermal_gap 0.5)
			(thermal_bridge_width 0.5)
			(island_removal_mode 0)
		)
		(polygon
			(pts
				(arc
					(start 321.511422 -401.674838)
					(mid 321.816222 -401.979638)
					(end 322.121022 -401.674838)
				)
				(arc
					(start 322.121022 -400.811238)
					(mid 321.816222 -400.506438)
					(end 321.511422 -400.811238)
				)
			)
		)
	)
	(zone
		(layers "In1.Cu" "In3.Cu" "In5.Cu" "In7.Cu" "In8.Cu" "In9.Cu" "In10.Cu"
			"In12.Cu"
		)
		(hatch none 0.5)
		(connect_pads
			(clearance 0)
		)
		(min_thickness 0.25)
		(keepout
			(tracks not_allowed)
			(vias allowed)
			(pads allowed)
			(copperpour not_allowed)
			(footprints allowed)
		)
		(placement
			(enabled no)
			(sheetname "")
		)
		(fill yes
			(thermal_gap 0.5)
			(thermal_bridge_width 0.5)
			(island_removal_mode 0)
		)
		(polygon
			(pts
				(arc
					(start 154.339544 -393.292838)
					(mid 154.644344 -393.597638)
					(end 154.949144 -393.292838)
				)
				(arc
					(start 154.949144 -392.429238)
					(mid 154.644344 -392.124438)
					(end 154.339544 -392.429238)
				)
			)
		)
	)
	(zone
		(layers "In1.Cu" "In3.Cu" "In5.Cu" "In7.Cu" "In8.Cu" "In9.Cu" "In10.Cu"
			"In12.Cu"
		)
		(hatch none 0.5)
		(connect_pads
			(clearance 0)
		)
		(min_thickness 0.25)
		(keepout
			(tracks not_allowed)
			(vias allowed)
			(pads allowed)
			(copperpour not_allowed)
			(footprints allowed)
		)
		(placement
			(enabled no)
			(sheetname "")
		)
		(fill yes
			(thermal_gap 0.5)
			(thermal_bridge_width 0.5)
			(island_removal_mode 0)
		)
		(polygon
			(pts
				(arc
					(start 94.439486 -393.292838)
					(mid 94.744286 -393.597638)
					(end 95.049086 -393.292838)
				)
				(arc
					(start 95.049086 -392.429238)
					(mid 94.744286 -392.124438)
					(end 94.439486 -392.429238)
				)
			)
		)
	)
	(zone
		(layers "In1.Cu" "In3.Cu" "In5.Cu" "In7.Cu" "In8.Cu" "In9.Cu" "In10.Cu"
			"In12.Cu"
		)
		(hatch none 0.5)
		(connect_pads
			(clearance 0)
		)
		(min_thickness 0.25)
		(keepout
			(tracks not_allowed)
			(vias allowed)
			(pads allowed)
			(copperpour not_allowed)
			(footprints allowed)
		)
		(placement
			(enabled no)
			(sheetname "")
		)
		(fill yes
			(thermal_gap 0.5)
			(thermal_bridge_width 0.5)
			(island_removal_mode 0)
		)
		(polygon
			(pts
				(arc
					(start 320.311526 -401.674838)
					(mid 320.616326 -401.979638)
					(end 320.921126 -401.674838)
				)
				(arc
					(start 320.921126 -400.811238)
					(mid 320.616326 -400.506438)
					(end 320.311526 -400.811238)
				)
			)
		)
	)
	(zone
		(layers "In1.Cu" "In3.Cu" "In5.Cu" "In7.Cu" "In8.Cu" "In9.Cu" "In10.Cu"
			"In12.Cu"
		)
		(hatch none 0.5)
		(connect_pads
			(clearance 0)
		)
		(min_thickness 0.25)
		(keepout
			(tracks not_allowed)
			(vias allowed)
			(pads allowed)
			(copperpour not_allowed)
			(footprints allowed)
		)
		(placement
			(enabled no)
			(sheetname "")
		)
		(fill yes
			(thermal_gap 0.5)
			(thermal_bridge_width 0.5)
			(island_removal_mode 0)
		)
		(polygon
			(pts
				(arc
					(start 409.13939 -401.674838)
					(mid 409.44419 -401.979638)
					(end 409.74899 -401.674838)
				)
				(arc
					(start 409.74899 -400.811238)
					(mid 409.44419 -400.506438)
					(end 409.13939 -400.811238)
				)
			)
		)
	)
	(zone
		(layers "In1.Cu" "In3.Cu" "In5.Cu" "In7.Cu" "In8.Cu" "In9.Cu" "In10.Cu"
			"In12.Cu"
		)
		(hatch none 0.5)
		(connect_pads
			(clearance 0)
		)
		(min_thickness 0.25)
		(keepout
			(tracks not_allowed)
			(vias allowed)
			(pads allowed)
			(copperpour not_allowed)
			(footprints allowed)
		)
		(placement
			(enabled no)
			(sheetname "")
		)
		(fill yes
			(thermal_gap 0.5)
			(thermal_bridge_width 0.5)
			(island_removal_mode 0)
		)
		(polygon
			(pts
				(arc
					(start 82.43951 -393.292838)
					(mid 82.74431 -393.597638)
					(end 83.04911 -393.292838)
				)
				(arc
					(start 83.04911 -392.429238)
					(mid 82.74431 -392.124438)
					(end 82.43951 -392.429238)
				)
			)
		)
	)
	(zone
		(layers "In1.Cu" "In3.Cu" "In5.Cu" "In7.Cu" "In8.Cu" "In9.Cu" "In10.Cu"
			"In12.Cu"
		)
		(hatch none 0.5)
		(connect_pads
			(clearance 0)
		)
		(min_thickness 0.25)
		(keepout
			(tracks not_allowed)
			(vias allowed)
			(pads allowed)
			(copperpour not_allowed)
			(footprints allowed)
		)
		(placement
			(enabled no)
			(sheetname "")
		)
		(fill yes
			(thermal_gap 0.5)
			(thermal_bridge_width 0.5)
			(island_removal_mode 0)
		)
		(polygon
			(pts
				(arc
					(start 319.111376 -401.674838)
					(mid 319.416176 -401.979638)
					(end 319.720976 -401.674838)
				)
				(arc
					(start 319.720976 -400.811238)
					(mid 319.416176 -400.506438)
					(end 319.111376 -400.811238)
				)
			)
		)
	)
	(zone
		(layers "In1.Cu" "In3.Cu" "In5.Cu" "In7.Cu" "In8.Cu" "In9.Cu" "In10.Cu"
			"In12.Cu"
		)
		(hatch none 0.5)
		(connect_pads
			(clearance 0)
		)
		(min_thickness 0.25)
		(keepout
			(tracks not_allowed)
			(vias allowed)
			(pads allowed)
			(copperpour not_allowed)
			(footprints allowed)
		)
		(placement
			(enabled no)
			(sheetname "")
		)
		(fill yes
			(thermal_gap 0.5)
			(thermal_bridge_width 0.5)
			(island_removal_mode 0)
		)
		(polygon
			(pts
				(arc
					(start 411.539436 -401.674838)
					(mid 411.844236 -401.979638)
					(end 412.149036 -401.674838)
				)
				(arc
					(start 412.149036 -400.811238)
					(mid 411.844236 -400.506438)
					(end 411.539436 -400.811238)
				)
			)
		)
	)
	(zone
		(layers "In1.Cu" "In3.Cu" "In5.Cu" "In7.Cu" "In8.Cu" "In9.Cu" "In10.Cu"
			"In12.Cu"
		)
		(hatch none 0.5)
		(connect_pads
			(clearance 0)
		)
		(min_thickness 0.25)
		(keepout
			(tracks not_allowed)
			(vias allowed)
			(pads allowed)
			(copperpour not_allowed)
			(footprints allowed)
		)
		(placement
			(enabled no)
			(sheetname "")
		)
		(fill yes
			(thermal_gap 0.5)
			(thermal_bridge_width 0.5)
			(island_removal_mode 0)
		)
		(polygon
			(pts
				(arc
					(start 98.039428 -393.292838)
					(mid 98.344228 -393.597638)
					(end 98.649028 -393.292838)
				)
				(arc
					(start 98.649028 -392.429238)
					(mid 98.344228 -392.124438)
					(end 98.039428 -392.429238)
				)
			)
		)
	)
	(zone
		(layers "In1.Cu" "In3.Cu" "In5.Cu" "In7.Cu" "In8.Cu" "In9.Cu" "In10.Cu"
			"In12.Cu"
		)
		(hatch none 0.5)
		(connect_pads
			(clearance 0)
		)
		(min_thickness 0.25)
		(keepout
			(tracks not_allowed)
			(vias allowed)
			(pads allowed)
			(copperpour not_allowed)
			(footprints allowed)
		)
		(placement
			(enabled no)
			(sheetname "")
		)
		(fill yes
			(thermal_gap 0.5)
			(thermal_bridge_width 0.5)
			(island_removal_mode 0)
		)
		(polygon
			(pts
				(arc
					(start 161.539428 -393.292838)
					(mid 161.844228 -393.597638)
					(end 162.149028 -393.292838)
				)
				(arc
					(start 162.149028 -392.429238)
					(mid 161.844228 -392.124438)
					(end 161.539428 -392.429238)
				)
			)
		)
	)
	(zone
		(layers "In1.Cu" "In3.Cu" "In5.Cu" "In7.Cu" "In8.Cu" "In9.Cu" "In10.Cu"
			"In12.Cu"
		)
		(hatch none 0.5)
		(connect_pads
			(clearance 0)
		)
		(min_thickness 0.25)
		(keepout
			(tracks not_allowed)
			(vias allowed)
			(pads allowed)
			(copperpour not_allowed)
			(footprints allowed)
		)
		(placement
			(enabled no)
			(sheetname "")
		)
		(fill yes
			(thermal_gap 0.5)
			(thermal_bridge_width 0.5)
			(island_removal_mode 0)
		)
		(polygon
			(pts
				(arc
					(start 90.839544 -393.292838)
					(mid 91.144344 -393.597638)
					(end 91.449144 -393.292838)
				)
				(arc
					(start 91.449144 -392.429238)
					(mid 91.144344 -392.124438)
					(end 90.839544 -392.429238)
				)
			)
		)
	)
	(zone
		(layers "In1.Cu" "In3.Cu" "In5.Cu" "In7.Cu" "In8.Cu" "In9.Cu" "In10.Cu"
			"In12.Cu"
		)
		(hatch none 0.5)
		(connect_pads
			(clearance 0)
		)
		(min_thickness 0.25)
		(keepout
			(tracks not_allowed)
			(vias allowed)
			(pads allowed)
			(copperpour not_allowed)
			(footprints allowed)
		)
		(placement
			(enabled no)
			(sheetname "")
		)
		(fill yes
			(thermal_gap 0.5)
			(thermal_bridge_width 0.5)
			(island_removal_mode 0)
		)
		(polygon
			(pts
				(arc
					(start 153.139394 -393.292838)
					(mid 153.444194 -393.597638)
					(end 153.748994 -393.292838)
				)
				(arc
					(start 153.748994 -392.429238)
					(mid 153.444194 -392.124438)
					(end 153.139394 -392.429238)
				)
			)
		)
	)
	(zone
		(layers "In1.Cu" "In3.Cu" "In5.Cu" "In7.Cu" "In8.Cu" "In9.Cu" "In10.Cu"
			"In12.Cu"
		)
		(hatch none 0.5)
		(connect_pads
			(clearance 0)
		)
		(min_thickness 0.25)
		(keepout
			(tracks not_allowed)
			(vias allowed)
			(pads allowed)
			(copperpour not_allowed)
			(footprints allowed)
		)
		(placement
			(enabled no)
			(sheetname "")
		)
		(fill yes
			(thermal_gap 0.5)
			(thermal_bridge_width 0.5)
			(island_removal_mode 0)
		)
		(polygon
			(pts
				(arc
					(start 86.039452 -393.292838)
					(mid 86.344252 -393.597638)
					(end 86.649052 -393.292838)
				)
				(arc
					(start 86.649052 -392.429238)
					(mid 86.344252 -392.124438)
					(end 86.039452 -392.429238)
				)
			)
		)
	)
	(zone
		(layers "In1.Cu" "In3.Cu" "In5.Cu" "In7.Cu" "In8.Cu" "In9.Cu" "In10.Cu"
			"In12.Cu"
		)
		(hatch none 0.5)
		(connect_pads
			(clearance 0)
		)
		(min_thickness 0.25)
		(keepout
			(tracks not_allowed)
			(vias allowed)
			(pads allowed)
			(copperpour not_allowed)
			(footprints allowed)
		)
		(placement
			(enabled no)
			(sheetname "")
		)
		(fill yes
			(thermal_gap 0.5)
			(thermal_bridge_width 0.5)
			(island_removal_mode 0)
		)
		(polygon
			(pts
				(arc
					(start 419.93947 -401.674838)
					(mid 420.24427 -401.979638)
					(end 420.54907 -401.674838)
				)
				(arc
					(start 420.54907 -400.811238)
					(mid 420.24427 -400.506438)
					(end 419.93947 -400.811238)
				)
			)
		)
	)
	(zone
		(layers "In1.Cu" "In3.Cu" "In5.Cu" "In7.Cu" "In8.Cu" "In9.Cu" "In10.Cu"
			"In12.Cu"
		)
		(hatch none 0.5)
		(connect_pads
			(clearance 0)
		)
		(min_thickness 0.25)
		(keepout
			(tracks not_allowed)
			(vias allowed)
			(pads allowed)
			(copperpour not_allowed)
			(footprints allowed)
		)
		(placement
			(enabled no)
			(sheetname "")
		)
		(fill yes
			(thermal_gap 0.5)
			(thermal_bridge_width 0.5)
			(island_removal_mode 0)
		)
		(polygon
			(pts
				(arc
					(start 316.711584 -401.674838)
					(mid 317.016384 -401.979638)
					(end 317.321184 -401.674838)
				)
				(arc
					(start 317.321184 -400.811238)
					(mid 317.016384 -400.506438)
					(end 316.711584 -400.811238)
				)
			)
		)
	)
	(zone
		(layers "In1.Cu" "In3.Cu" "In5.Cu" "In7.Cu" "In8.Cu" "In9.Cu" "In10.Cu"
			"In12.Cu"
		)
		(hatch none 0.5)
		(connect_pads
			(clearance 0)
		)
		(min_thickness 0.25)
		(keepout
			(tracks not_allowed)
			(vias allowed)
			(pads allowed)
			(copperpour not_allowed)
			(footprints allowed)
		)
		(placement
			(enabled no)
			(sheetname "")
		)
		(fill yes
			(thermal_gap 0.5)
			(thermal_bridge_width 0.5)
			(island_removal_mode 0)
		)
		(polygon
			(pts
				(arc
					(start 163.939474 -393.292838)
					(mid 164.244274 -393.597638)
					(end 164.549074 -393.292838)
				)
				(arc
					(start 164.549074 -392.429238)
					(mid 164.244274 -392.124438)
					(end 163.939474 -392.429238)
				)
			)
		)
	)
	(zone
		(layers "In1.Cu" "In3.Cu" "In5.Cu" "In7.Cu" "In8.Cu" "In9.Cu" "In10.Cu"
			"In12.Cu"
		)
		(hatch none 0.5)
		(connect_pads
			(clearance 0)
		)
		(min_thickness 0.25)
		(keepout
			(tracks not_allowed)
			(vias allowed)
			(pads allowed)
			(copperpour not_allowed)
			(footprints allowed)
		)
		(placement
			(enabled no)
			(sheetname "")
		)
		(fill yes
			(thermal_gap 0.5)
			(thermal_bridge_width 0.5)
			(island_removal_mode 0)
		)
		(polygon
			(pts
				(arc
					(start 162.739324 -393.292838)
					(mid 163.044124 -393.597638)
					(end 163.348924 -393.292838)
				)
				(arc
					(start 163.348924 -392.429238)
					(mid 163.044124 -392.124438)
					(end 162.739324 -392.429238)
				)
			)
		)
	)
	(zone
		(layers "In1.Cu" "In3.Cu" "In5.Cu" "In7.Cu" "In8.Cu" "In9.Cu" "In10.Cu"
			"In12.Cu"
		)
		(hatch none 0.5)
		(connect_pads
			(clearance 0)
		)
		(min_thickness 0.25)
		(keepout
			(tracks not_allowed)
			(vias allowed)
			(pads allowed)
			(copperpour not_allowed)
			(footprints allowed)
		)
		(placement
			(enabled no)
			(sheetname "")
		)
		(fill yes
			(thermal_gap 0.5)
			(thermal_bridge_width 0.5)
			(island_removal_mode 0)
		)
		(polygon
			(pts
				(arc
					(start 83.639406 -393.292838)
					(mid 83.944206 -393.597638)
					(end 84.249006 -393.292838)
				)
				(arc
					(start 84.249006 -392.429238)
					(mid 83.944206 -392.124438)
					(end 83.639406 -392.429238)
				)
			)
		)
	)
	(zone
		(layers "In1.Cu" "In3.Cu" "In5.Cu" "In7.Cu" "In8.Cu" "In9.Cu" "In10.Cu"
			"In12.Cu"
		)
		(hatch none 0.5)
		(connect_pads
			(clearance 0)
		)
		(min_thickness 0.25)
		(keepout
			(tracks not_allowed)
			(vias allowed)
			(pads allowed)
			(copperpour not_allowed)
			(footprints allowed)
		)
		(placement
			(enabled no)
			(sheetname "")
		)
		(fill yes
			(thermal_gap 0.5)
			(thermal_bridge_width 0.5)
			(island_removal_mode 0)
		)
		(polygon
			(pts
				(arc
					(start 160.339532 -393.292838)
					(mid 160.644332 -393.597638)
					(end 160.949132 -393.292838)
				)
				(arc
					(start 160.949132 -392.429238)
					(mid 160.644332 -392.124438)
					(end 160.339532 -392.429238)
				)
			)
		)
	)
	(zone
		(layers "In1.Cu" "In3.Cu" "In5.Cu" "In7.Cu" "In8.Cu" "In9.Cu" "In10.Cu"
			"In12.Cu"
		)
		(hatch none 0.5)
		(connect_pads
			(clearance 0)
		)
		(min_thickness 0.25)
		(keepout
			(tracks not_allowed)
			(vias allowed)
			(pads allowed)
			(copperpour not_allowed)
			(footprints allowed)
		)
		(placement
			(enabled no)
			(sheetname "")
		)
		(fill yes
			(thermal_gap 0.5)
			(thermal_bridge_width 0.5)
			(island_removal_mode 0)
		)
		(polygon
			(pts
				(arc
					(start 417.539424 -401.674838)
					(mid 417.844224 -401.979638)
					(end 418.149024 -401.674838)
				)
				(arc
					(start 418.149024 -400.811238)
					(mid 417.844224 -400.506438)
					(end 417.539424 -400.811238)
				)
			)
		)
	)
	(zone
		(layers "In1.Cu" "In3.Cu" "In5.Cu" "In7.Cu" "In8.Cu" "In9.Cu" "In10.Cu"
			"In12.Cu"
		)
		(hatch none 0.5)
		(connect_pads
			(clearance 0)
		)
		(min_thickness 0.25)
		(keepout
			(tracks not_allowed)
			(vias allowed)
			(pads allowed)
			(copperpour not_allowed)
			(footprints allowed)
		)
		(placement
			(enabled no)
			(sheetname "")
		)
		(fill yes
			(thermal_gap 0.5)
			(thermal_bridge_width 0.5)
			(island_removal_mode 0)
		)
		(polygon
			(pts
				(arc
					(start 151.939498 -393.292838)
					(mid 152.244298 -393.597638)
					(end 152.549098 -393.292838)
				)
				(arc
					(start 152.549098 -392.429238)
					(mid 152.244298 -392.124438)
					(end 151.939498 -392.429238)
				)
			)
		)
	)
	(zone
		(layers "In1.Cu" "In3.Cu" "In5.Cu" "In7.Cu" "In8.Cu" "In9.Cu" "In10.Cu"
			"In12.Cu"
		)
		(hatch none 0.5)
		(connect_pads
			(clearance 0)
		)
		(min_thickness 0.25)
		(keepout
			(tracks not_allowed)
			(vias allowed)
			(pads allowed)
			(copperpour not_allowed)
			(footprints allowed)
		)
		(placement
			(enabled no)
			(sheetname "")
		)
		(fill yes
			(thermal_gap 0.5)
			(thermal_bridge_width 0.5)
			(island_removal_mode 0)
		)
		(polygon
			(pts
				(arc
					(start 415.139632 -401.674838)
					(mid 415.444432 -401.979638)
					(end 415.749232 -401.674838)
				)
				(arc
					(start 415.749232 -400.811238)
					(mid 415.444432 -400.506438)
					(end 415.139632 -400.811238)
				)
			)
		)
	)
	(zone
		(layers "In1.Cu" "In3.Cu" "In5.Cu" "In7.Cu" "In8.Cu" "In9.Cu" "In10.Cu"
			"In12.Cu" "In14.Cu" "In16.Cu"
		)
		(hatch none 0.5)
		(connect_pads
			(clearance 0)
		)
		(min_thickness 0.25)
		(keepout
			(tracks not_allowed)
			(vias allowed)
			(pads allowed)
			(copperpour not_allowed)
			(footprints allowed)
		)
		(placement
			(enabled no)
			(sheetname "")
		)
		(fill yes
			(thermal_gap 0.5)
			(thermal_bridge_width 0.5)
			(island_removal_mode 0)
		)
		(polygon
			(pts
				(arc
					(start 199.049386 -37.328094)
					(mid 197.271386 -37.328094)
					(end 199.049386 -37.328094)
				)
			)
		)
	)
	(zone
		(layers "In1.Cu" "In3.Cu" "In5.Cu" "In7.Cu" "In8.Cu" "In9.Cu" "In10.Cu"
			"In12.Cu" "In14.Cu" "In16.Cu"
		)
		(hatch none 0.5)
		(connect_pads
			(clearance 0)
		)
		(min_thickness 0.25)
		(keepout
			(tracks not_allowed)
			(vias allowed)
			(pads allowed)
			(copperpour not_allowed)
			(footprints allowed)
		)
		(placement
			(enabled no)
			(sheetname "")
		)
		(fill yes
			(thermal_gap 0.5)
			(thermal_bridge_width 0.5)
			(island_removal_mode 0)
		)
		(polygon
			(pts
				(arc
					(start 251.668534 -50.444146)
					(mid 249.890534 -50.444146)
					(end 251.668534 -50.444146)
				)
			)
		)
	)
	(zone
		(layers "In1.Cu" "In3.Cu" "In5.Cu" "In7.Cu" "In8.Cu" "In9.Cu" "In10.Cu"
			"In12.Cu" "In14.Cu" "In16.Cu"
		)
		(hatch none 0.5)
		(connect_pads
			(clearance 0)
		)
		(min_thickness 0.25)
		(keepout
			(tracks not_allowed)
			(vias allowed)
			(pads allowed)
			(copperpour not_allowed)
			(footprints allowed)
		)
		(placement
			(enabled no)
			(sheetname "")
		)
		(fill yes
			(thermal_gap 0.5)
			(thermal_bridge_width 0.5)
			(island_removal_mode 0)
		)
		(polygon
			(pts
				(arc
					(start 187.519818 -354.097844)
					(mid 185.741818 -354.097844)
					(end 187.519818 -354.097844)
				)
			)
		)
	)
	(zone
		(layers "In1.Cu" "In3.Cu" "In5.Cu" "In7.Cu" "In8.Cu" "In9.Cu" "In10.Cu"
			"In12.Cu" "In14.Cu" "In16.Cu"
		)
		(hatch none 0.5)
		(connect_pads
			(clearance 0)
		)
		(min_thickness 0.25)
		(keepout
			(tracks not_allowed)
			(vias allowed)
			(pads allowed)
			(copperpour not_allowed)
			(footprints allowed)
		)
		(placement
			(enabled no)
			(sheetname "")
		)
		(fill yes
			(thermal_gap 0.5)
			(thermal_bridge_width 0.5)
			(island_removal_mode 0)
		)
		(polygon
			(pts
				(arc
					(start 91.722194 -338.517484)
					(mid 89.944194 -338.517484)
					(end 91.722194 -338.517484)
				)
			)
		)
	)
	(zone
		(layers "In1.Cu" "In3.Cu" "In5.Cu" "In7.Cu" "In8.Cu" "In9.Cu" "In10.Cu"
			"In12.Cu" "In14.Cu" "In16.Cu"
		)
		(hatch none 0.5)
		(connect_pads
			(clearance 0)
		)
		(min_thickness 0.25)
		(keepout
			(tracks not_allowed)
			(vias allowed)
			(pads allowed)
			(copperpour not_allowed)
			(footprints allowed)
		)
		(placement
			(enabled no)
			(sheetname "")
		)
		(fill yes
			(thermal_gap 0.5)
			(thermal_bridge_width 0.5)
			(island_removal_mode 0)
		)
		(polygon
			(pts
				(arc
					(start 31.406084 -348.709488)
					(mid 29.645864 -348.709488)
					(end 31.406084 -348.709488)
				)
			)
		)
	)
	(zone
		(layers "In1.Cu" "In3.Cu" "In5.Cu" "In7.Cu" "In8.Cu" "In9.Cu" "In10.Cu"
			"In12.Cu" "In14.Cu" "In16.Cu"
		)
		(hatch none 0.5)
		(connect_pads
			(clearance 0)
		)
		(min_thickness 0.25)
		(keepout
			(tracks not_allowed)
			(vias allowed)
			(pads allowed)
			(copperpour not_allowed)
			(footprints allowed)
		)
		(placement
			(enabled no)
			(sheetname "")
		)
		(fill yes
			(thermal_gap 0.5)
			(thermal_bridge_width 0.5)
			(island_removal_mode 0)
		)
		(polygon
			(pts
				(arc
					(start 107.23245 -342.713564)
					(mid 105.45445 -342.713564)
					(end 107.23245 -342.713564)
				)
			)
		)
	)
	(zone
		(layers "In1.Cu" "In3.Cu" "In5.Cu" "In7.Cu" "In8.Cu" "In9.Cu" "In10.Cu"
			"In12.Cu" "In14.Cu" "In16.Cu"
		)
		(hatch none 0.5)
		(connect_pads
			(clearance 0)
		)
		(min_thickness 0.25)
		(keepout
			(tracks not_allowed)
			(vias allowed)
			(pads allowed)
			(copperpour not_allowed)
			(footprints allowed)
		)
		(placement
			(enabled no)
			(sheetname "")
		)
		(fill yes
			(thermal_gap 0.5)
			(thermal_bridge_width 0.5)
			(island_removal_mode 0)
		)
		(polygon
			(pts
				(arc
					(start 321.862196 -338.592668)
					(mid 320.084196 -338.592668)
					(end 321.862196 -338.592668)
				)
			)
		)
	)
	(zone
		(layers "In1.Cu" "In3.Cu" "In5.Cu" "In7.Cu" "In8.Cu" "In9.Cu" "In10.Cu"
			"In12.Cu" "In14.Cu" "In16.Cu"
		)
		(hatch none 0.5)
		(connect_pads
			(clearance 0)
		)
		(min_thickness 0.25)
		(keepout
			(tracks not_allowed)
			(vias allowed)
			(pads allowed)
			(copperpour not_allowed)
			(footprints allowed)
		)
		(placement
			(enabled no)
			(sheetname "")
		)
		(fill yes
			(thermal_gap 0.5)
			(thermal_bridge_width 0.5)
			(island_removal_mode 0)
		)
		(polygon
			(pts
				(arc
					(start 363.893608 -175.859186)
					(mid 362.133388 -175.859186)
					(end 363.893608 -175.859186)
				)
			)
		)
	)
	(zone
		(layers "In1.Cu" "In3.Cu" "In5.Cu" "In7.Cu" "In8.Cu" "In9.Cu" "In10.Cu"
			"In12.Cu" "In14.Cu" "In16.Cu"
		)
		(hatch none 0.5)
		(connect_pads
			(clearance 0)
		)
		(min_thickness 0.25)
		(keepout
			(tracks not_allowed)
			(vias allowed)
			(pads allowed)
			(copperpour not_allowed)
			(footprints allowed)
		)
		(placement
			(enabled no)
			(sheetname "")
		)
		(fill yes
			(thermal_gap 0.5)
			(thermal_bridge_width 0.5)
			(island_removal_mode 0)
		)
		(polygon
			(pts
				(arc
					(start 192.817496 -353.309174)
					(mid 191.057276 -353.309174)
					(end 192.817496 -353.309174)
				)
			)
		)
	)
	(zone
		(layers "In1.Cu" "In3.Cu" "In5.Cu" "In7.Cu" "In8.Cu" "In9.Cu" "In10.Cu"
			"In12.Cu" "In14.Cu" "In16.Cu"
		)
		(hatch none 0.5)
		(connect_pads
			(clearance 0)
		)
		(min_thickness 0.25)
		(keepout
			(tracks not_allowed)
			(vias allowed)
			(pads allowed)
			(copperpour not_allowed)
			(footprints allowed)
		)
		(placement
			(enabled no)
			(sheetname "")
		)
		(fill yes
			(thermal_gap 0.5)
			(thermal_bridge_width 0.5)
			(island_removal_mode 0)
		)
		(polygon
			(pts
				(arc
					(start 78.362048 -351.5995)
					(mid 76.584048 -351.5995)
					(end 78.362048 -351.5995)
				)
			)
		)
	)
	(zone
		(layers "In1.Cu" "In3.Cu" "In5.Cu" "In7.Cu" "In8.Cu" "In9.Cu" "In10.Cu"
			"In12.Cu" "In14.Cu" "In16.Cu"
		)
		(hatch none 0.5)
		(connect_pads
			(clearance 0)
		)
		(min_thickness 0.25)
		(keepout
			(tracks not_allowed)
			(vias allowed)
			(pads allowed)
			(copperpour not_allowed)
			(footprints allowed)
		)
		(placement
			(enabled no)
			(sheetname "")
		)
		(fill yes
			(thermal_gap 0.5)
			(thermal_bridge_width 0.5)
			(island_removal_mode 0)
		)
		(polygon
			(pts
				(arc
					(start 50.877978 -358.108504)
					(mid 49.099978 -358.108504)
					(end 50.877978 -358.108504)
				)
			)
		)
	)
	(zone
		(layers "In1.Cu" "In3.Cu" "In5.Cu" "In7.Cu" "In8.Cu" "In9.Cu" "In10.Cu"
			"In12.Cu" "In14.Cu" "In16.Cu"
		)
		(hatch none 0.5)
		(connect_pads
			(clearance 0)
		)
		(min_thickness 0.25)
		(keepout
			(tracks not_allowed)
			(vias allowed)
			(pads allowed)
			(copperpour not_allowed)
			(footprints allowed)
		)
		(placement
			(enabled no)
			(sheetname "")
		)
		(fill yes
			(thermal_gap 0.5)
			(thermal_bridge_width 0.5)
			(island_removal_mode 0)
		)
		(polygon
			(pts
				(arc
					(start 367.646204 -165.19398)
					(mid 365.868204 -165.19398)
					(end 367.646204 -165.19398)
				)
			)
		)
	)
	(zone
		(layers "In1.Cu" "In3.Cu" "In5.Cu" "In7.Cu" "In8.Cu" "In9.Cu" "In10.Cu"
			"In12.Cu" "In14.Cu" "In16.Cu"
		)
		(hatch none 0.5)
		(connect_pads
			(clearance 0)
		)
		(min_thickness 0.25)
		(keepout
			(tracks not_allowed)
			(vias allowed)
			(pads allowed)
			(copperpour not_allowed)
			(footprints allowed)
		)
		(placement
			(enabled no)
			(sheetname "")
		)
		(fill yes
			(thermal_gap 0.5)
			(thermal_bridge_width 0.5)
			(island_removal_mode 0)
		)
		(polygon
			(pts
				(arc
					(start 442.243718 -20.73656)
					(mid 440.465718 -20.73656)
					(end 442.243718 -20.73656)
				)
			)
		)
	)
	(zone
		(layers "In1.Cu" "In3.Cu" "In5.Cu" "In7.Cu" "In8.Cu" "In9.Cu" "In10.Cu"
			"In12.Cu" "In14.Cu" "In16.Cu"
		)
		(hatch none 0.5)
		(connect_pads
			(clearance 0)
		)
		(min_thickness 0.25)
		(keepout
			(tracks not_allowed)
			(vias allowed)
			(pads allowed)
			(copperpour not_allowed)
			(footprints allowed)
		)
		(placement
			(enabled no)
			(sheetname "")
		)
		(fill yes
			(thermal_gap 0.5)
			(thermal_bridge_width 0.5)
			(island_removal_mode 0)
		)
		(polygon
			(pts
				(arc
					(start 239.832134 -44.040806)
					(mid 238.054134 -44.040806)
					(end 239.832134 -44.040806)
				)
			)
		)
	)
	(zone
		(layers "In1.Cu" "In3.Cu" "In5.Cu" "In7.Cu" "In8.Cu" "In9.Cu" "In10.Cu"
			"In12.Cu" "In14.Cu" "In16.Cu"
		)
		(hatch none 0.5)
		(connect_pads
			(clearance 0)
		)
		(min_thickness 0.25)
		(keepout
			(tracks not_allowed)
			(vias allowed)
			(pads allowed)
			(copperpour not_allowed)
			(footprints allowed)
		)
		(placement
			(enabled no)
			(sheetname "")
		)
		(fill yes
			(thermal_gap 0.5)
			(thermal_bridge_width 0.5)
			(island_removal_mode 0)
		)
		(polygon
			(pts
				(arc
					(start 345.439238 -157.955996)
					(mid 343.661238 -157.955996)
					(end 345.439238 -157.955996)
				)
			)
		)
	)
	(zone
		(layers "In1.Cu" "In3.Cu" "In5.Cu" "In7.Cu" "In8.Cu" "In9.Cu" "In10.Cu"
			"In12.Cu" "In14.Cu" "In16.Cu"
		)
		(hatch none 0.5)
		(connect_pads
			(clearance 0)
		)
		(min_thickness 0.25)
		(keepout
			(tracks not_allowed)
			(vias allowed)
			(pads allowed)
			(copperpour not_allowed)
			(footprints allowed)
		)
		(placement
			(enabled no)
			(sheetname "")
		)
		(fill yes
			(thermal_gap 0.5)
			(thermal_bridge_width 0.5)
			(island_removal_mode 0)
		)
		(polygon
			(pts
				(arc
					(start 73.214484 -336.988404)
					(mid 71.454264 -336.988404)
					(end 73.214484 -336.988404)
				)
			)
		)
	)
	(zone
		(layers "In1.Cu" "In3.Cu" "In5.Cu" "In7.Cu" "In8.Cu" "In9.Cu" "In10.Cu"
			"In12.Cu" "In14.Cu" "In16.Cu"
		)
		(hatch none 0.5)
		(connect_pads
			(clearance 0)
		)
		(min_thickness 0.25)
		(keepout
			(tracks not_allowed)
			(vias allowed)
			(pads allowed)
			(copperpour not_allowed)
			(footprints allowed)
		)
		(placement
			(enabled no)
			(sheetname "")
		)
		(fill yes
			(thermal_gap 0.5)
			(thermal_bridge_width 0.5)
			(island_removal_mode 0)
		)
		(polygon
			(pts
				(arc
					(start 367.633504 -164.53358)
					(mid 365.855504 -164.53358)
					(end 367.633504 -164.53358)
				)
			)
		)
	)
	(zone
		(layers "In1.Cu" "In3.Cu" "In5.Cu" "In7.Cu" "In8.Cu" "In9.Cu" "In10.Cu"
			"In12.Cu" "In14.Cu" "In16.Cu"
		)
		(hatch none 0.5)
		(connect_pads
			(clearance 0)
		)
		(min_thickness 0.25)
		(keepout
			(tracks not_allowed)
			(vias allowed)
			(pads allowed)
			(copperpour not_allowed)
			(footprints allowed)
		)
		(placement
			(enabled no)
			(sheetname "")
		)
		(fill yes
			(thermal_gap 0.5)
			(thermal_bridge_width 0.5)
			(island_removal_mode 0)
		)
		(polygon
			(pts
				(arc
					(start 287.25495 -355.279198)
					(mid 285.47695 -355.279198)
					(end 287.25495 -355.279198)
				)
			)
		)
	)
	(zone
		(layers "In1.Cu" "In3.Cu" "In5.Cu" "In7.Cu" "In8.Cu" "In9.Cu" "In10.Cu"
			"In12.Cu" "In14.Cu" "In16.Cu"
		)
		(hatch none 0.5)
		(connect_pads
			(clearance 0)
		)
		(min_thickness 0.25)
		(keepout
			(tracks not_allowed)
			(vias allowed)
			(pads allowed)
			(copperpour not_allowed)
			(footprints allowed)
		)
		(placement
			(enabled no)
			(sheetname "")
		)
		(fill yes
			(thermal_gap 0.5)
			(thermal_bridge_width 0.5)
			(island_removal_mode 0)
		)
		(polygon
			(pts
				(arc
					(start 379.266958 -162.59683)
					(mid 376.472958 -162.59683)
					(end 379.266958 -162.59683)
				)
			)
		)
	)
	(zone
		(layers "In1.Cu" "In3.Cu" "In5.Cu" "In7.Cu" "In8.Cu" "In9.Cu" "In10.Cu"
			"In12.Cu" "In14.Cu" "In16.Cu"
		)
		(hatch none 0.5)
		(connect_pads
			(clearance 0)
		)
		(min_thickness 0.25)
		(keepout
			(tracks not_allowed)
			(vias allowed)
			(pads allowed)
			(copperpour not_allowed)
			(footprints allowed)
		)
		(placement
			(enabled no)
			(sheetname "")
		)
		(fill yes
			(thermal_gap 0.5)
			(thermal_bridge_width 0.5)
			(island_removal_mode 0)
		)
		(polygon
			(pts
				(arc
					(start 57.584594 -349.142558)
					(mid 55.806594 -349.142558)
					(end 57.584594 -349.142558)
				)
			)
		)
	)
	(zone
		(layers "In1.Cu" "In3.Cu" "In5.Cu" "In7.Cu" "In8.Cu" "In9.Cu" "In10.Cu"
			"In12.Cu" "In14.Cu" "In16.Cu"
		)
		(hatch none 0.5)
		(connect_pads
			(clearance 0)
		)
		(min_thickness 0.25)
		(keepout
			(tracks not_allowed)
			(vias allowed)
			(pads allowed)
			(copperpour not_allowed)
			(footprints allowed)
		)
		(placement
			(enabled no)
			(sheetname "")
		)
		(fill yes
			(thermal_gap 0.5)
			(thermal_bridge_width 0.5)
			(island_removal_mode 0)
		)
		(polygon
			(pts
				(arc
					(start 256.236978 -39.380922)
					(mid 254.458978 -39.380922)
					(end 256.236978 -39.380922)
				)
			)
		)
	)
	(zone
		(layers "In1.Cu" "In3.Cu" "In5.Cu" "In7.Cu" "In8.Cu" "In9.Cu" "In10.Cu"
			"In12.Cu" "In14.Cu" "In16.Cu"
		)
		(hatch none 0.5)
		(connect_pads
			(clearance 0)
		)
		(min_thickness 0.25)
		(keepout
			(tracks not_allowed)
			(vias allowed)
			(pads allowed)
			(copperpour not_allowed)
			(footprints allowed)
		)
		(placement
			(enabled no)
			(sheetname "")
		)
		(fill yes
			(thermal_gap 0.5)
			(thermal_bridge_width 0.5)
			(island_removal_mode 0)
		)
		(polygon
			(pts
				(arc
					(start 346.906596 -337.885278)
					(mid 345.128596 -337.885278)
					(end 346.906596 -337.885278)
				)
			)
		)
	)
	(zone
		(layers "In1.Cu" "In3.Cu" "In5.Cu" "In7.Cu" "In8.Cu" "In9.Cu" "In10.Cu"
			"In12.Cu" "In14.Cu" "In16.Cu"
		)
		(hatch none 0.5)
		(connect_pads
			(clearance 0)
		)
		(min_thickness 0.25)
		(keepout
			(tracks not_allowed)
			(vias allowed)
			(pads allowed)
			(copperpour not_allowed)
			(footprints allowed)
		)
		(placement
			(enabled no)
			(sheetname "")
		)
		(fill yes
			(thermal_gap 0.5)
			(thermal_bridge_width 0.5)
			(island_removal_mode 0)
		)
		(polygon
			(pts
				(arc
					(start 412.266638 -161.346388)
					(mid 410.488638 -161.346388)
					(end 412.266638 -161.346388)
				)
			)
		)
	)
	(zone
		(layers "In1.Cu" "In3.Cu" "In5.Cu" "In7.Cu" "In8.Cu" "In9.Cu" "In10.Cu"
			"In12.Cu" "In14.Cu" "In16.Cu"
		)
		(hatch none 0.5)
		(connect_pads
			(clearance 0)
		)
		(min_thickness 0.25)
		(keepout
			(tracks not_allowed)
			(vias allowed)
			(pads allowed)
			(copperpour not_allowed)
			(footprints allowed)
		)
		(placement
			(enabled no)
			(sheetname "")
		)
		(fill yes
			(thermal_gap 0.5)
			(thermal_bridge_width 0.5)
			(island_removal_mode 0)
		)
		(polygon
			(pts
				(arc
					(start 91.12885 -163.457636)
					(mid 89.35085 -163.457636)
					(end 91.12885 -163.457636)
				)
			)
		)
	)
	(zone
		(layers "In1.Cu" "In3.Cu" "In5.Cu" "In7.Cu" "In8.Cu" "In9.Cu" "In10.Cu"
			"In12.Cu" "In14.Cu" "In16.Cu"
		)
		(hatch none 0.5)
		(connect_pads
			(clearance 0)
		)
		(min_thickness 0.25)
		(keepout
			(tracks not_allowed)
			(vias allowed)
			(pads allowed)
			(copperpour not_allowed)
			(footprints allowed)
		)
		(placement
			(enabled no)
			(sheetname "")
		)
		(fill yes
			(thermal_gap 0.5)
			(thermal_bridge_width 0.5)
			(island_removal_mode 0)
		)
		(polygon
			(pts
				(arc
					(start 106.534712 -341.927688)
					(mid 104.774492 -341.927688)
					(end 106.534712 -341.927688)
				)
			)
		)
	)
	(zone
		(layers "In1.Cu" "In3.Cu" "In5.Cu" "In7.Cu" "In8.Cu" "In9.Cu" "In10.Cu"
			"In12.Cu" "In14.Cu" "In16.Cu"
		)
		(hatch none 0.5)
		(connect_pads
			(clearance 0)
		)
		(min_thickness 0.25)
		(keepout
			(tracks not_allowed)
			(vias allowed)
			(pads allowed)
			(copperpour not_allowed)
			(footprints allowed)
		)
		(placement
			(enabled no)
			(sheetname "")
		)
		(fill yes
			(thermal_gap 0.5)
			(thermal_bridge_width 0.5)
			(island_removal_mode 0)
		)
		(polygon
			(pts
				(arc
					(start 451.558914 -14.526514)
					(mid 449.780914 -14.526514)
					(end 451.558914 -14.526514)
				)
			)
		)
	)
	(zone
		(layers "In1.Cu" "In3.Cu" "In5.Cu" "In7.Cu" "In8.Cu" "In9.Cu" "In10.Cu"
			"In12.Cu" "In14.Cu" "In16.Cu"
		)
		(hatch none 0.5)
		(connect_pads
			(clearance 0)
		)
		(min_thickness 0.25)
		(keepout
			(tracks not_allowed)
			(vias allowed)
			(pads allowed)
			(copperpour not_allowed)
			(footprints allowed)
		)
		(placement
			(enabled no)
			(sheetname "")
		)
		(fill yes
			(thermal_gap 0.5)
			(thermal_bridge_width 0.5)
			(island_removal_mode 0)
		)
		(polygon
			(pts
				(arc
					(start 124.1552 -163.204144)
					(mid 122.39498 -163.204144)
					(end 124.1552 -163.204144)
				)
			)
		)
	)
	(zone
		(layers "In1.Cu" "In3.Cu" "In5.Cu" "In7.Cu" "In8.Cu" "In9.Cu" "In10.Cu"
			"In12.Cu" "In14.Cu" "In16.Cu"
		)
		(hatch none 0.5)
		(connect_pads
			(clearance 0)
		)
		(min_thickness 0.25)
		(keepout
			(tracks not_allowed)
			(vias allowed)
			(pads allowed)
			(copperpour not_allowed)
			(footprints allowed)
		)
		(placement
			(enabled no)
			(sheetname "")
		)
		(fill yes
			(thermal_gap 0.5)
			(thermal_bridge_width 0.5)
			(island_removal_mode 0)
		)
		(polygon
			(pts
				(arc
					(start 88.39327 -179.492402)
					(mid 86.61527 -179.492402)
					(end 88.39327 -179.492402)
				)
			)
		)
	)
	(zone
		(layers "In1.Cu" "In3.Cu" "In5.Cu" "In7.Cu" "In8.Cu" "In9.Cu" "In10.Cu"
			"In12.Cu" "In14.Cu" "In16.Cu"
		)
		(hatch none 0.5)
		(connect_pads
			(clearance 0)
		)
		(min_thickness 0.25)
		(keepout
			(tracks not_allowed)
			(vias allowed)
			(pads allowed)
			(copperpour not_allowed)
			(footprints allowed)
		)
		(placement
			(enabled no)
			(sheetname "")
		)
		(fill yes
			(thermal_gap 0.5)
			(thermal_bridge_width 0.5)
			(island_removal_mode 0)
		)
		(polygon
			(pts
				(arc
					(start 104.63403 -174.632874)
					(mid 102.85603 -174.632874)
					(end 104.63403 -174.632874)
				)
			)
		)
	)
	(zone
		(layers "In1.Cu" "In3.Cu" "In5.Cu" "In7.Cu" "In8.Cu" "In9.Cu" "In10.Cu"
			"In12.Cu" "In14.Cu" "In16.Cu"
		)
		(hatch none 0.5)
		(connect_pads
			(clearance 0)
		)
		(min_thickness 0.25)
		(keepout
			(tracks not_allowed)
			(vias allowed)
			(pads allowed)
			(copperpour not_allowed)
			(footprints allowed)
		)
		(placement
			(enabled no)
			(sheetname "")
		)
		(fill yes
			(thermal_gap 0.5)
			(thermal_bridge_width 0.5)
			(island_removal_mode 0)
		)
		(polygon
			(pts
				(arc
					(start 32.641794 -349.142558)
					(mid 30.863794 -349.142558)
					(end 32.641794 -349.142558)
				)
			)
		)
	)
	(zone
		(layers "In1.Cu" "In3.Cu" "In5.Cu" "In7.Cu" "In8.Cu" "In9.Cu" "In10.Cu"
			"In12.Cu" "In14.Cu" "In16.Cu"
		)
		(hatch none 0.5)
		(connect_pads
			(clearance 0)
		)
		(min_thickness 0.25)
		(keepout
			(tracks not_allowed)
			(vias allowed)
			(pads allowed)
			(copperpour not_allowed)
			(footprints allowed)
		)
		(placement
			(enabled no)
			(sheetname "")
		)
		(fill yes
			(thermal_gap 0.5)
			(thermal_bridge_width 0.5)
			(island_removal_mode 0)
		)
		(polygon
			(pts
				(arc
					(start 47.511716 -393.292838)
					(mid 47.816516 -393.597638)
					(end 48.121316 -393.292838)
				)
				(arc
					(start 48.121316 -392.429238)
					(mid 47.816516 -392.124438)
					(end 47.511716 -392.429238)
				)
			)
		)
	)
	(zone
		(layers "In1.Cu" "In3.Cu" "In5.Cu" "In7.Cu" "In8.Cu" "In9.Cu" "In10.Cu"
			"In12.Cu" "In14.Cu" "In16.Cu"
		)
		(hatch none 0.5)
		(connect_pads
			(clearance 0)
		)
		(min_thickness 0.25)
		(keepout
			(tracks not_allowed)
			(vias allowed)
			(pads allowed)
			(copperpour not_allowed)
			(footprints allowed)
		)
		(placement
			(enabled no)
			(sheetname "")
		)
		(fill yes
			(thermal_gap 0.5)
			(thermal_bridge_width 0.5)
			(island_removal_mode 0)
		)
		(polygon
			(pts
				(arc
					(start 41.480994 -349.523558)
					(mid 39.702994 -349.523558)
					(end 41.480994 -349.523558)
				)
			)
		)
	)
	(zone
		(layers "In1.Cu" "In3.Cu" "In5.Cu" "In7.Cu" "In8.Cu" "In9.Cu" "In10.Cu"
			"In12.Cu" "In14.Cu" "In16.Cu"
		)
		(hatch none 0.5)
		(connect_pads
			(clearance 0)
		)
		(min_thickness 0.25)
		(keepout
			(tracks not_allowed)
			(vias allowed)
			(pads allowed)
			(copperpour not_allowed)
			(footprints allowed)
		)
		(placement
			(enabled no)
			(sheetname "")
		)
		(fill yes
			(thermal_gap 0.5)
			(thermal_bridge_width 0.5)
			(island_removal_mode 0)
		)
		(polygon
			(pts
				(arc
					(start 411.707838 -161.701988)
					(mid 409.929838 -161.701988)
					(end 411.707838 -161.701988)
				)
			)
		)
	)
	(zone
		(layers "In1.Cu" "In3.Cu" "In5.Cu" "In7.Cu" "In8.Cu" "In9.Cu" "In10.Cu"
			"In12.Cu" "In14.Cu" "In16.Cu"
		)
		(hatch none 0.5)
		(connect_pads
			(clearance 0)
		)
		(min_thickness 0.25)
		(keepout
			(tracks not_allowed)
			(vias allowed)
			(pads allowed)
			(copperpour not_allowed)
			(footprints allowed)
		)
		(placement
			(enabled no)
			(sheetname "")
		)
		(fill yes
			(thermal_gap 0.5)
			(thermal_bridge_width 0.5)
			(island_removal_mode 0)
		)
		(polygon
			(pts
				(arc
					(start 386.587238 -179.204874)
					(mid 384.809238 -179.204874)
					(end 386.587238 -179.204874)
				)
			)
		)
	)
	(zone
		(layers "In1.Cu" "In3.Cu" "In5.Cu" "In7.Cu" "In8.Cu" "In9.Cu" "In10.Cu"
			"In12.Cu" "In14.Cu" "In16.Cu"
		)
		(hatch none 0.5)
		(connect_pads
			(clearance 0)
		)
		(min_thickness 0.25)
		(keepout
			(tracks not_allowed)
			(vias allowed)
			(pads allowed)
			(copperpour not_allowed)
			(footprints allowed)
		)
		(placement
			(enabled no)
			(sheetname "")
		)
		(fill yes
			(thermal_gap 0.5)
			(thermal_bridge_width 0.5)
			(island_removal_mode 0)
		)
		(polygon
			(pts
				(arc
					(start 33.200594 -348.786958)
					(mid 31.422594 -348.786958)
					(end 33.200594 -348.786958)
				)
			)
		)
	)
	(zone
		(layers "In1.Cu" "In3.Cu" "In5.Cu" "In7.Cu" "In8.Cu" "In9.Cu" "In10.Cu"
			"In12.Cu" "In14.Cu" "In16.Cu"
		)
		(hatch none 0.5)
		(connect_pads
			(clearance 0)
		)
		(min_thickness 0.25)
		(keepout
			(tracks not_allowed)
			(vias allowed)
			(pads allowed)
			(copperpour not_allowed)
			(footprints allowed)
		)
		(placement
			(enabled no)
			(sheetname "")
		)
		(fill yes
			(thermal_gap 0.5)
			(thermal_bridge_width 0.5)
			(island_removal_mode 0)
		)
		(polygon
			(pts
				(arc
					(start 58.143394 -348.786958)
					(mid 56.365394 -348.786958)
					(end 58.143394 -348.786958)
				)
			)
		)
	)
	(zone
		(layers "In1.Cu" "In3.Cu" "In5.Cu" "In7.Cu" "In8.Cu" "In9.Cu" "In10.Cu"
			"In12.Cu" "In14.Cu" "In16.Cu"
		)
		(hatch none 0.5)
		(connect_pads
			(clearance 0)
		)
		(min_thickness 0.25)
		(keepout
			(tracks not_allowed)
			(vias allowed)
			(pads allowed)
			(copperpour not_allowed)
			(footprints allowed)
		)
		(placement
			(enabled no)
			(sheetname "")
		)
		(fill yes
			(thermal_gap 0.5)
			(thermal_bridge_width 0.5)
			(island_removal_mode 0)
		)
		(polygon
			(pts
				(arc
					(start 435.487064 -354.00107)
					(mid 433.709064 -354.00107)
					(end 435.487064 -354.00107)
				)
			)
		)
	)
	(zone
		(layers "In1.Cu" "In3.Cu" "In5.Cu" "In7.Cu" "In8.Cu" "In9.Cu" "In10.Cu"
			"In12.Cu" "In14.Cu" "In16.Cu"
		)
		(hatch none 0.5)
		(connect_pads
			(clearance 0)
		)
		(min_thickness 0.25)
		(keepout
			(tracks not_allowed)
			(vias allowed)
			(pads allowed)
			(copperpour not_allowed)
			(footprints allowed)
		)
		(placement
			(enabled no)
			(sheetname "")
		)
		(fill yes
			(thermal_gap 0.5)
			(thermal_bridge_width 0.5)
			(island_removal_mode 0)
		)
		(polygon
			(pts
				(arc
					(start 89.6366 -180.687472)
					(mid 87.87638 -180.687472)
					(end 89.6366 -180.687472)
				)
			)
		)
	)
	(zone
		(layers "In1.Cu" "In3.Cu" "In5.Cu" "In7.Cu" "In8.Cu" "In9.Cu" "In10.Cu"
			"In12.Cu" "In14.Cu" "In16.Cu"
		)
		(hatch none 0.5)
		(connect_pads
			(clearance 0)
		)
		(min_thickness 0.25)
		(keepout
			(tracks not_allowed)
			(vias allowed)
			(pads allowed)
			(copperpour not_allowed)
			(footprints allowed)
		)
		(placement
			(enabled no)
			(sheetname "")
		)
		(fill yes
			(thermal_gap 0.5)
			(thermal_bridge_width 0.5)
			(island_removal_mode 0)
		)
		(polygon
			(pts
				(arc
					(start 71.980044 -336.988404)
					(mid 70.219824 -336.988404)
					(end 71.980044 -336.988404)
				)
			)
		)
	)
	(zone
		(layers "In1.Cu" "In3.Cu" "In5.Cu" "In7.Cu" "In8.Cu" "In9.Cu" "In10.Cu"
			"In12.Cu" "In14.Cu" "In16.Cu"
		)
		(hatch none 0.5)
		(connect_pads
			(clearance 0)
		)
		(min_thickness 0.25)
		(keepout
			(tracks not_allowed)
			(vias allowed)
			(pads allowed)
			(copperpour not_allowed)
			(footprints allowed)
		)
		(placement
			(enabled no)
			(sheetname "")
		)
		(fill yes
			(thermal_gap 0.5)
			(thermal_bridge_width 0.5)
			(island_removal_mode 0)
		)
		(polygon
			(pts
				(arc
					(start 78.400402 -352.978212)
					(mid 76.622402 -352.978212)
					(end 78.400402 -352.978212)
				)
			)
		)
	)
	(zone
		(layers "In1.Cu" "In3.Cu" "In5.Cu" "In7.Cu" "In8.Cu" "In9.Cu" "In10.Cu"
			"In12.Cu" "In14.Cu" "In16.Cu"
		)
		(hatch none 0.5)
		(connect_pads
			(clearance 0)
		)
		(min_thickness 0.25)
		(keepout
			(tracks not_allowed)
			(vias allowed)
			(pads allowed)
			(copperpour not_allowed)
			(footprints allowed)
		)
		(placement
			(enabled no)
			(sheetname "")
		)
		(fill yes
			(thermal_gap 0.5)
			(thermal_bridge_width 0.5)
			(island_removal_mode 0)
		)
		(polygon
			(pts
				(arc
					(start 32.11703 -349.581978)
					(mid 30.33903 -349.581978)
					(end 32.11703 -349.581978)
				)
			)
		)
	)
	(zone
		(layers "In1.Cu" "In3.Cu" "In5.Cu" "In7.Cu" "In8.Cu" "In9.Cu" "In10.Cu"
			"In12.Cu" "In14.Cu" "In16.Cu"
		)
		(hatch none 0.5)
		(connect_pads
			(clearance 0)
		)
		(min_thickness 0.25)
		(keepout
			(tracks not_allowed)
			(vias allowed)
			(pads allowed)
			(copperpour not_allowed)
			(footprints allowed)
		)
		(placement
			(enabled no)
			(sheetname "")
		)
		(fill yes
			(thermal_gap 0.5)
			(thermal_bridge_width 0.5)
			(island_removal_mode 0)
		)
		(polygon
			(pts
				(arc
					(start 388.182358 -153.793952)
					(mid 386.404358 -153.793952)
					(end 388.182358 -153.793952)
				)
			)
		)
	)
	(zone
		(layers "In1.Cu" "In3.Cu" "In5.Cu" "In7.Cu" "In8.Cu" "In9.Cu" "In10.Cu"
			"In12.Cu" "In14.Cu" "In16.Cu"
		)
		(hatch none 0.5)
		(connect_pads
			(clearance 0)
		)
		(min_thickness 0.25)
		(keepout
			(tracks not_allowed)
			(vias allowed)
			(pads allowed)
			(copperpour not_allowed)
			(footprints allowed)
		)
		(placement
			(enabled no)
			(sheetname "")
		)
		(fill yes
			(thermal_gap 0.5)
			(thermal_bridge_width 0.5)
			(island_removal_mode 0)
		)
		(polygon
			(pts
				(arc
					(start 404.409402 -165.732968)
					(mid 402.631402 -165.732968)
					(end 404.409402 -165.732968)
				)
			)
		)
	)
	(zone
		(layers "In1.Cu" "In3.Cu" "In5.Cu" "In7.Cu" "In8.Cu" "In9.Cu" "In10.Cu"
			"In12.Cu" "In14.Cu" "In16.Cu"
		)
		(hatch none 0.5)
		(connect_pads
			(clearance 0)
		)
		(min_thickness 0.25)
		(keepout
			(tracks not_allowed)
			(vias allowed)
			(pads allowed)
			(copperpour not_allowed)
			(footprints allowed)
		)
		(placement
			(enabled no)
			(sheetname "")
		)
		(fill yes
			(thermal_gap 0.5)
			(thermal_bridge_width 0.5)
			(island_removal_mode 0)
		)
		(polygon
			(pts
				(arc
					(start 370.41201 -180.322474)
					(mid 368.63401 -180.322474)
					(end 370.41201 -180.322474)
				)
			)
		)
	)
	(zone
		(layers "In1.Cu" "In3.Cu" "In5.Cu" "In7.Cu" "In8.Cu" "In9.Cu" "In10.Cu"
			"In12.Cu" "In14.Cu" "In16.Cu"
		)
		(hatch none 0.5)
		(connect_pads
			(clearance 0)
		)
		(min_thickness 0.25)
		(keepout
			(tracks not_allowed)
			(vias allowed)
			(pads allowed)
			(copperpour not_allowed)
			(footprints allowed)
		)
		(placement
			(enabled no)
			(sheetname "")
		)
		(fill yes
			(thermal_gap 0.5)
			(thermal_bridge_width 0.5)
			(island_removal_mode 0)
		)
		(polygon
			(pts
				(arc
					(start 66.755264 -12.43711)
					(mid 64.977264 -12.43711)
					(end 66.755264 -12.43711)
				)
			)
		)
	)
	(zone
		(layers "In1.Cu" "In3.Cu" "In5.Cu" "In7.Cu" "In8.Cu" "In9.Cu" "In10.Cu"
			"In12.Cu" "In14.Cu" "In16.Cu"
		)
		(hatch none 0.5)
		(connect_pads
			(clearance 0)
		)
		(min_thickness 0.25)
		(keepout
			(tracks not_allowed)
			(vias allowed)
			(pads allowed)
			(copperpour not_allowed)
			(footprints allowed)
		)
		(placement
			(enabled no)
			(sheetname "")
		)
		(fill yes
			(thermal_gap 0.5)
			(thermal_bridge_width 0.5)
			(island_removal_mode 0)
		)
		(polygon
			(pts
				(arc
					(start 88.943434 -179.078382)
					(mid 87.165434 -179.078382)
					(end 88.943434 -179.078382)
				)
			)
		)
	)
	(zone
		(layers "In1.Cu" "In3.Cu" "In5.Cu" "In7.Cu" "In8.Cu" "In9.Cu" "In10.Cu"
			"In12.Cu" "In14.Cu" "In16.Cu"
		)
		(hatch none 0.5)
		(connect_pads
			(clearance 0)
		)
		(min_thickness 0.25)
		(keepout
			(tracks not_allowed)
			(vias allowed)
			(pads allowed)
			(copperpour not_allowed)
			(footprints allowed)
		)
		(placement
			(enabled no)
			(sheetname "")
		)
		(fill yes
			(thermal_gap 0.5)
			(thermal_bridge_width 0.5)
			(island_removal_mode 0)
		)
		(polygon
			(pts
				(arc
					(start 278.938482 -350.313752)
					(mid 277.160482 -350.313752)
					(end 278.938482 -350.313752)
				)
			)
		)
	)
	(zone
		(layers "In1.Cu" "In3.Cu" "In5.Cu" "In7.Cu" "In8.Cu" "In9.Cu" "In10.Cu"
			"In12.Cu" "In14.Cu" "In16.Cu"
		)
		(hatch none 0.5)
		(connect_pads
			(clearance 0)
		)
		(min_thickness 0.25)
		(keepout
			(tracks not_allowed)
			(vias allowed)
			(pads allowed)
			(copperpour not_allowed)
			(footprints allowed)
		)
		(placement
			(enabled no)
			(sheetname "")
		)
		(fill yes
			(thermal_gap 0.5)
			(thermal_bridge_width 0.5)
			(island_removal_mode 0)
		)
		(polygon
			(pts
				(arc
					(start 378.256038 -179.941474)
					(mid 376.478038 -179.941474)
					(end 378.256038 -179.941474)
				)
			)
		)
	)
	(zone
		(layers "In1.Cu" "In3.Cu" "In5.Cu" "In7.Cu" "In8.Cu" "In9.Cu" "In10.Cu"
			"In12.Cu" "In14.Cu" "In16.Cu"
		)
		(hatch none 0.5)
		(connect_pads
			(clearance 0)
		)
		(min_thickness 0.25)
		(keepout
			(tracks not_allowed)
			(vias allowed)
			(pads allowed)
			(copperpour not_allowed)
			(footprints allowed)
		)
		(placement
			(enabled no)
			(sheetname "")
		)
		(fill yes
			(thermal_gap 0.5)
			(thermal_bridge_width 0.5)
			(island_removal_mode 0)
		)
		(polygon
			(pts
				(arc
					(start 201.594974 -30.720538)
					(mid 199.816974 -30.720538)
					(end 201.594974 -30.720538)
				)
			)
		)
	)
	(zone
		(layers "In1.Cu" "In3.Cu" "In5.Cu" "In7.Cu" "In8.Cu" "In9.Cu" "In10.Cu"
			"In12.Cu" "In14.Cu" "In16.Cu"
		)
		(hatch none 0.5)
		(connect_pads
			(clearance 0)
		)
		(min_thickness 0.25)
		(keepout
			(tracks not_allowed)
			(vias allowed)
			(pads allowed)
			(copperpour not_allowed)
			(footprints allowed)
		)
		(placement
			(enabled no)
			(sheetname "")
		)
		(fill yes
			(thermal_gap 0.5)
			(thermal_bridge_width 0.5)
			(island_removal_mode 0)
		)
		(polygon
			(pts
				(arc
					(start 50.29073 -357.457502)
					(mid 48.51273 -357.457502)
					(end 50.29073 -357.457502)
				)
			)
		)
	)
	(zone
		(layers "In1.Cu" "In3.Cu" "In5.Cu" "In7.Cu" "In8.Cu" "In9.Cu" "In10.Cu"
			"In12.Cu" "In14.Cu" "In16.Cu"
		)
		(hatch none 0.5)
		(connect_pads
			(clearance 0)
		)
		(min_thickness 0.25)
		(keepout
			(tracks not_allowed)
			(vias allowed)
			(pads allowed)
			(copperpour not_allowed)
			(footprints allowed)
		)
		(placement
			(enabled no)
			(sheetname "")
		)
		(fill yes
			(thermal_gap 0.5)
			(thermal_bridge_width 0.5)
			(island_removal_mode 0)
		)
		(polygon
			(pts
				(arc
					(start 187.519818 -353.361244)
					(mid 185.741818 -353.361244)
					(end 187.519818 -353.361244)
				)
			)
		)
	)
	(zone
		(layers "In1.Cu" "In3.Cu" "In5.Cu" "In7.Cu" "In8.Cu" "In9.Cu" "In10.Cu"
			"In12.Cu" "In14.Cu" "In16.Cu"
		)
		(hatch none 0.5)
		(connect_pads
			(clearance 0)
		)
		(min_thickness 0.25)
		(keepout
			(tracks not_allowed)
			(vias allowed)
			(pads allowed)
			(copperpour not_allowed)
			(footprints allowed)
		)
		(placement
			(enabled no)
			(sheetname "")
		)
		(fill yes
			(thermal_gap 0.5)
			(thermal_bridge_width 0.5)
			(island_removal_mode 0)
		)
		(polygon
			(pts
				(arc
					(start 194.747134 -16.543528)
					(mid 192.969134 -16.543528)
					(end 194.747134 -16.543528)
				)
			)
		)
	)
	(zone
		(layers "In1.Cu" "In3.Cu" "In5.Cu" "In7.Cu" "In8.Cu" "In9.Cu" "In10.Cu"
			"In12.Cu" "In14.Cu" "In16.Cu"
		)
		(hatch none 0.5)
		(connect_pads
			(clearance 0)
		)
		(min_thickness 0.25)
		(keepout
			(tracks not_allowed)
			(vias allowed)
			(pads allowed)
			(copperpour not_allowed)
			(footprints allowed)
		)
		(placement
			(enabled no)
			(sheetname "")
		)
		(fill yes
			(thermal_gap 0.5)
			(thermal_bridge_width 0.5)
			(island_removal_mode 0)
		)
		(polygon
			(pts
				(arc
					(start 346.906596 -339.358478)
					(mid 345.128596 -339.358478)
					(end 346.906596 -339.358478)
				)
			)
		)
	)
	(zone
		(layers "In1.Cu" "In3.Cu" "In5.Cu" "In7.Cu" "In8.Cu" "In9.Cu" "In10.Cu"
			"In12.Cu" "In14.Cu" "In16.Cu"
		)
		(hatch none 0.5)
		(connect_pads
			(clearance 0)
		)
		(min_thickness 0.25)
		(keepout
			(tracks not_allowed)
			(vias allowed)
			(pads allowed)
			(copperpour not_allowed)
			(footprints allowed)
		)
		(placement
			(enabled no)
			(sheetname "")
		)
		(fill yes
			(thermal_gap 0.5)
			(thermal_bridge_width 0.5)
			(island_removal_mode 0)
		)
		(polygon
			(pts
				(arc
					(start 113.39703 -168.740074)
					(mid 111.61903 -168.740074)
					(end 113.39703 -168.740074)
				)
			)
		)
	)
	(zone
		(layers "In1.Cu" "In3.Cu" "In5.Cu" "In7.Cu" "In8.Cu" "In9.Cu" "In10.Cu"
			"In12.Cu" "In14.Cu" "In16.Cu"
		)
		(hatch none 0.5)
		(connect_pads
			(clearance 0)
		)
		(min_thickness 0.25)
		(keepout
			(tracks not_allowed)
			(vias allowed)
			(pads allowed)
			(copperpour not_allowed)
			(footprints allowed)
		)
		(placement
			(enabled no)
			(sheetname "")
		)
		(fill yes
			(thermal_gap 0.5)
			(thermal_bridge_width 0.5)
			(island_removal_mode 0)
		)
		(polygon
			(pts
				(arc
					(start 354.988368 -167.507666)
					(mid 353.228148 -167.507666)
					(end 354.988368 -167.507666)
				)
			)
		)
	)
	(zone
		(layers "In1.Cu" "In3.Cu" "In5.Cu" "In7.Cu" "In8.Cu" "In9.Cu" "In10.Cu"
			"In12.Cu" "In14.Cu" "In16.Cu"
		)
		(hatch none 0.5)
		(connect_pads
			(clearance 0)
		)
		(min_thickness 0.25)
		(keepout
			(tracks not_allowed)
			(vias allowed)
			(pads allowed)
			(copperpour not_allowed)
			(footprints allowed)
		)
		(placement
			(enabled no)
			(sheetname "")
		)
		(fill yes
			(thermal_gap 0.5)
			(thermal_bridge_width 0.5)
			(island_removal_mode 0)
		)
		(polygon
			(pts
				(arc
					(start 304.431446 -349.899732)
					(mid 302.653446 -349.899732)
					(end 304.431446 -349.899732)
				)
			)
		)
	)
	(zone
		(layers "In1.Cu" "In3.Cu" "In5.Cu" "In7.Cu" "In8.Cu" "In9.Cu" "In10.Cu"
			"In12.Cu" "In14.Cu" "In16.Cu"
		)
		(hatch none 0.5)
		(connect_pads
			(clearance 0)
		)
		(min_thickness 0.25)
		(keepout
			(tracks not_allowed)
			(vias allowed)
			(pads allowed)
			(copperpour not_allowed)
			(footprints allowed)
		)
		(placement
			(enabled no)
			(sheetname "")
		)
		(fill yes
			(thermal_gap 0.5)
			(thermal_bridge_width 0.5)
			(island_removal_mode 0)
		)
		(polygon
			(pts
				(arc
					(start 371.418358 -181.405276)
					(mid 369.640358 -181.405276)
					(end 371.418358 -181.405276)
				)
			)
		)
	)
	(zone
		(layers "In1.Cu" "In3.Cu" "In5.Cu" "In7.Cu" "In8.Cu" "In9.Cu" "In10.Cu"
			"In12.Cu" "In14.Cu" "In16.Cu"
		)
		(hatch none 0.5)
		(connect_pads
			(clearance 0)
		)
		(min_thickness 0.25)
		(keepout
			(tracks not_allowed)
			(vias allowed)
			(pads allowed)
			(copperpour not_allowed)
			(footprints allowed)
		)
		(placement
			(enabled no)
			(sheetname "")
		)
		(fill yes
			(thermal_gap 0.5)
			(thermal_bridge_width 0.5)
			(island_removal_mode 0)
		)
		(polygon
			(pts
				(arc
					(start 112.86363 -168.384474)
					(mid 111.08563 -168.384474)
					(end 112.86363 -168.384474)
				)
			)
		)
	)
	(zone
		(layers "In1.Cu" "In3.Cu" "In5.Cu" "In7.Cu" "In8.Cu" "In9.Cu" "In10.Cu"
			"In12.Cu" "In14.Cu" "In16.Cu"
		)
		(hatch none 0.5)
		(connect_pads
			(clearance 0)
		)
		(min_thickness 0.25)
		(keepout
			(tracks not_allowed)
			(vias allowed)
			(pads allowed)
			(copperpour not_allowed)
			(footprints allowed)
		)
		(placement
			(enabled no)
			(sheetname "")
		)
		(fill yes
			(thermal_gap 0.5)
			(thermal_bridge_width 0.5)
			(island_removal_mode 0)
		)
		(polygon
			(pts
				(arc
					(start 400.054064 -81.051146)
					(mid 398.276064 -81.051146)
					(end 400.054064 -81.051146)
				)
			)
		)
	)
	(zone
		(layers "In1.Cu" "In3.Cu" "In5.Cu" "In7.Cu" "In8.Cu" "In9.Cu" "In10.Cu"
			"In12.Cu" "In14.Cu" "In16.Cu"
		)
		(hatch none 0.5)
		(connect_pads
			(clearance 0)
		)
		(min_thickness 0.25)
		(keepout
			(tracks not_allowed)
			(vias allowed)
			(pads allowed)
			(copperpour not_allowed)
			(footprints allowed)
		)
		(placement
			(enabled no)
			(sheetname "")
		)
		(fill yes
			(thermal_gap 0.5)
			(thermal_bridge_width 0.5)
			(island_removal_mode 0)
		)
		(polygon
			(pts
				(arc
					(start 33.200594 -349.523558)
					(mid 31.422594 -349.523558)
					(end 33.200594 -349.523558)
				)
			)
		)
	)
	(zone
		(layers "In1.Cu" "In3.Cu" "In5.Cu" "In7.Cu" "In8.Cu" "In9.Cu" "In10.Cu"
			"In12.Cu" "In14.Cu" "In16.Cu"
		)
		(hatch none 0.5)
		(connect_pads
			(clearance 0)
		)
		(min_thickness 0.25)
		(keepout
			(tracks not_allowed)
			(vias allowed)
			(pads allowed)
			(copperpour not_allowed)
			(footprints allowed)
		)
		(placement
			(enabled no)
			(sheetname "")
		)
		(fill yes
			(thermal_gap 0.5)
			(thermal_bridge_width 0.5)
			(island_removal_mode 0)
		)
		(polygon
			(pts
				(arc
					(start 63.909194 -166.06774)
					(mid 62.131194 -166.06774)
					(end 63.909194 -166.06774)
				)
			)
		)
	)
	(zone
		(layers "In1.Cu" "In3.Cu" "In5.Cu" "In7.Cu" "In8.Cu" "In9.Cu" "In10.Cu"
			"In12.Cu" "In14.Cu" "In16.Cu"
		)
		(hatch none 0.5)
		(connect_pads
			(clearance 0)
		)
		(min_thickness 0.25)
		(keepout
			(tracks not_allowed)
			(vias allowed)
			(pads allowed)
			(copperpour not_allowed)
			(footprints allowed)
		)
		(placement
			(enabled no)
			(sheetname "")
		)
		(fill yes
			(thermal_gap 0.5)
			(thermal_bridge_width 0.5)
			(island_removal_mode 0)
		)
		(polygon
			(pts
				(arc
					(start 84.386674 -165.962076)
					(mid 81.592674 -165.962076)
					(end 84.386674 -165.962076)
				)
			)
		)
	)
	(zone
		(layers "In1.Cu" "In3.Cu" "In5.Cu" "In7.Cu" "In8.Cu" "In9.Cu" "In10.Cu"
			"In12.Cu" "In14.Cu" "In16.Cu"
		)
		(hatch none 0.5)
		(connect_pads
			(clearance 0)
		)
		(min_thickness 0.25)
		(keepout
			(tracks not_allowed)
			(vias allowed)
			(pads allowed)
			(copperpour not_allowed)
			(footprints allowed)
		)
		(placement
			(enabled no)
			(sheetname "")
		)
		(fill yes
			(thermal_gap 0.5)
			(thermal_bridge_width 0.5)
			(island_removal_mode 0)
		)
		(polygon
			(pts
				(arc
					(start 87.92845 -162.812476)
					(mid 86.15045 -162.812476)
					(end 87.92845 -162.812476)
				)
			)
		)
	)
	(zone
		(layers "In1.Cu" "In3.Cu" "In5.Cu" "In7.Cu" "In8.Cu" "In9.Cu" "In10.Cu"
			"In12.Cu" "In14.Cu" "In16.Cu"
		)
		(hatch none 0.5)
		(connect_pads
			(clearance 0)
		)
		(min_thickness 0.25)
		(keepout
			(tracks not_allowed)
			(vias allowed)
			(pads allowed)
			(copperpour not_allowed)
			(footprints allowed)
		)
		(placement
			(enabled no)
			(sheetname "")
		)
		(fill yes
			(thermal_gap 0.5)
			(thermal_bridge_width 0.5)
			(island_removal_mode 0)
		)
		(polygon
			(pts
				(arc
					(start 67.822064 -13.09751)
					(mid 66.044064 -13.09751)
					(end 67.822064 -13.09751)
				)
			)
		)
	)
	(zone
		(layers "In1.Cu" "In3.Cu" "In5.Cu" "In7.Cu" "In8.Cu" "In9.Cu" "In10.Cu"
			"In12.Cu" "In14.Cu" "In16.Cu"
		)
		(hatch none 0.5)
		(connect_pads
			(clearance 0)
		)
		(min_thickness 0.25)
		(keepout
			(tracks not_allowed)
			(vias allowed)
			(pads allowed)
			(copperpour not_allowed)
			(footprints allowed)
		)
		(placement
			(enabled no)
			(sheetname "")
		)
		(fill yes
			(thermal_gap 0.5)
			(thermal_bridge_width 0.5)
			(island_removal_mode 0)
		)
		(polygon
			(pts
				(arc
					(start 367.633504 -163.89858)
					(mid 365.855504 -163.89858)
					(end 367.633504 -163.89858)
				)
			)
		)
	)
	(zone
		(layers "In1.Cu" "In3.Cu" "In5.Cu" "In7.Cu" "In8.Cu" "In9.Cu" "In10.Cu"
			"In12.Cu" "In14.Cu" "In16.Cu"
		)
		(hatch none 0.5)
		(connect_pads
			(clearance 0)
		)
		(min_thickness 0.25)
		(keepout
			(tracks not_allowed)
			(vias allowed)
			(pads allowed)
			(copperpour not_allowed)
			(footprints allowed)
		)
		(placement
			(enabled no)
			(sheetname "")
		)
		(fill yes
			(thermal_gap 0.5)
			(thermal_bridge_width 0.5)
			(island_removal_mode 0)
		)
		(polygon
			(pts
				(arc
					(start 202.634342 -344.8304)
					(mid 200.856342 -344.8304)
					(end 202.634342 -344.8304)
				)
			)
		)
	)
	(zone
		(layers "In1.Cu" "In3.Cu" "In5.Cu" "In7.Cu" "In8.Cu" "In9.Cu" "In10.Cu"
			"In12.Cu" "In14.Cu" "In16.Cu"
		)
		(hatch none 0.5)
		(connect_pads
			(clearance 0)
		)
		(min_thickness 0.25)
		(keepout
			(tracks not_allowed)
			(vias allowed)
			(pads allowed)
			(copperpour not_allowed)
			(footprints allowed)
		)
		(placement
			(enabled no)
			(sheetname "")
		)
		(fill yes
			(thermal_gap 0.5)
			(thermal_bridge_width 0.5)
			(island_removal_mode 0)
		)
		(polygon
			(pts
				(arc
					(start 64.468248 -168.42232)
					(mid 62.690248 -168.42232)
					(end 64.468248 -168.42232)
				)
			)
		)
	)
	(zone
		(layers "In1.Cu" "In3.Cu" "In5.Cu" "In7.Cu" "In8.Cu" "In9.Cu" "In10.Cu"
			"In12.Cu" "In14.Cu" "In16.Cu"
		)
		(hatch none 0.5)
		(connect_pads
			(clearance 0)
		)
		(min_thickness 0.25)
		(keepout
			(tracks not_allowed)
			(vias allowed)
			(pads allowed)
			(copperpour not_allowed)
			(footprints allowed)
		)
		(placement
			(enabled no)
			(sheetname "")
		)
		(fill yes
			(thermal_gap 0.5)
			(thermal_bridge_width 0.5)
			(island_removal_mode 0)
		)
		(polygon
			(pts
				(arc
					(start 185.851292 -351.822004)
					(mid 184.073292 -351.822004)
					(end 185.851292 -351.822004)
				)
			)
		)
	)
	(zone
		(layers "In1.Cu" "In3.Cu" "In5.Cu" "In7.Cu" "In8.Cu" "In9.Cu" "In10.Cu"
			"In12.Cu" "In14.Cu" "In16.Cu"
		)
		(hatch none 0.5)
		(connect_pads
			(clearance 0)
		)
		(min_thickness 0.25)
		(keepout
			(tracks not_allowed)
			(vias allowed)
			(pads allowed)
			(copperpour not_allowed)
			(footprints allowed)
		)
		(placement
			(enabled no)
			(sheetname "")
		)
		(fill yes
			(thermal_gap 0.5)
			(thermal_bridge_width 0.5)
			(island_removal_mode 0)
		)
		(polygon
			(pts
				(arc
					(start 312.762646 -349.899732)
					(mid 310.984646 -349.899732)
					(end 312.762646 -349.899732)
				)
			)
		)
	)
	(zone
		(layers "In1.Cu" "In3.Cu" "In5.Cu" "In7.Cu" "In8.Cu" "In9.Cu" "In10.Cu"
			"In12.Cu" "In14.Cu" "In16.Cu"
		)
		(hatch none 0.5)
		(connect_pads
			(clearance 0)
		)
		(min_thickness 0.25)
		(keepout
			(tracks not_allowed)
			(vias allowed)
			(pads allowed)
			(copperpour not_allowed)
			(footprints allowed)
		)
		(placement
			(enabled no)
			(sheetname "")
		)
		(fill yes
			(thermal_gap 0.5)
			(thermal_bridge_width 0.5)
			(island_removal_mode 0)
		)
		(polygon
			(pts
				(arc
					(start 30.788864 -348.709488)
					(mid 29.028644 -348.709488)
					(end 30.788864 -348.709488)
				)
			)
		)
	)
	(zone
		(layers "In1.Cu" "In3.Cu" "In5.Cu" "In7.Cu" "In8.Cu" "In9.Cu" "In10.Cu"
			"In12.Cu" "In14.Cu" "In16.Cu"
		)
		(hatch none 0.5)
		(connect_pads
			(clearance 0)
		)
		(min_thickness 0.25)
		(keepout
			(tracks not_allowed)
			(vias allowed)
			(pads allowed)
			(copperpour not_allowed)
			(footprints allowed)
		)
		(placement
			(enabled no)
			(sheetname "")
		)
		(fill yes
			(thermal_gap 0.5)
			(thermal_bridge_width 0.5)
			(island_removal_mode 0)
		)
		(polygon
			(pts
				(arc
					(start 194.17792 -352.563684)
					(mid 192.39992 -352.563684)
					(end 194.17792 -352.563684)
				)
			)
		)
	)
	(zone
		(layers "In1.Cu" "In3.Cu" "In5.Cu" "In7.Cu" "In8.Cu" "In9.Cu" "In10.Cu"
			"In12.Cu" "In14.Cu" "In16.Cu"
		)
		(hatch none 0.5)
		(connect_pads
			(clearance 0)
		)
		(min_thickness 0.25)
		(keepout
			(tracks not_allowed)
			(vias allowed)
			(pads allowed)
			(copperpour not_allowed)
			(footprints allowed)
		)
		(placement
			(enabled no)
			(sheetname "")
		)
		(fill yes
			(thermal_gap 0.5)
			(thermal_bridge_width 0.5)
			(island_removal_mode 0)
		)
		(polygon
			(pts
				(arc
					(start 278.482806 -347.288612)
					(mid 276.704806 -347.288612)
					(end 278.482806 -347.288612)
				)
			)
		)
	)
	(zone
		(layers "In1.Cu" "In3.Cu" "In5.Cu" "In7.Cu" "In8.Cu" "In9.Cu" "In10.Cu"
			"In12.Cu" "In14.Cu" "In16.Cu"
		)
		(hatch none 0.5)
		(connect_pads
			(clearance 0)
		)
		(min_thickness 0.25)
		(keepout
			(tracks not_allowed)
			(vias allowed)
			(pads allowed)
			(copperpour not_allowed)
			(footprints allowed)
		)
		(placement
			(enabled no)
			(sheetname "")
		)
		(fill yes
			(thermal_gap 0.5)
			(thermal_bridge_width 0.5)
			(island_removal_mode 0)
		)
		(polygon
			(pts
				(arc
					(start 296.608246 -349.518732)
					(mid 294.830246 -349.518732)
					(end 296.608246 -349.518732)
				)
			)
		)
	)
	(zone
		(layers "In1.Cu" "In3.Cu" "In5.Cu" "In7.Cu" "In8.Cu" "In9.Cu" "In10.Cu"
			"In12.Cu" "In14.Cu" "In16.Cu"
		)
		(hatch none 0.5)
		(connect_pads
			(clearance 0)
		)
		(min_thickness 0.25)
		(keepout
			(tracks not_allowed)
			(vias allowed)
			(pads allowed)
			(copperpour not_allowed)
			(footprints allowed)
		)
		(placement
			(enabled no)
			(sheetname "")
		)
		(fill yes
			(thermal_gap 0.5)
			(thermal_bridge_width 0.5)
			(island_removal_mode 0)
		)
		(polygon
			(pts
				(arc
					(start 81.130648 -182.2196)
					(mid 79.352648 -182.2196)
					(end 81.130648 -182.2196)
				)
			)
		)
	)
	(zone
		(layers "In1.Cu" "In3.Cu" "In5.Cu" "In7.Cu" "In8.Cu" "In9.Cu" "In10.Cu"
			"In12.Cu" "In14.Cu" "In16.Cu"
		)
		(hatch none 0.5)
		(connect_pads
			(clearance 0)
		)
		(min_thickness 0.25)
		(keepout
			(tracks not_allowed)
			(vias allowed)
			(pads allowed)
			(copperpour not_allowed)
			(footprints allowed)
		)
		(placement
			(enabled no)
			(sheetname "")
		)
		(fill yes
			(thermal_gap 0.5)
			(thermal_bridge_width 0.5)
			(island_removal_mode 0)
		)
		(polygon
			(pts
				(arc
					(start 442.243718 -18.57756)
					(mid 440.465718 -18.57756)
					(end 442.243718 -18.57756)
				)
			)
		)
	)
	(zone
		(layers "In1.Cu" "In3.Cu" "In5.Cu" "In7.Cu" "In8.Cu" "In9.Cu" "In10.Cu"
			"In12.Cu" "In14.Cu" "In16.Cu"
		)
		(hatch none 0.5)
		(connect_pads
			(clearance 0)
		)
		(min_thickness 0.25)
		(keepout
			(tracks not_allowed)
			(vias allowed)
			(pads allowed)
			(copperpour not_allowed)
			(footprints allowed)
		)
		(placement
			(enabled no)
			(sheetname "")
		)
		(fill yes
			(thermal_gap 0.5)
			(thermal_bridge_width 0.5)
			(island_removal_mode 0)
		)
		(polygon
			(pts
				(arc
					(start 187.519818 -354.834444)
					(mid 185.741818 -354.834444)
					(end 187.519818 -354.834444)
				)
			)
		)
	)
	(zone
		(layers "In1.Cu" "In3.Cu" "In5.Cu" "In7.Cu" "In8.Cu" "In9.Cu" "In10.Cu"
			"In12.Cu" "In14.Cu" "In16.Cu"
		)
		(hatch none 0.5)
		(connect_pads
			(clearance 0)
		)
		(min_thickness 0.25)
		(keepout
			(tracks not_allowed)
			(vias allowed)
			(pads allowed)
			(copperpour not_allowed)
			(footprints allowed)
		)
		(placement
			(enabled no)
			(sheetname "")
		)
		(fill yes
			(thermal_gap 0.5)
			(thermal_bridge_width 0.5)
			(island_removal_mode 0)
		)
		(polygon
			(pts
				(arc
					(start 278.482806 -348.025212)
					(mid 276.704806 -348.025212)
					(end 278.482806 -348.025212)
				)
			)
		)
	)
	(zone
		(layers "In1.Cu" "In3.Cu" "In5.Cu" "In7.Cu" "In8.Cu" "In9.Cu" "In10.Cu"
			"In12.Cu" "In14.Cu" "In16.Cu"
		)
		(hatch none 0.5)
		(connect_pads
			(clearance 0)
		)
		(min_thickness 0.25)
		(keepout
			(tracks not_allowed)
			(vias allowed)
			(pads allowed)
			(copperpour not_allowed)
			(footprints allowed)
		)
		(placement
			(enabled no)
			(sheetname "")
		)
		(fill yes
			(thermal_gap 0.5)
			(thermal_bridge_width 0.5)
			(island_removal_mode 0)
		)
		(polygon
			(pts
				(arc
					(start 310.267096 -348.704662)
					(mid 308.506876 -348.704662)
					(end 310.267096 -348.704662)
				)
			)
		)
	)
	(zone
		(layers "In1.Cu" "In3.Cu" "In5.Cu" "In7.Cu" "In8.Cu" "In9.Cu" "In10.Cu"
			"In12.Cu" "In14.Cu" "In16.Cu"
		)
		(hatch none 0.5)
		(connect_pads
			(clearance 0)
		)
		(min_thickness 0.25)
		(keepout
			(tracks not_allowed)
			(vias allowed)
			(pads allowed)
			(copperpour not_allowed)
			(footprints allowed)
		)
		(placement
			(enabled no)
			(sheetname "")
		)
		(fill yes
			(thermal_gap 0.5)
			(thermal_bridge_width 0.5)
			(island_removal_mode 0)
		)
		(polygon
			(pts
				(arc
					(start 199.375014 -30.133798)
					(mid 197.597014 -30.133798)
					(end 199.375014 -30.133798)
				)
			)
		)
	)
	(zone
		(layers "In1.Cu" "In3.Cu" "In5.Cu" "In7.Cu" "In8.Cu" "In9.Cu" "In10.Cu"
			"In12.Cu" "In14.Cu" "In16.Cu"
		)
		(hatch none 0.5)
		(connect_pads
			(clearance 0)
		)
		(min_thickness 0.25)
		(keepout
			(tracks not_allowed)
			(vias allowed)
			(pads allowed)
			(copperpour not_allowed)
			(footprints allowed)
		)
		(placement
			(enabled no)
			(sheetname "")
		)
		(fill yes
			(thermal_gap 0.5)
			(thermal_bridge_width 0.5)
			(island_removal_mode 0)
		)
		(polygon
			(pts
				(arc
					(start 105.917492 -341.927688)
					(mid 104.157272 -341.927688)
					(end 105.917492 -341.927688)
				)
			)
		)
	)
	(zone
		(layers "In1.Cu" "In3.Cu" "In5.Cu" "In7.Cu" "In8.Cu" "In9.Cu" "In10.Cu"
			"In12.Cu" "In14.Cu" "In16.Cu"
		)
		(hatch none 0.5)
		(connect_pads
			(clearance 0)
		)
		(min_thickness 0.25)
		(keepout
			(tracks not_allowed)
			(vias allowed)
			(pads allowed)
			(copperpour not_allowed)
			(footprints allowed)
		)
		(placement
			(enabled no)
			(sheetname "")
		)
		(fill yes
			(thermal_gap 0.5)
			(thermal_bridge_width 0.5)
			(island_removal_mode 0)
		)
		(polygon
			(pts
				(arc
					(start 313.296046 -349.518732)
					(mid 311.518046 -349.518732)
					(end 313.296046 -349.518732)
				)
			)
		)
	)
	(zone
		(layers "In1.Cu" "In3.Cu" "In5.Cu" "In7.Cu" "In8.Cu" "In9.Cu" "In10.Cu"
			"In12.Cu" "In14.Cu" "In16.Cu"
		)
		(hatch none 0.5)
		(connect_pads
			(clearance 0)
		)
		(min_thickness 0.25)
		(keepout
			(tracks not_allowed)
			(vias allowed)
			(pads allowed)
			(copperpour not_allowed)
			(footprints allowed)
		)
		(placement
			(enabled no)
			(sheetname "")
		)
		(fill yes
			(thermal_gap 0.5)
			(thermal_bridge_width 0.5)
			(island_removal_mode 0)
		)
		(polygon
			(pts
				(arc
					(start 121.67743 -162.009074)
					(mid 119.89943 -162.009074)
					(end 121.67743 -162.009074)
				)
			)
		)
	)
	(zone
		(layers "In1.Cu" "In3.Cu" "In5.Cu" "In7.Cu" "In8.Cu" "In9.Cu" "In10.Cu"
			"In12.Cu" "In14.Cu" "In16.Cu"
		)
		(hatch none 0.5)
		(connect_pads
			(clearance 0)
		)
		(min_thickness 0.25)
		(keepout
			(tracks not_allowed)
			(vias allowed)
			(pads allowed)
			(copperpour not_allowed)
			(footprints allowed)
		)
		(placement
			(enabled no)
			(sheetname "")
		)
		(fill yes
			(thermal_gap 0.5)
			(thermal_bridge_width 0.5)
			(island_removal_mode 0)
		)
		(polygon
			(pts
				(arc
					(start 67.187064 -13.09751)
					(mid 65.409064 -13.09751)
					(end 67.187064 -13.09751)
				)
			)
		)
	)
	(zone
		(layers "In1.Cu" "In3.Cu" "In5.Cu" "In7.Cu" "In8.Cu" "In9.Cu" "In10.Cu"
			"In12.Cu" "In14.Cu" "In16.Cu"
		)
		(hatch none 0.5)
		(connect_pads
			(clearance 0)
		)
		(min_thickness 0.25)
		(keepout
			(tracks not_allowed)
			(vias allowed)
			(pads allowed)
			(copperpour not_allowed)
			(footprints allowed)
		)
		(placement
			(enabled no)
			(sheetname "")
		)
		(fill yes
			(thermal_gap 0.5)
			(thermal_bridge_width 0.5)
			(island_removal_mode 0)
		)
		(polygon
			(pts
				(arc
					(start 80.292194 -178.384454)
					(mid 78.514194 -178.384454)
					(end 80.292194 -178.384454)
				)
			)
		)
	)
	(zone
		(layers "In1.Cu" "In3.Cu" "In5.Cu" "In7.Cu" "In8.Cu" "In9.Cu" "In10.Cu"
			"In12.Cu" "In14.Cu" "In16.Cu"
		)
		(hatch none 0.5)
		(connect_pads
			(clearance 0)
		)
		(min_thickness 0.25)
		(keepout
			(tracks not_allowed)
			(vias allowed)
			(pads allowed)
			(copperpour not_allowed)
			(footprints allowed)
		)
		(placement
			(enabled no)
			(sheetname "")
		)
		(fill yes
			(thermal_gap 0.5)
			(thermal_bridge_width 0.5)
			(island_removal_mode 0)
		)
		(polygon
			(pts
				(arc
					(start 57.1119 -393.292838)
					(mid 57.4167 -393.597638)
					(end 57.7215 -393.292838)
				)
				(arc
					(start 57.7215 -392.429238)
					(mid 57.4167 -392.124438)
					(end 57.1119 -392.429238)
				)
			)
		)
	)
	(zone
		(layers "In1.Cu" "In3.Cu" "In5.Cu" "In7.Cu" "In8.Cu" "In9.Cu" "In10.Cu"
			"In12.Cu" "In14.Cu" "In16.Cu"
		)
		(hatch none 0.5)
		(connect_pads
			(clearance 0)
		)
		(min_thickness 0.25)
		(keepout
			(tracks not_allowed)
			(vias allowed)
			(pads allowed)
			(copperpour not_allowed)
			(footprints allowed)
		)
		(placement
			(enabled no)
			(sheetname "")
		)
		(fill yes
			(thermal_gap 0.5)
			(thermal_bridge_width 0.5)
			(island_removal_mode 0)
		)
		(polygon
			(pts
				(arc
					(start 427.160436 -354.71227)
					(mid 425.382436 -354.71227)
					(end 427.160436 -354.71227)
				)
			)
		)
	)
	(zone
		(layers "In1.Cu" "In3.Cu" "In5.Cu" "In7.Cu" "In8.Cu" "In9.Cu" "In10.Cu"
			"In12.Cu" "In14.Cu" "In16.Cu"
		)
		(hatch none 0.5)
		(connect_pads
			(clearance 0)
		)
		(min_thickness 0.25)
		(keepout
			(tracks not_allowed)
			(vias allowed)
			(pads allowed)
			(copperpour not_allowed)
			(footprints allowed)
		)
		(placement
			(enabled no)
			(sheetname "")
		)
		(fill yes
			(thermal_gap 0.5)
			(thermal_bridge_width 0.5)
			(island_removal_mode 0)
		)
		(polygon
			(pts
				(arc
					(start 435.487064 -354.73767)
					(mid 433.709064 -354.73767)
					(end 435.487064 -354.73767)
				)
			)
		)
	)
	(zone
		(layers "In1.Cu" "In3.Cu" "In5.Cu" "In7.Cu" "In8.Cu" "In9.Cu" "In10.Cu"
			"In12.Cu" "In14.Cu" "In16.Cu"
		)
		(hatch none 0.5)
		(connect_pads
			(clearance 0)
		)
		(min_thickness 0.25)
		(keepout
			(tracks not_allowed)
			(vias allowed)
			(pads allowed)
			(copperpour not_allowed)
			(footprints allowed)
		)
		(placement
			(enabled no)
			(sheetname "")
		)
		(fill yes
			(thermal_gap 0.5)
			(thermal_bridge_width 0.5)
			(island_removal_mode 0)
		)
		(polygon
			(pts
				(arc
					(start 355.605588 -167.507666)
					(mid 353.845368 -167.507666)
					(end 355.605588 -167.507666)
				)
			)
		)
	)
	(zone
		(layers "In1.Cu" "In3.Cu" "In5.Cu" "In7.Cu" "In8.Cu" "In9.Cu" "In10.Cu"
			"In12.Cu" "In14.Cu" "In16.Cu"
		)
		(hatch none 0.5)
		(connect_pads
			(clearance 0)
		)
		(min_thickness 0.25)
		(keepout
			(tracks not_allowed)
			(vias allowed)
			(pads allowed)
			(copperpour not_allowed)
			(footprints allowed)
		)
		(placement
			(enabled no)
			(sheetname "")
		)
		(fill yes
			(thermal_gap 0.5)
			(thermal_bridge_width 0.5)
			(island_removal_mode 0)
		)
		(polygon
			(pts
				(arc
					(start 33.200594 -350.260158)
					(mid 31.422594 -350.260158)
					(end 33.200594 -350.260158)
				)
			)
		)
	)
	(zone
		(layers "In1.Cu" "In3.Cu" "In5.Cu" "In7.Cu" "In8.Cu" "In9.Cu" "In10.Cu"
			"In12.Cu" "In14.Cu" "In16.Cu"
		)
		(hatch none 0.5)
		(connect_pads
			(clearance 0)
		)
		(min_thickness 0.25)
		(keepout
			(tracks not_allowed)
			(vias allowed)
			(pads allowed)
			(copperpour not_allowed)
			(footprints allowed)
		)
		(placement
			(enabled no)
			(sheetname "")
		)
		(fill yes
			(thermal_gap 0.5)
			(thermal_bridge_width 0.5)
			(island_removal_mode 0)
		)
		(polygon
			(pts
				(arc
					(start 434.776118 -353.12858)
					(mid 433.015898 -353.12858)
					(end 434.776118 -353.12858)
				)
			)
		)
	)
	(zone
		(layers "In1.Cu" "In3.Cu" "In5.Cu" "In7.Cu" "In8.Cu" "In9.Cu" "In10.Cu"
			"In12.Cu" "In14.Cu" "In16.Cu"
		)
		(hatch none 0.5)
		(connect_pads
			(clearance 0)
		)
		(min_thickness 0.25)
		(keepout
			(tracks not_allowed)
			(vias allowed)
			(pads allowed)
			(copperpour not_allowed)
			(footprints allowed)
		)
		(placement
			(enabled no)
			(sheetname "")
		)
		(fill yes
			(thermal_gap 0.5)
			(thermal_bridge_width 0.5)
			(island_removal_mode 0)
		)
		(polygon
			(pts
				(arc
					(start 362.575602 -174.173896)
					(mid 360.797602 -174.173896)
					(end 362.575602 -174.173896)
				)
			)
		)
	)
	(zone
		(layers "In1.Cu" "In3.Cu" "In5.Cu" "In7.Cu" "In8.Cu" "In9.Cu" "In10.Cu"
			"In12.Cu" "In14.Cu" "In16.Cu"
		)
		(hatch none 0.5)
		(connect_pads
			(clearance 0)
		)
		(min_thickness 0.25)
		(keepout
			(tracks not_allowed)
			(vias allowed)
			(pads allowed)
			(copperpour not_allowed)
			(footprints allowed)
		)
		(placement
			(enabled no)
			(sheetname "")
		)
		(fill yes
			(thermal_gap 0.5)
			(thermal_bridge_width 0.5)
			(island_removal_mode 0)
		)
		(polygon
			(pts
				(arc
					(start 241.782854 -44.830746)
					(mid 240.004854 -44.830746)
					(end 241.782854 -44.830746)
				)
			)
		)
	)
	(zone
		(layers "In1.Cu" "In3.Cu" "In5.Cu" "In7.Cu" "In8.Cu" "In9.Cu" "In10.Cu"
			"In12.Cu" "In14.Cu" "In16.Cu"
		)
		(hatch none 0.5)
		(connect_pads
			(clearance 0)
		)
		(min_thickness 0.25)
		(keepout
			(tracks not_allowed)
			(vias allowed)
			(pads allowed)
			(copperpour not_allowed)
			(footprints allowed)
		)
		(placement
			(enabled no)
			(sheetname "")
		)
		(fill yes
			(thermal_gap 0.5)
			(thermal_bridge_width 0.5)
			(island_removal_mode 0)
		)
		(polygon
			(pts
				(arc
					(start 130.685794 -153.670254)
					(mid 128.907794 -153.670254)
					(end 130.685794 -153.670254)
				)
			)
		)
	)
	(zone
		(layers "In1.Cu" "In3.Cu" "In5.Cu" "In7.Cu" "In8.Cu" "In9.Cu" "In10.Cu"
			"In12.Cu" "In14.Cu" "In16.Cu"
		)
		(hatch none 0.5)
		(connect_pads
			(clearance 0)
		)
		(min_thickness 0.25)
		(keepout
			(tracks not_allowed)
			(vias allowed)
			(pads allowed)
			(copperpour not_allowed)
			(footprints allowed)
		)
		(placement
			(enabled no)
			(sheetname "")
		)
		(fill yes
			(thermal_gap 0.5)
			(thermal_bridge_width 0.5)
			(island_removal_mode 0)
		)
		(polygon
			(pts
				(arc
					(start 90.46845 -163.447476)
					(mid 88.69045 -163.447476)
					(end 90.46845 -163.447476)
				)
			)
		)
	)
	(zone
		(layers "In1.Cu" "In3.Cu" "In5.Cu" "In7.Cu" "In8.Cu" "In9.Cu" "In10.Cu"
			"In12.Cu" "In14.Cu" "In16.Cu"
		)
		(hatch none 0.5)
		(connect_pads
			(clearance 0)
		)
		(min_thickness 0.25)
		(keepout
			(tracks not_allowed)
			(vias allowed)
			(pads allowed)
			(copperpour not_allowed)
			(footprints allowed)
		)
		(placement
			(enabled no)
			(sheetname "")
		)
		(fill yes
			(thermal_gap 0.5)
			(thermal_bridge_width 0.5)
			(island_removal_mode 0)
		)
		(polygon
			(pts
				(arc
					(start 364.510828 -175.859186)
					(mid 362.750608 -175.859186)
					(end 364.510828 -175.859186)
				)
			)
		)
	)
	(zone
		(layers "In1.Cu" "In3.Cu" "In5.Cu" "In7.Cu" "In8.Cu" "In9.Cu" "In10.Cu"
			"In12.Cu" "In14.Cu" "In16.Cu"
		)
		(hatch none 0.5)
		(connect_pads
			(clearance 0)
		)
		(min_thickness 0.25)
		(keepout
			(tracks not_allowed)
			(vias allowed)
			(pads allowed)
			(copperpour not_allowed)
			(footprints allowed)
		)
		(placement
			(enabled no)
			(sheetname "")
		)
		(fill yes
			(thermal_gap 0.5)
			(thermal_bridge_width 0.5)
			(island_removal_mode 0)
		)
		(polygon
			(pts
				(arc
					(start 330.742544 -337.409536)
					(mid 328.964544 -337.409536)
					(end 330.742544 -337.409536)
				)
			)
		)
	)
	(zone
		(layers "In1.Cu" "In3.Cu" "In5.Cu" "In7.Cu" "In8.Cu" "In9.Cu" "In10.Cu"
			"In12.Cu" "In14.Cu" "In16.Cu"
		)
		(hatch none 0.5)
		(connect_pads
			(clearance 0)
		)
		(min_thickness 0.25)
		(keepout
			(tracks not_allowed)
			(vias allowed)
			(pads allowed)
			(copperpour not_allowed)
			(footprints allowed)
		)
		(placement
			(enabled no)
			(sheetname "")
		)
		(fill yes
			(thermal_gap 0.5)
			(thermal_bridge_width 0.5)
			(island_removal_mode 0)
		)
		(polygon
			(pts
				(arc
					(start 426.575474 -351.62109)
					(mid 424.797474 -351.62109)
					(end 426.575474 -351.62109)
				)
			)
		)
	)
	(zone
		(layers "In1.Cu" "In3.Cu" "In5.Cu" "In7.Cu" "In8.Cu" "In9.Cu" "In10.Cu"
			"In12.Cu" "In14.Cu" "In16.Cu"
		)
		(hatch none 0.5)
		(connect_pads
			(clearance 0)
		)
		(min_thickness 0.25)
		(keepout
			(tracks not_allowed)
			(vias allowed)
			(pads allowed)
			(copperpour not_allowed)
			(footprints allowed)
		)
		(placement
			(enabled no)
			(sheetname "")
		)
		(fill yes
			(thermal_gap 0.5)
			(thermal_bridge_width 0.5)
			(island_removal_mode 0)
		)
		(polygon
			(pts
				(arc
					(start 426.44949 -353.10318)
					(mid 424.68927 -353.10318)
					(end 426.44949 -353.10318)
				)
			)
		)
	)
	(zone
		(layers "In1.Cu" "In3.Cu" "In5.Cu" "In7.Cu" "In8.Cu" "In9.Cu" "In10.Cu"
			"In12.Cu" "In14.Cu" "In16.Cu"
		)
		(hatch none 0.5)
		(connect_pads
			(clearance 0)
		)
		(min_thickness 0.25)
		(keepout
			(tracks not_allowed)
			(vias allowed)
			(pads allowed)
			(copperpour not_allowed)
			(footprints allowed)
		)
		(placement
			(enabled no)
			(sheetname "")
		)
		(fill yes
			(thermal_gap 0.5)
			(thermal_bridge_width 0.5)
			(island_removal_mode 0)
		)
		(polygon
			(pts
				(arc
					(start 312.212482 -349.577152)
					(mid 310.434482 -349.577152)
					(end 312.212482 -349.577152)
				)
			)
		)
	)
	(zone
		(layers "In1.Cu" "In3.Cu" "In5.Cu" "In7.Cu" "In8.Cu" "In9.Cu" "In10.Cu"
			"In12.Cu" "In14.Cu" "In16.Cu"
		)
		(hatch none 0.5)
		(connect_pads
			(clearance 0)
		)
		(min_thickness 0.25)
		(keepout
			(tracks not_allowed)
			(vias allowed)
			(pads allowed)
			(copperpour not_allowed)
			(footprints allowed)
		)
		(placement
			(enabled no)
			(sheetname "")
		)
		(fill yes
			(thermal_gap 0.5)
			(thermal_bridge_width 0.5)
			(island_removal_mode 0)
		)
		(polygon
			(pts
				(arc
					(start 56.616854 -347.260418)
					(mid 54.838854 -347.260418)
					(end 56.616854 -347.260418)
				)
			)
		)
	)
	(zone
		(layers "In1.Cu" "In3.Cu" "In5.Cu" "In7.Cu" "In8.Cu" "In9.Cu" "In10.Cu"
			"In12.Cu" "In14.Cu" "In16.Cu"
		)
		(hatch none 0.5)
		(connect_pads
			(clearance 0)
		)
		(min_thickness 0.25)
		(keepout
			(tracks not_allowed)
			(vias allowed)
			(pads allowed)
			(copperpour not_allowed)
			(footprints allowed)
		)
		(placement
			(enabled no)
			(sheetname "")
		)
		(fill yes
			(thermal_gap 0.5)
			(thermal_bridge_width 0.5)
			(island_removal_mode 0)
		)
		(polygon
			(pts
				(arc
					(start 303.881282 -350.313752)
					(mid 302.103282 -350.313752)
					(end 303.881282 -350.313752)
				)
			)
		)
	)
	(zone
		(layers "In1.Cu" "In3.Cu" "In5.Cu" "In7.Cu" "In8.Cu" "In9.Cu" "In10.Cu"
			"In12.Cu" "In14.Cu" "In16.Cu"
		)
		(hatch none 0.5)
		(connect_pads
			(clearance 0)
		)
		(min_thickness 0.25)
		(keepout
			(tracks not_allowed)
			(vias allowed)
			(pads allowed)
			(copperpour not_allowed)
			(footprints allowed)
		)
		(placement
			(enabled no)
			(sheetname "")
		)
		(fill yes
			(thermal_gap 0.5)
			(thermal_bridge_width 0.5)
			(island_removal_mode 0)
		)
		(polygon
			(pts
				(arc
					(start 67.771264 -22.26691)
					(mid 65.993264 -22.26691)
					(end 67.771264 -22.26691)
				)
			)
		)
	)
	(zone
		(layers "In1.Cu" "In3.Cu" "In5.Cu" "In7.Cu" "In8.Cu" "In9.Cu" "In10.Cu"
			"In12.Cu" "In14.Cu" "In16.Cu"
		)
		(hatch none 0.5)
		(connect_pads
			(clearance 0)
		)
		(min_thickness 0.25)
		(keepout
			(tracks not_allowed)
			(vias allowed)
			(pads allowed)
			(copperpour not_allowed)
			(footprints allowed)
		)
		(placement
			(enabled no)
			(sheetname "")
		)
		(fill yes
			(thermal_gap 0.5)
			(thermal_bridge_width 0.5)
			(island_removal_mode 0)
		)
		(polygon
			(pts
				(arc
					(start 388.182358 -156.366972)
					(mid 386.404358 -156.366972)
					(end 388.182358 -156.366972)
				)
			)
		)
	)
	(zone
		(layers "In1.Cu" "In3.Cu" "In5.Cu" "In7.Cu" "In8.Cu" "In9.Cu" "In10.Cu"
			"In12.Cu" "In14.Cu" "In16.Cu"
		)
		(hatch none 0.5)
		(connect_pads
			(clearance 0)
		)
		(min_thickness 0.25)
		(keepout
			(tracks not_allowed)
			(vias allowed)
			(pads allowed)
			(copperpour not_allowed)
			(footprints allowed)
		)
		(placement
			(enabled no)
			(sheetname "")
		)
		(fill yes
			(thermal_gap 0.5)
			(thermal_bridge_width 0.5)
			(island_removal_mode 0)
		)
		(polygon
			(pts
				(arc
					(start 48.769778 -358.108504)
					(mid 46.991778 -358.108504)
					(end 48.769778 -358.108504)
				)
			)
		)
	)
	(zone
		(layers "In1.Cu" "In3.Cu" "In5.Cu" "In7.Cu" "In8.Cu" "In9.Cu" "In10.Cu"
			"In12.Cu" "In14.Cu" "In16.Cu"
		)
		(hatch none 0.5)
		(connect_pads
			(clearance 0)
		)
		(min_thickness 0.25)
		(keepout
			(tracks not_allowed)
			(vias allowed)
			(pads allowed)
			(copperpour not_allowed)
			(footprints allowed)
		)
		(placement
			(enabled no)
			(sheetname "")
		)
		(fill yes
			(thermal_gap 0.5)
			(thermal_bridge_width 0.5)
			(island_removal_mode 0)
		)
		(polygon
			(pts
				(arc
					(start 178.999134 -26.634948)
					(mid 177.221134 -26.634948)
					(end 178.999134 -26.634948)
				)
			)
		)
	)
	(zone
		(layers "In1.Cu" "In3.Cu" "In5.Cu" "In7.Cu" "In8.Cu" "In9.Cu" "In10.Cu"
			"In12.Cu" "In14.Cu" "In16.Cu"
		)
		(hatch none 0.5)
		(connect_pads
			(clearance 0)
		)
		(min_thickness 0.25)
		(keepout
			(tracks not_allowed)
			(vias allowed)
			(pads allowed)
			(copperpour not_allowed)
			(footprints allowed)
		)
		(placement
			(enabled no)
			(sheetname "")
		)
		(fill yes
			(thermal_gap 0.5)
			(thermal_bridge_width 0.5)
			(island_removal_mode 0)
		)
		(polygon
			(pts
				(arc
					(start 251.668534 -51.333146)
					(mid 249.890534 -51.333146)
					(end 251.668534 -51.333146)
				)
			)
		)
	)
	(zone
		(layers "In1.Cu" "In3.Cu" "In5.Cu" "In7.Cu" "In8.Cu" "In9.Cu" "In10.Cu"
			"In12.Cu" "In14.Cu" "In16.Cu"
		)
		(hatch none 0.5)
		(connect_pads
			(clearance 0)
		)
		(min_thickness 0.25)
		(keepout
			(tracks not_allowed)
			(vias allowed)
			(pads allowed)
			(copperpour not_allowed)
			(footprints allowed)
		)
		(placement
			(enabled no)
			(sheetname "")
		)
		(fill yes
			(thermal_gap 0.5)
			(thermal_bridge_width 0.5)
			(island_removal_mode 0)
		)
		(polygon
			(pts
				(arc
					(start 112.86363 -169.121074)
					(mid 111.08563 -169.121074)
					(end 112.86363 -169.121074)
				)
			)
		)
	)
	(zone
		(layers "In1.Cu" "In3.Cu" "In5.Cu" "In7.Cu" "In8.Cu" "In9.Cu" "In10.Cu"
			"In12.Cu" "In14.Cu" "In16.Cu"
		)
		(hatch none 0.5)
		(connect_pads
			(clearance 0)
		)
		(min_thickness 0.25)
		(keepout
			(tracks not_allowed)
			(vias allowed)
			(pads allowed)
			(copperpour not_allowed)
			(footprints allowed)
		)
		(placement
			(enabled no)
			(sheetname "")
		)
		(fill yes
			(thermal_gap 0.5)
			(thermal_bridge_width 0.5)
			(island_removal_mode 0)
		)
		(polygon
			(pts
				(arc
					(start 387.670802 -179.146454)
					(mid 385.892802 -179.146454)
					(end 387.670802 -179.146454)
				)
			)
		)
	)
	(zone
		(layers "In1.Cu" "In3.Cu" "In5.Cu" "In7.Cu" "In8.Cu" "In9.Cu" "In10.Cu"
			"In12.Cu" "In14.Cu" "In16.Cu"
		)
		(hatch none 0.5)
		(connect_pads
			(clearance 0)
		)
		(min_thickness 0.25)
		(keepout
			(tracks not_allowed)
			(vias allowed)
			(pads allowed)
			(copperpour not_allowed)
			(footprints allowed)
		)
		(placement
			(enabled no)
			(sheetname "")
		)
		(fill yes
			(thermal_gap 0.5)
			(thermal_bridge_width 0.5)
			(island_removal_mode 0)
		)
		(polygon
			(pts
				(arc
					(start 90.203528 -345.237562)
					(mid 88.425528 -345.237562)
					(end 90.203528 -345.237562)
				)
			)
		)
	)
	(zone
		(layers "In1.Cu" "In3.Cu" "In5.Cu" "In7.Cu" "In8.Cu" "In9.Cu" "In10.Cu"
			"In12.Cu" "In14.Cu" "In16.Cu"
		)
		(hatch none 0.5)
		(connect_pads
			(clearance 0)
		)
		(min_thickness 0.25)
		(keepout
			(tracks not_allowed)
			(vias allowed)
			(pads allowed)
			(copperpour not_allowed)
			(footprints allowed)
		)
		(placement
			(enabled no)
			(sheetname "")
		)
		(fill yes
			(thermal_gap 0.5)
			(thermal_bridge_width 0.5)
			(island_removal_mode 0)
		)
		(polygon
			(pts
				(arc
					(start 40.947594 -349.904558)
					(mid 39.169594 -349.904558)
					(end 40.947594 -349.904558)
				)
			)
		)
	)
	(zone
		(layers "In1.Cu" "In3.Cu" "In5.Cu" "In7.Cu" "In8.Cu" "In9.Cu" "In10.Cu"
			"In12.Cu" "In14.Cu" "In16.Cu"
		)
		(hatch none 0.5)
		(connect_pads
			(clearance 0)
		)
		(min_thickness 0.25)
		(keepout
			(tracks not_allowed)
			(vias allowed)
			(pads allowed)
			(copperpour not_allowed)
			(footprints allowed)
		)
		(placement
			(enabled no)
			(sheetname "")
		)
		(fill yes
			(thermal_gap 0.5)
			(thermal_bridge_width 0.5)
			(island_removal_mode 0)
		)
		(polygon
			(pts
				(arc
					(start 346.19565 -337.012788)
					(mid 344.43543 -337.012788)
					(end 346.19565 -337.012788)
				)
			)
		)
	)
	(zone
		(layers "In1.Cu" "In3.Cu" "In5.Cu" "In7.Cu" "In8.Cu" "In9.Cu" "In10.Cu"
			"In12.Cu" "In14.Cu" "In16.Cu"
		)
		(hatch none 0.5)
		(connect_pads
			(clearance 0)
		)
		(min_thickness 0.25)
		(keepout
			(tracks not_allowed)
			(vias allowed)
			(pads allowed)
			(copperpour not_allowed)
			(footprints allowed)
		)
		(placement
			(enabled no)
			(sheetname "")
		)
		(fill yes
			(thermal_gap 0.5)
			(thermal_bridge_width 0.5)
			(island_removal_mode 0)
		)
		(polygon
			(pts
				(arc
					(start 370.936774 -179.146454)
					(mid 369.158774 -179.146454)
					(end 370.936774 -179.146454)
				)
			)
		)
	)
	(zone
		(layers "In1.Cu" "In3.Cu" "In5.Cu" "In7.Cu" "In8.Cu" "In9.Cu" "In10.Cu"
			"In12.Cu" "In14.Cu" "In16.Cu"
		)
		(hatch none 0.5)
		(connect_pads
			(clearance 0)
		)
		(min_thickness 0.25)
		(keepout
			(tracks not_allowed)
			(vias allowed)
			(pads allowed)
			(copperpour not_allowed)
			(footprints allowed)
		)
		(placement
			(enabled no)
			(sheetname "")
		)
		(fill yes
			(thermal_gap 0.5)
			(thermal_bridge_width 0.5)
			(island_removal_mode 0)
		)
		(polygon
			(pts
				(arc
					(start 442.018674 -25.982422)
					(mid 440.240674 -25.982422)
					(end 442.018674 -25.982422)
				)
			)
		)
	)
	(zone
		(layers "In1.Cu" "In3.Cu" "In5.Cu" "In7.Cu" "In8.Cu" "In9.Cu" "In10.Cu"
			"In12.Cu" "In14.Cu" "In16.Cu"
		)
		(hatch none 0.5)
		(connect_pads
			(clearance 0)
		)
		(min_thickness 0.25)
		(keepout
			(tracks not_allowed)
			(vias allowed)
			(pads allowed)
			(copperpour not_allowed)
			(footprints allowed)
		)
		(placement
			(enabled no)
			(sheetname "")
		)
		(fill yes
			(thermal_gap 0.5)
			(thermal_bridge_width 0.5)
			(island_removal_mode 0)
		)
		(polygon
			(pts
				(arc
					(start 55.91175 -393.292838)
					(mid 56.21655 -393.597638)
					(end 56.52135 -393.292838)
				)
				(arc
					(start 56.52135 -392.429238)
					(mid 56.21655 -392.124438)
					(end 55.91175 -392.429238)
				)
			)
		)
	)
	(zone
		(layers "In1.Cu" "In3.Cu" "In5.Cu" "In7.Cu" "In8.Cu" "In9.Cu" "In10.Cu"
			"In12.Cu" "In14.Cu" "In16.Cu"
		)
		(hatch none 0.5)
		(connect_pads
			(clearance 0)
		)
		(min_thickness 0.25)
		(keepout
			(tracks not_allowed)
			(vias allowed)
			(pads allowed)
			(copperpour not_allowed)
			(footprints allowed)
		)
		(placement
			(enabled no)
			(sheetname "")
		)
		(fill yes
			(thermal_gap 0.5)
			(thermal_bridge_width 0.5)
			(island_removal_mode 0)
		)
		(polygon
			(pts
				(arc
					(start 177.857912 -21.349208)
					(mid 176.079912 -21.349208)
					(end 177.857912 -21.349208)
				)
			)
		)
	)
	(zone
		(layers "In1.Cu" "In3.Cu" "In5.Cu" "In7.Cu" "In8.Cu" "In9.Cu" "In10.Cu"
			"In12.Cu" "In14.Cu" "In16.Cu"
		)
		(hatch none 0.5)
		(connect_pads
			(clearance 0)
		)
		(min_thickness 0.25)
		(keepout
			(tracks not_allowed)
			(vias allowed)
			(pads allowed)
			(copperpour not_allowed)
			(footprints allowed)
		)
		(placement
			(enabled no)
			(sheetname "")
		)
		(fill yes
			(thermal_gap 0.5)
			(thermal_bridge_width 0.5)
			(island_removal_mode 0)
		)
		(polygon
			(pts
				(arc
					(start 69.447664 -24.88311)
					(mid 67.669664 -24.88311)
					(end 69.447664 -24.88311)
				)
			)
		)
	)
	(zone
		(layers "In1.Cu" "In3.Cu" "In5.Cu" "In7.Cu" "In8.Cu" "In9.Cu" "In10.Cu"
			"In12.Cu" "In14.Cu" "In16.Cu"
		)
		(hatch none 0.5)
		(connect_pads
			(clearance 0)
		)
		(min_thickness 0.25)
		(keepout
			(tracks not_allowed)
			(vias allowed)
			(pads allowed)
			(copperpour not_allowed)
			(footprints allowed)
		)
		(placement
			(enabled no)
			(sheetname "")
		)
		(fill yes
			(thermal_gap 0.5)
			(thermal_bridge_width 0.5)
			(island_removal_mode 0)
		)
		(polygon
			(pts
				(arc
					(start 31.684214 -347.229938)
					(mid 29.906214 -347.229938)
					(end 31.684214 -347.229938)
				)
			)
		)
	)
	(zone
		(layers "In1.Cu" "In3.Cu" "In5.Cu" "In7.Cu" "In8.Cu" "In9.Cu" "In10.Cu"
			"In12.Cu" "In14.Cu" "In16.Cu"
		)
		(hatch none 0.5)
		(connect_pads
			(clearance 0)
		)
		(min_thickness 0.25)
		(keepout
			(tracks not_allowed)
			(vias allowed)
			(pads allowed)
			(copperpour not_allowed)
			(footprints allowed)
		)
		(placement
			(enabled no)
			(sheetname "")
		)
		(fill yes
			(thermal_gap 0.5)
			(thermal_bridge_width 0.5)
			(island_removal_mode 0)
		)
		(polygon
			(pts
				(arc
					(start 370.838984 -164.53358)
					(mid 369.060984 -164.53358)
					(end 370.838984 -164.53358)
				)
			)
		)
	)
	(zone
		(layers "In1.Cu" "In3.Cu" "In5.Cu" "In7.Cu" "In8.Cu" "In9.Cu" "In10.Cu"
			"In12.Cu" "In14.Cu" "In16.Cu"
		)
		(hatch none 0.5)
		(connect_pads
			(clearance 0)
		)
		(min_thickness 0.25)
		(keepout
			(tracks not_allowed)
			(vias allowed)
			(pads allowed)
			(copperpour not_allowed)
			(footprints allowed)
		)
		(placement
			(enabled no)
			(sheetname "")
		)
		(fill yes
			(thermal_gap 0.5)
			(thermal_bridge_width 0.5)
			(island_removal_mode 0)
		)
		(polygon
			(pts
				(arc
					(start 337.24723 -336.961988)
					(mid 335.48701 -336.961988)
					(end 337.24723 -336.961988)
				)
			)
		)
	)
	(zone
		(layers "In1.Cu" "In3.Cu" "In5.Cu" "In7.Cu" "In8.Cu" "In9.Cu" "In10.Cu"
			"In12.Cu" "In14.Cu" "In16.Cu"
		)
		(hatch none 0.5)
		(connect_pads
			(clearance 0)
		)
		(min_thickness 0.25)
		(keepout
			(tracks not_allowed)
			(vias allowed)
			(pads allowed)
			(copperpour not_allowed)
			(footprints allowed)
		)
		(placement
			(enabled no)
			(sheetname "")
		)
		(fill yes
			(thermal_gap 0.5)
			(thermal_bridge_width 0.5)
			(island_removal_mode 0)
		)
		(polygon
			(pts
				(arc
					(start 97.335594 -179.095654)
					(mid 95.557594 -179.095654)
					(end 97.335594 -179.095654)
				)
			)
		)
	)
	(zone
		(layers "In1.Cu" "In3.Cu" "In5.Cu" "In7.Cu" "In8.Cu" "In9.Cu" "In10.Cu"
			"In12.Cu" "In14.Cu" "In16.Cu"
		)
		(hatch none 0.5)
		(connect_pads
			(clearance 0)
		)
		(min_thickness 0.25)
		(keepout
			(tracks not_allowed)
			(vias allowed)
			(pads allowed)
			(copperpour not_allowed)
			(footprints allowed)
		)
		(placement
			(enabled no)
			(sheetname "")
		)
		(fill yes
			(thermal_gap 0.5)
			(thermal_bridge_width 0.5)
			(island_removal_mode 0)
		)
		(polygon
			(pts
				(arc
					(start 187.685172 -360.710988)
					(mid 185.907172 -360.710988)
					(end 187.685172 -360.710988)
				)
			)
		)
	)
	(zone
		(layers "In1.Cu" "In3.Cu" "In5.Cu" "In7.Cu" "In8.Cu" "In9.Cu" "In10.Cu"
			"In12.Cu" "In14.Cu" "In16.Cu"
		)
		(hatch none 0.5)
		(connect_pads
			(clearance 0)
		)
		(min_thickness 0.25)
		(keepout
			(tracks not_allowed)
			(vias allowed)
			(pads allowed)
			(copperpour not_allowed)
			(footprints allowed)
		)
		(placement
			(enabled no)
			(sheetname "")
		)
		(fill yes
			(thermal_gap 0.5)
			(thermal_bridge_width 0.5)
			(island_removal_mode 0)
		)
		(polygon
			(pts
				(arc
					(start 130.685794 -152.933654)
					(mid 128.907794 -152.933654)
					(end 130.685794 -152.933654)
				)
			)
		)
	)
	(zone
		(layers "In1.Cu" "In3.Cu" "In5.Cu" "In7.Cu" "In8.Cu" "In9.Cu" "In10.Cu"
			"In12.Cu" "In14.Cu" "In16.Cu"
		)
		(hatch none 0.5)
		(connect_pads
			(clearance 0)
		)
		(min_thickness 0.25)
		(keepout
			(tracks not_allowed)
			(vias allowed)
			(pads allowed)
			(copperpour not_allowed)
			(footprints allowed)
		)
		(placement
			(enabled no)
			(sheetname "")
		)
		(fill yes
			(thermal_gap 0.5)
			(thermal_bridge_width 0.5)
			(island_removal_mode 0)
		)
		(polygon
			(pts
				(arc
					(start 72.222614 -174.028354)
					(mid 70.444614 -174.028354)
					(end 72.222614 -174.028354)
				)
			)
		)
	)
	(zone
		(layers "In1.Cu" "In3.Cu" "In5.Cu" "In7.Cu" "In8.Cu" "In9.Cu" "In10.Cu"
			"In12.Cu" "In14.Cu" "In16.Cu"
		)
		(hatch none 0.5)
		(connect_pads
			(clearance 0)
		)
		(min_thickness 0.25)
		(keepout
			(tracks not_allowed)
			(vias allowed)
			(pads allowed)
			(copperpour not_allowed)
			(footprints allowed)
		)
		(placement
			(enabled no)
			(sheetname "")
		)
		(fill yes
			(thermal_gap 0.5)
			(thermal_bridge_width 0.5)
			(island_removal_mode 0)
		)
		(polygon
			(pts
				(arc
					(start 438.95899 -13.069316)
					(mid 437.18099 -13.069316)
					(end 438.95899 -13.069316)
				)
			)
		)
	)
	(zone
		(layers "In1.Cu" "In3.Cu" "In5.Cu" "In7.Cu" "In8.Cu" "In9.Cu" "In10.Cu"
			"In12.Cu" "In14.Cu" "In16.Cu"
		)
		(hatch none 0.5)
		(connect_pads
			(clearance 0)
		)
		(min_thickness 0.25)
		(keepout
			(tracks not_allowed)
			(vias allowed)
			(pads allowed)
			(copperpour not_allowed)
			(footprints allowed)
		)
		(placement
			(enabled no)
			(sheetname "")
		)
		(fill yes
			(thermal_gap 0.5)
			(thermal_bridge_width 0.5)
			(island_removal_mode 0)
		)
		(polygon
			(pts
				(arc
					(start 444.22949 -25.461976)
					(mid 442.45149 -25.461976)
					(end 444.22949 -25.461976)
				)
			)
		)
	)
	(zone
		(layers "In1.Cu" "In3.Cu" "In5.Cu" "In7.Cu" "In8.Cu" "In9.Cu" "In10.Cu"
			"In12.Cu" "In14.Cu" "In16.Cu"
		)
		(hatch none 0.5)
		(connect_pads
			(clearance 0)
		)
		(min_thickness 0.25)
		(keepout
			(tracks not_allowed)
			(vias allowed)
			(pads allowed)
			(copperpour not_allowed)
			(footprints allowed)
		)
		(placement
			(enabled no)
			(sheetname "")
		)
		(fill yes
			(thermal_gap 0.5)
			(thermal_bridge_width 0.5)
			(island_removal_mode 0)
		)
		(polygon
			(pts
				(arc
					(start 113.42243 -169.502074)
					(mid 111.64443 -169.502074)
					(end 113.42243 -169.502074)
				)
			)
		)
	)
	(zone
		(layers "In1.Cu" "In3.Cu" "In5.Cu" "In7.Cu" "In8.Cu" "In9.Cu" "In10.Cu"
			"In12.Cu" "In14.Cu" "In16.Cu"
		)
		(hatch none 0.5)
		(connect_pads
			(clearance 0)
		)
		(min_thickness 0.25)
		(keepout
			(tracks not_allowed)
			(vias allowed)
			(pads allowed)
			(copperpour not_allowed)
			(footprints allowed)
		)
		(placement
			(enabled no)
			(sheetname "")
		)
		(fill yes
			(thermal_gap 0.5)
			(thermal_bridge_width 0.5)
			(island_removal_mode 0)
		)
		(polygon
			(pts
				(arc
					(start 38.452044 -348.709488)
					(mid 36.691824 -348.709488)
					(end 38.452044 -348.709488)
				)
			)
		)
	)
	(zone
		(layers "In1.Cu" "In3.Cu" "In5.Cu" "In7.Cu" "In8.Cu" "In9.Cu" "In10.Cu"
			"In12.Cu" "In14.Cu" "In16.Cu"
		)
		(hatch none 0.5)
		(connect_pads
			(clearance 0)
		)
		(min_thickness 0.25)
		(keepout
			(tracks not_allowed)
			(vias allowed)
			(pads allowed)
			(copperpour not_allowed)
			(footprints allowed)
		)
		(placement
			(enabled no)
			(sheetname "")
		)
		(fill yes
			(thermal_gap 0.5)
			(thermal_bridge_width 0.5)
			(island_removal_mode 0)
		)
		(polygon
			(pts
				(arc
					(start 193.350134 -15.781528)
					(mid 191.572134 -15.781528)
					(end 193.350134 -15.781528)
				)
			)
		)
	)
	(zone
		(layers "In1.Cu" "In3.Cu" "In5.Cu" "In7.Cu" "In8.Cu" "In9.Cu" "In10.Cu"
			"In12.Cu" "In14.Cu" "In16.Cu"
		)
		(hatch none 0.5)
		(connect_pads
			(clearance 0)
		)
		(min_thickness 0.25)
		(keepout
			(tracks not_allowed)
			(vias allowed)
			(pads allowed)
			(copperpour not_allowed)
			(footprints allowed)
		)
		(placement
			(enabled no)
			(sheetname "")
		)
		(fill yes
			(thermal_gap 0.5)
			(thermal_bridge_width 0.5)
			(island_removal_mode 0)
		)
		(polygon
			(pts
				(arc
					(start 67.288664 -25.56891)
					(mid 65.510664 -25.56891)
					(end 67.288664 -25.56891)
				)
			)
		)
	)
	(zone
		(layers "In1.Cu" "In3.Cu" "In5.Cu" "In7.Cu" "In8.Cu" "In9.Cu" "In10.Cu"
			"In12.Cu" "In14.Cu" "In16.Cu"
		)
		(hatch none 0.5)
		(connect_pads
			(clearance 0)
		)
		(min_thickness 0.25)
		(keepout
			(tracks not_allowed)
			(vias allowed)
			(pads allowed)
			(copperpour not_allowed)
			(footprints allowed)
		)
		(placement
			(enabled no)
			(sheetname "")
		)
		(fill yes
			(thermal_gap 0.5)
			(thermal_bridge_width 0.5)
			(island_removal_mode 0)
		)
		(polygon
			(pts
				(arc
					(start 371.418358 -182.141876)
					(mid 369.640358 -182.141876)
					(end 371.418358 -182.141876)
				)
			)
		)
	)
	(zone
		(layers "In1.Cu" "In3.Cu" "In5.Cu" "In7.Cu" "In8.Cu" "In9.Cu" "In10.Cu"
			"In12.Cu" "In14.Cu" "In16.Cu"
		)
		(hatch none 0.5)
		(connect_pads
			(clearance 0)
		)
		(min_thickness 0.25)
		(keepout
			(tracks not_allowed)
			(vias allowed)
			(pads allowed)
			(copperpour not_allowed)
			(footprints allowed)
		)
		(placement
			(enabled no)
			(sheetname "")
		)
		(fill yes
			(thermal_gap 0.5)
			(thermal_bridge_width 0.5)
			(island_removal_mode 0)
		)
		(polygon
			(pts
				(arc
					(start 81.858104 -336.245708)
					(mid 80.097884 -336.245708)
					(end 81.858104 -336.245708)
				)
			)
		)
	)
	(zone
		(layers "In1.Cu" "In3.Cu" "In5.Cu" "In7.Cu" "In8.Cu" "In9.Cu" "In10.Cu"
			"In12.Cu" "In14.Cu" "In16.Cu"
		)
		(hatch none 0.5)
		(connect_pads
			(clearance 0)
		)
		(min_thickness 0.25)
		(keepout
			(tracks not_allowed)
			(vias allowed)
			(pads allowed)
			(copperpour not_allowed)
			(footprints allowed)
		)
		(placement
			(enabled no)
			(sheetname "")
		)
		(fill yes
			(thermal_gap 0.5)
			(thermal_bridge_width 0.5)
			(island_removal_mode 0)
		)
		(polygon
			(pts
				(arc
					(start 187.685172 -361.472988)
					(mid 185.907172 -361.472988)
					(end 187.685172 -361.472988)
				)
			)
		)
	)
	(zone
		(layers "In1.Cu" "In3.Cu" "In5.Cu" "In7.Cu" "In8.Cu" "In9.Cu" "In10.Cu"
			"In12.Cu" "In14.Cu" "In16.Cu"
		)
		(hatch none 0.5)
		(connect_pads
			(clearance 0)
		)
		(min_thickness 0.25)
		(keepout
			(tracks not_allowed)
			(vias allowed)
			(pads allowed)
			(copperpour not_allowed)
			(footprints allowed)
		)
		(placement
			(enabled no)
			(sheetname "")
		)
		(fill yes
			(thermal_gap 0.5)
			(thermal_bridge_width 0.5)
			(island_removal_mode 0)
		)
		(polygon
			(pts
				(arc
					(start 181.810914 -27.107388)
					(mid 180.032914 -27.107388)
					(end 181.810914 -27.107388)
				)
			)
		)
	)
	(zone
		(layers "In1.Cu" "In3.Cu" "In5.Cu" "In7.Cu" "In8.Cu" "In9.Cu" "In10.Cu"
			"In12.Cu" "In14.Cu" "In16.Cu"
		)
		(hatch none 0.5)
		(connect_pads
			(clearance 0)
		)
		(min_thickness 0.25)
		(keepout
			(tracks not_allowed)
			(vias allowed)
			(pads allowed)
			(copperpour not_allowed)
			(footprints allowed)
		)
		(placement
			(enabled no)
			(sheetname "")
		)
		(fill yes
			(thermal_gap 0.5)
			(thermal_bridge_width 0.5)
			(island_removal_mode 0)
		)
		(polygon
			(pts
				(arc
					(start 342.914224 -351.453196)
					(mid 341.136224 -351.453196)
					(end 342.914224 -351.453196)
				)
			)
		)
	)
	(zone
		(layers "In1.Cu" "In3.Cu" "In5.Cu" "In7.Cu" "In8.Cu" "In9.Cu" "In10.Cu"
			"In12.Cu" "In14.Cu" "In16.Cu"
		)
		(hatch none 0.5)
		(connect_pads
			(clearance 0)
		)
		(min_thickness 0.25)
		(keepout
			(tracks not_allowed)
			(vias allowed)
			(pads allowed)
			(copperpour not_allowed)
			(footprints allowed)
		)
		(placement
			(enabled no)
			(sheetname "")
		)
		(fill yes
			(thermal_gap 0.5)
			(thermal_bridge_width 0.5)
			(island_removal_mode 0)
		)
		(polygon
			(pts
				(arc
					(start 199.725026 -37.965634)
					(mid 197.947026 -37.965634)
					(end 199.725026 -37.965634)
				)
			)
		)
	)
	(zone
		(layers "In1.Cu" "In3.Cu" "In5.Cu" "In7.Cu" "In8.Cu" "In9.Cu" "In10.Cu"
			"In12.Cu" "In14.Cu" "In16.Cu"
		)
		(hatch none 0.5)
		(connect_pads
			(clearance 0)
		)
		(min_thickness 0.25)
		(keepout
			(tracks not_allowed)
			(vias allowed)
			(pads allowed)
			(copperpour not_allowed)
			(footprints allowed)
		)
		(placement
			(enabled no)
			(sheetname "")
		)
		(fill yes
			(thermal_gap 0.5)
			(thermal_bridge_width 0.5)
			(island_removal_mode 0)
		)
		(polygon
			(pts
				(arc
					(start 185.851292 -352.558604)
					(mid 184.073292 -352.558604)
					(end 185.851292 -352.558604)
				)
			)
		)
	)
	(zone
		(layers "In1.Cu" "In3.Cu" "In5.Cu" "In7.Cu" "In8.Cu" "In9.Cu" "In10.Cu"
			"In12.Cu" "In14.Cu" "In16.Cu"
		)
		(hatch none 0.5)
		(connect_pads
			(clearance 0)
		)
		(min_thickness 0.25)
		(keepout
			(tracks not_allowed)
			(vias allowed)
			(pads allowed)
			(copperpour not_allowed)
			(footprints allowed)
		)
		(placement
			(enabled no)
			(sheetname "")
		)
		(fill yes
			(thermal_gap 0.5)
			(thermal_bridge_width 0.5)
			(island_removal_mode 0)
		)
		(polygon
			(pts
				(arc
					(start 90.239088 -345.96959)
					(mid 88.461088 -345.96959)
					(end 90.239088 -345.96959)
				)
			)
		)
	)
	(zone
		(layers "In1.Cu" "In3.Cu" "In5.Cu" "In7.Cu" "In8.Cu" "In9.Cu" "In10.Cu"
			"In12.Cu" "In14.Cu" "In16.Cu"
		)
		(hatch none 0.5)
		(connect_pads
			(clearance 0)
		)
		(min_thickness 0.25)
		(keepout
			(tracks not_allowed)
			(vias allowed)
			(pads allowed)
			(copperpour not_allowed)
			(footprints allowed)
		)
		(placement
			(enabled no)
			(sheetname "")
		)
		(fill yes
			(thermal_gap 0.5)
			(thermal_bridge_width 0.5)
			(island_removal_mode 0)
		)
		(polygon
			(pts
				(arc
					(start 131.37896 -154.542744)
					(mid 129.61874 -154.542744)
					(end 131.37896 -154.542744)
				)
			)
		)
	)
	(zone
		(layers "In1.Cu" "In3.Cu" "In5.Cu" "In7.Cu" "In8.Cu" "In9.Cu" "In10.Cu"
			"In12.Cu" "In14.Cu" "In16.Cu"
		)
		(hatch none 0.5)
		(connect_pads
			(clearance 0)
		)
		(min_thickness 0.25)
		(keepout
			(tracks not_allowed)
			(vias allowed)
			(pads allowed)
			(copperpour not_allowed)
			(footprints allowed)
		)
		(placement
			(enabled no)
			(sheetname "")
		)
		(fill yes
			(thermal_gap 0.5)
			(thermal_bridge_width 0.5)
			(island_removal_mode 0)
		)
		(polygon
			(pts
				(arc
					(start 336.808064 -349.43161)
					(mid 334.014064 -349.43161)
					(end 336.808064 -349.43161)
				)
			)
		)
	)
	(zone
		(layers "In1.Cu" "In3.Cu" "In5.Cu" "In7.Cu" "In8.Cu" "In9.Cu" "In10.Cu"
			"In12.Cu" "In14.Cu" "In16.Cu"
		)
		(hatch none 0.5)
		(connect_pads
			(clearance 0)
		)
		(min_thickness 0.25)
		(keepout
			(tracks not_allowed)
			(vias allowed)
			(pads allowed)
			(copperpour not_allowed)
			(footprints allowed)
		)
		(placement
			(enabled no)
			(sheetname "")
		)
		(fill yes
			(thermal_gap 0.5)
			(thermal_bridge_width 0.5)
			(island_removal_mode 0)
		)
		(polygon
			(pts
				(arc
					(start 67.663822 -20.327366)
					(mid 65.885822 -20.327366)
					(end 67.663822 -20.327366)
				)
			)
		)
	)
	(zone
		(layers "In1.Cu" "In3.Cu" "In5.Cu" "In7.Cu" "In8.Cu" "In9.Cu" "In10.Cu"
			"In12.Cu" "In14.Cu" "In16.Cu"
		)
		(hatch none 0.5)
		(connect_pads
			(clearance 0)
		)
		(min_thickness 0.25)
		(keepout
			(tracks not_allowed)
			(vias allowed)
			(pads allowed)
			(copperpour not_allowed)
			(footprints allowed)
		)
		(placement
			(enabled no)
			(sheetname "")
		)
		(fill yes
			(thermal_gap 0.5)
			(thermal_bridge_width 0.5)
			(island_removal_mode 0)
		)
		(polygon
			(pts
				(arc
					(start 413.484568 -161.779458)
					(mid 411.724348 -161.779458)
					(end 413.484568 -161.779458)
				)
			)
		)
	)
	(zone
		(layers "In1.Cu" "In3.Cu" "In5.Cu" "In7.Cu" "In8.Cu" "In9.Cu" "In10.Cu"
			"In12.Cu" "In14.Cu" "In16.Cu"
		)
		(hatch none 0.5)
		(connect_pads
			(clearance 0)
		)
		(min_thickness 0.25)
		(keepout
			(tracks not_allowed)
			(vias allowed)
			(pads allowed)
			(copperpour not_allowed)
			(footprints allowed)
		)
		(placement
			(enabled no)
			(sheetname "")
		)
		(fill yes
			(thermal_gap 0.5)
			(thermal_bridge_width 0.5)
			(island_removal_mode 0)
		)
		(polygon
			(pts
				(arc
					(start 106.814112 -341.229442)
					(mid 105.053892 -341.229442)
					(end 106.814112 -341.229442)
				)
			)
		)
	)
	(zone
		(layers "In1.Cu" "In3.Cu" "In5.Cu" "In7.Cu" "In8.Cu" "In9.Cu" "In10.Cu"
			"In12.Cu" "In14.Cu" "In16.Cu"
		)
		(hatch none 0.5)
		(connect_pads
			(clearance 0)
		)
		(min_thickness 0.25)
		(keepout
			(tracks not_allowed)
			(vias allowed)
			(pads allowed)
			(copperpour not_allowed)
			(footprints allowed)
		)
		(placement
			(enabled no)
			(sheetname "")
		)
		(fill yes
			(thermal_gap 0.5)
			(thermal_bridge_width 0.5)
			(island_removal_mode 0)
		)
		(polygon
			(pts
				(arc
					(start 321.4497 -335.503012)
					(mid 319.6717 -335.503012)
					(end 321.4497 -335.503012)
				)
			)
		)
	)
	(zone
		(layers "In1.Cu" "In3.Cu" "In5.Cu" "In7.Cu" "In8.Cu" "In9.Cu" "In10.Cu"
			"In12.Cu" "In14.Cu" "In16.Cu"
		)
		(hatch none 0.5)
		(connect_pads
			(clearance 0)
		)
		(min_thickness 0.25)
		(keepout
			(tracks not_allowed)
			(vias allowed)
			(pads allowed)
			(copperpour not_allowed)
			(footprints allowed)
		)
		(placement
			(enabled no)
			(sheetname "")
		)
		(fill yes
			(thermal_gap 0.5)
			(thermal_bridge_width 0.5)
			(island_removal_mode 0)
		)
		(polygon
			(pts
				(arc
					(start 251.338334 -49.555146)
					(mid 249.560334 -49.555146)
					(end 251.338334 -49.555146)
				)
			)
		)
	)
	(zone
		(layers "In1.Cu" "In3.Cu" "In5.Cu" "In7.Cu" "In8.Cu" "In9.Cu" "In10.Cu"
			"In12.Cu" "In14.Cu" "In16.Cu"
		)
		(hatch none 0.5)
		(connect_pads
			(clearance 0)
		)
		(min_thickness 0.25)
		(keepout
			(tracks not_allowed)
			(vias allowed)
			(pads allowed)
			(copperpour not_allowed)
			(footprints allowed)
		)
		(placement
			(enabled no)
			(sheetname "")
		)
		(fill yes
			(thermal_gap 0.5)
			(thermal_bridge_width 0.5)
			(island_removal_mode 0)
		)
		(polygon
			(pts
				(arc
					(start 433.541678 -353.12858)
					(mid 431.781458 -353.12858)
					(end 433.541678 -353.12858)
				)
			)
		)
	)
	(zone
		(layers "In1.Cu" "In3.Cu" "In5.Cu" "In7.Cu" "In8.Cu" "In9.Cu" "In10.Cu"
			"In12.Cu" "In14.Cu" "In16.Cu"
		)
		(hatch none 0.5)
		(connect_pads
			(clearance 0)
		)
		(min_thickness 0.25)
		(keepout
			(tracks not_allowed)
			(vias allowed)
			(pads allowed)
			(copperpour not_allowed)
			(footprints allowed)
		)
		(placement
			(enabled no)
			(sheetname "")
		)
		(fill yes
			(thermal_gap 0.5)
			(thermal_bridge_width 0.5)
			(island_removal_mode 0)
		)
		(polygon
			(pts
				(arc
					(start 117.782594 -152.657556)
					(mid 116.004594 -152.657556)
					(end 117.782594 -152.657556)
				)
			)
		)
	)
	(zone
		(layers "In1.Cu" "In3.Cu" "In5.Cu" "In7.Cu" "In8.Cu" "In9.Cu" "In10.Cu"
			"In12.Cu" "In14.Cu" "In16.Cu"
		)
		(hatch none 0.5)
		(connect_pads
			(clearance 0)
		)
		(min_thickness 0.25)
		(keepout
			(tracks not_allowed)
			(vias allowed)
			(pads allowed)
			(copperpour not_allowed)
			(footprints allowed)
		)
		(placement
			(enabled no)
			(sheetname "")
		)
		(fill yes
			(thermal_gap 0.5)
			(thermal_bridge_width 0.5)
			(island_removal_mode 0)
		)
		(polygon
			(pts
				(arc
					(start 371.575584 -164.53358)
					(mid 369.797584 -164.53358)
					(end 371.575584 -164.53358)
				)
			)
		)
	)
	(zone
		(layers "In1.Cu" "In3.Cu" "In5.Cu" "In7.Cu" "In8.Cu" "In9.Cu" "In10.Cu"
			"In12.Cu" "In14.Cu" "In16.Cu"
		)
		(hatch none 0.5)
		(connect_pads
			(clearance 0)
		)
		(min_thickness 0.25)
		(keepout
			(tracks not_allowed)
			(vias allowed)
			(pads allowed)
			(copperpour not_allowed)
			(footprints allowed)
		)
		(placement
			(enabled no)
			(sheetname "")
		)
		(fill yes
			(thermal_gap 0.5)
			(thermal_bridge_width 0.5)
			(island_removal_mode 0)
		)
		(polygon
			(pts
				(arc
					(start 442.364622 -13.488162)
					(mid 440.586622 -13.488162)
					(end 442.364622 -13.488162)
				)
			)
		)
	)
	(zone
		(layers "In1.Cu" "In3.Cu" "In5.Cu" "In7.Cu" "In8.Cu" "In9.Cu" "In10.Cu"
			"In12.Cu" "In14.Cu" "In16.Cu"
		)
		(hatch none 0.5)
		(connect_pads
			(clearance 0)
		)
		(min_thickness 0.25)
		(keepout
			(tracks not_allowed)
			(vias allowed)
			(pads allowed)
			(copperpour not_allowed)
			(footprints allowed)
		)
		(placement
			(enabled no)
			(sheetname "")
		)
		(fill yes
			(thermal_gap 0.5)
			(thermal_bridge_width 0.5)
			(island_removal_mode 0)
		)
		(polygon
			(pts
				(arc
					(start 90.277442 -346.639896)
					(mid 88.499442 -346.639896)
					(end 90.277442 -346.639896)
				)
			)
		)
	)
	(zone
		(layers "In1.Cu" "In3.Cu" "In5.Cu" "In7.Cu" "In8.Cu" "In9.Cu" "In10.Cu"
			"In12.Cu" "In14.Cu" "In16.Cu"
		)
		(hatch none 0.5)
		(connect_pads
			(clearance 0)
		)
		(min_thickness 0.25)
		(keepout
			(tracks not_allowed)
			(vias allowed)
			(pads allowed)
			(copperpour not_allowed)
			(footprints allowed)
		)
		(placement
			(enabled no)
			(sheetname "")
		)
		(fill yes
			(thermal_gap 0.5)
			(thermal_bridge_width 0.5)
			(island_removal_mode 0)
		)
		(polygon
			(pts
				(arc
					(start 44.824904 -358.51084)
					(mid 43.046904 -358.51084)
					(end 44.824904 -358.51084)
				)
			)
		)
	)
	(zone
		(layers "In1.Cu" "In3.Cu" "In5.Cu" "In7.Cu" "In8.Cu" "In9.Cu" "In10.Cu"
			"In12.Cu" "In14.Cu" "In16.Cu"
		)
		(hatch none 0.5)
		(connect_pads
			(clearance 0)
		)
		(min_thickness 0.25)
		(keepout
			(tracks not_allowed)
			(vias allowed)
			(pads allowed)
			(copperpour not_allowed)
			(footprints allowed)
		)
		(placement
			(enabled no)
			(sheetname "")
		)
		(fill yes
			(thermal_gap 0.5)
			(thermal_bridge_width 0.5)
			(island_removal_mode 0)
		)
		(polygon
			(pts
				(arc
					(start 339.12556 -338.157058)
					(mid 337.34756 -338.157058)
					(end 339.12556 -338.157058)
				)
			)
		)
	)
	(zone
		(layers "In1.Cu" "In3.Cu" "In5.Cu" "In7.Cu" "In8.Cu" "In9.Cu" "In10.Cu"
			"In12.Cu" "In14.Cu" "In16.Cu"
		)
		(hatch none 0.5)
		(connect_pads
			(clearance 0)
		)
		(min_thickness 0.25)
		(keepout
			(tracks not_allowed)
			(vias allowed)
			(pads allowed)
			(copperpour not_allowed)
			(footprints allowed)
		)
		(placement
			(enabled no)
			(sheetname "")
		)
		(fill yes
			(thermal_gap 0.5)
			(thermal_bridge_width 0.5)
			(island_removal_mode 0)
		)
		(polygon
			(pts
				(arc
					(start 56.348884 -348.709488)
					(mid 54.588664 -348.709488)
					(end 56.348884 -348.709488)
				)
			)
		)
	)
	(zone
		(layers "In1.Cu" "In3.Cu" "In5.Cu" "In7.Cu" "In8.Cu" "In9.Cu" "In10.Cu"
			"In12.Cu" "In14.Cu" "In16.Cu"
		)
		(hatch none 0.5)
		(connect_pads
			(clearance 0)
		)
		(min_thickness 0.25)
		(keepout
			(tracks not_allowed)
			(vias allowed)
			(pads allowed)
			(copperpour not_allowed)
			(footprints allowed)
		)
		(placement
			(enabled no)
			(sheetname "")
		)
		(fill yes
			(thermal_gap 0.5)
			(thermal_bridge_width 0.5)
			(island_removal_mode 0)
		)
		(polygon
			(pts
				(arc
					(start 89.17813 -164.097716)
					(mid 87.40013 -164.097716)
					(end 89.17813 -164.097716)
				)
			)
		)
	)
	(zone
		(layers "In1.Cu" "In3.Cu" "In5.Cu" "In7.Cu" "In8.Cu" "In9.Cu" "In10.Cu"
			"In12.Cu" "In14.Cu" "In16.Cu"
		)
		(hatch none 0.5)
		(connect_pads
			(clearance 0)
		)
		(min_thickness 0.25)
		(keepout
			(tracks not_allowed)
			(vias allowed)
			(pads allowed)
			(copperpour not_allowed)
			(footprints allowed)
		)
		(placement
			(enabled no)
			(sheetname "")
		)
		(fill yes
			(thermal_gap 0.5)
			(thermal_bridge_width 0.5)
			(island_removal_mode 0)
		)
		(polygon
			(pts
				(arc
					(start 79.74203 -178.798474)
					(mid 77.96403 -178.798474)
					(end 79.74203 -178.798474)
				)
			)
		)
	)
	(zone
		(layers "In1.Cu" "In3.Cu" "In5.Cu" "In7.Cu" "In8.Cu" "In9.Cu" "In10.Cu"
			"In12.Cu" "In14.Cu" "In16.Cu"
		)
		(hatch none 0.5)
		(connect_pads
			(clearance 0)
		)
		(min_thickness 0.25)
		(keepout
			(tracks not_allowed)
			(vias allowed)
			(pads allowed)
			(copperpour not_allowed)
			(footprints allowed)
		)
		(placement
			(enabled no)
			(sheetname "")
		)
		(fill yes
			(thermal_gap 0.5)
			(thermal_bridge_width 0.5)
			(island_removal_mode 0)
		)
		(polygon
			(pts
				(arc
					(start 195.313046 -354.504244)
					(mid 193.535046 -354.504244)
					(end 195.313046 -354.504244)
				)
			)
		)
	)
	(zone
		(layers "In1.Cu" "In3.Cu" "In5.Cu" "In7.Cu" "In8.Cu" "In9.Cu" "In10.Cu"
			"In12.Cu" "In14.Cu" "In16.Cu"
		)
		(hatch none 0.5)
		(connect_pads
			(clearance 0)
		)
		(min_thickness 0.25)
		(keepout
			(tracks not_allowed)
			(vias allowed)
			(pads allowed)
			(copperpour not_allowed)
			(footprints allowed)
		)
		(placement
			(enabled no)
			(sheetname "")
		)
		(fill yes
			(thermal_gap 0.5)
			(thermal_bridge_width 0.5)
			(island_removal_mode 0)
		)
		(polygon
			(pts
				(arc
					(start 64.941704 -348.038928)
					(mid 63.181484 -348.038928)
					(end 64.941704 -348.038928)
				)
			)
		)
	)
	(zone
		(layers "In1.Cu" "In3.Cu" "In5.Cu" "In7.Cu" "In8.Cu" "In9.Cu" "In10.Cu"
			"In12.Cu" "In14.Cu" "In16.Cu"
		)
		(hatch none 0.5)
		(connect_pads
			(clearance 0)
		)
		(min_thickness 0.25)
		(keepout
			(tracks not_allowed)
			(vias allowed)
			(pads allowed)
			(copperpour not_allowed)
			(footprints allowed)
		)
		(placement
			(enabled no)
			(sheetname "")
		)
		(fill yes
			(thermal_gap 0.5)
			(thermal_bridge_width 0.5)
			(island_removal_mode 0)
		)
		(polygon
			(pts
				(arc
					(start 287.218882 -350.313752)
					(mid 285.440882 -350.313752)
					(end 287.218882 -350.313752)
				)
			)
		)
	)
	(zone
		(layers "In1.Cu" "In3.Cu" "In5.Cu" "In7.Cu" "In8.Cu" "In9.Cu" "In10.Cu"
			"In12.Cu" "In14.Cu" "In16.Cu"
		)
		(hatch none 0.5)
		(connect_pads
			(clearance 0)
		)
		(min_thickness 0.25)
		(keepout
			(tracks not_allowed)
			(vias allowed)
			(pads allowed)
			(copperpour not_allowed)
			(footprints allowed)
		)
		(placement
			(enabled no)
			(sheetname "")
		)
		(fill yes
			(thermal_gap 0.5)
			(thermal_bridge_width 0.5)
			(island_removal_mode 0)
		)
		(polygon
			(pts
				(arc
					(start 342.152224 -352.215196)
					(mid 340.374224 -352.215196)
					(end 342.152224 -352.215196)
				)
			)
		)
	)
	(zone
		(layers "In1.Cu" "In3.Cu" "In5.Cu" "In7.Cu" "In8.Cu" "In9.Cu" "In10.Cu"
			"In12.Cu" "In14.Cu" "In16.Cu"
		)
		(hatch none 0.5)
		(connect_pads
			(clearance 0)
		)
		(min_thickness 0.25)
		(keepout
			(tracks not_allowed)
			(vias allowed)
			(pads allowed)
			(copperpour not_allowed)
			(footprints allowed)
		)
		(placement
			(enabled no)
			(sheetname "")
		)
		(fill yes
			(thermal_gap 0.5)
			(thermal_bridge_width 0.5)
			(island_removal_mode 0)
		)
		(polygon
			(pts
				(arc
					(start 65.409064 -13.09751)
					(mid 63.631064 -13.09751)
					(end 65.409064 -13.09751)
				)
			)
		)
	)
	(zone
		(layers "In1.Cu" "In3.Cu" "In5.Cu" "In7.Cu" "In8.Cu" "In9.Cu" "In10.Cu"
			"In12.Cu" "In14.Cu" "In16.Cu"
		)
		(hatch none 0.5)
		(connect_pads
			(clearance 0)
		)
		(min_thickness 0.25)
		(keepout
			(tracks not_allowed)
			(vias allowed)
			(pads allowed)
			(copperpour not_allowed)
			(footprints allowed)
		)
		(placement
			(enabled no)
			(sheetname "")
		)
		(fill yes
			(thermal_gap 0.5)
			(thermal_bridge_width 0.5)
			(island_removal_mode 0)
		)
		(polygon
			(pts
				(arc
					(start 370.38661 -179.560474)
					(mid 368.60861 -179.560474)
					(end 370.38661 -179.560474)
				)
			)
		)
	)
	(zone
		(layers "In1.Cu" "In3.Cu" "In5.Cu" "In7.Cu" "In8.Cu" "In9.Cu" "In10.Cu"
			"In12.Cu" "In14.Cu" "In16.Cu"
		)
		(hatch none 0.5)
		(connect_pads
			(clearance 0)
		)
		(min_thickness 0.25)
		(keepout
			(tracks not_allowed)
			(vias allowed)
			(pads allowed)
			(copperpour not_allowed)
			(footprints allowed)
		)
		(placement
			(enabled no)
			(sheetname "")
		)
		(fill yes
			(thermal_gap 0.5)
			(thermal_bridge_width 0.5)
			(island_removal_mode 0)
		)
		(polygon
			(pts
				(arc
					(start 427.160436 -353.97567)
					(mid 425.382436 -353.97567)
					(end 427.160436 -353.97567)
				)
			)
		)
	)
	(zone
		(layers "In1.Cu" "In3.Cu" "In5.Cu" "In7.Cu" "In8.Cu" "In9.Cu" "In10.Cu"
			"In12.Cu" "In14.Cu" "In16.Cu"
		)
		(hatch none 0.5)
		(connect_pads
			(clearance 0)
		)
		(min_thickness 0.25)
		(keepout
			(tracks not_allowed)
			(vias allowed)
			(pads allowed)
			(copperpour not_allowed)
			(footprints allowed)
		)
		(placement
			(enabled no)
			(sheetname "")
		)
		(fill yes
			(thermal_gap 0.5)
			(thermal_bridge_width 0.5)
			(island_removal_mode 0)
		)
		(polygon
			(pts
				(arc
					(start 118.448074 -152.657556)
					(mid 116.670074 -152.657556)
					(end 118.448074 -152.657556)
				)
			)
		)
	)
	(zone
		(layers "In1.Cu" "In3.Cu" "In5.Cu" "In7.Cu" "In8.Cu" "In9.Cu" "In10.Cu"
			"In12.Cu" "In14.Cu" "In16.Cu"
		)
		(hatch none 0.5)
		(connect_pads
			(clearance 0)
		)
		(min_thickness 0.25)
		(keepout
			(tracks not_allowed)
			(vias allowed)
			(pads allowed)
			(copperpour not_allowed)
			(footprints allowed)
		)
		(placement
			(enabled no)
			(sheetname "")
		)
		(fill yes
			(thermal_gap 0.5)
			(thermal_bridge_width 0.5)
			(island_removal_mode 0)
		)
		(polygon
			(pts
				(arc
					(start 177.221134 -26.634948)
					(mid 175.443134 -26.634948)
					(end 177.221134 -26.634948)
				)
			)
		)
	)
	(zone
		(layers "In1.Cu" "In3.Cu" "In5.Cu" "In7.Cu" "In8.Cu" "In9.Cu" "In10.Cu"
			"In12.Cu" "In14.Cu" "In16.Cu"
		)
		(hatch none 0.5)
		(connect_pads
			(clearance 0)
		)
		(min_thickness 0.25)
		(keepout
			(tracks not_allowed)
			(vias allowed)
			(pads allowed)
			(copperpour not_allowed)
			(footprints allowed)
		)
		(placement
			(enabled no)
			(sheetname "")
		)
		(fill yes
			(thermal_gap 0.5)
			(thermal_bridge_width 0.5)
			(island_removal_mode 0)
		)
		(polygon
			(pts
				(arc
					(start 40.922194 -349.142558)
					(mid 39.144194 -349.142558)
					(end 40.922194 -349.142558)
				)
			)
		)
	)
	(zone
		(layers "In1.Cu" "In3.Cu" "In5.Cu" "In7.Cu" "In8.Cu" "In9.Cu" "In10.Cu"
			"In12.Cu" "In14.Cu" "In16.Cu"
		)
		(hatch none 0.5)
		(connect_pads
			(clearance 0)
		)
		(min_thickness 0.25)
		(keepout
			(tracks not_allowed)
			(vias allowed)
			(pads allowed)
			(copperpour not_allowed)
			(footprints allowed)
		)
		(placement
			(enabled no)
			(sheetname "")
		)
		(fill yes
			(thermal_gap 0.5)
			(thermal_bridge_width 0.5)
			(island_removal_mode 0)
		)
		(polygon
			(pts
				(arc
					(start 355.182424 -343.531952)
					(mid 353.404424 -343.531952)
					(end 355.182424 -343.531952)
				)
			)
		)
	)
	(zone
		(layers "In1.Cu" "In3.Cu" "In5.Cu" "In7.Cu" "In8.Cu" "In9.Cu" "In10.Cu"
			"In12.Cu" "In14.Cu" "In16.Cu"
		)
		(hatch none 0.5)
		(connect_pads
			(clearance 0)
		)
		(min_thickness 0.25)
		(keepout
			(tracks not_allowed)
			(vias allowed)
			(pads allowed)
			(copperpour not_allowed)
			(footprints allowed)
		)
		(placement
			(enabled no)
			(sheetname "")
		)
		(fill yes
			(thermal_gap 0.5)
			(thermal_bridge_width 0.5)
			(island_removal_mode 0)
		)
		(polygon
			(pts
				(arc
					(start 328.581258 -104.30129)
					(mid 326.803258 -104.30129)
					(end 328.581258 -104.30129)
				)
			)
		)
	)
	(zone
		(layers "In1.Cu" "In3.Cu" "In5.Cu" "In7.Cu" "In8.Cu" "In9.Cu" "In10.Cu"
			"In12.Cu" "In14.Cu" "In16.Cu"
		)
		(hatch none 0.5)
		(connect_pads
			(clearance 0)
		)
		(min_thickness 0.25)
		(keepout
			(tracks not_allowed)
			(vias allowed)
			(pads allowed)
			(copperpour not_allowed)
			(footprints allowed)
		)
		(placement
			(enabled no)
			(sheetname "")
		)
		(fill yes
			(thermal_gap 0.5)
			(thermal_bridge_width 0.5)
			(island_removal_mode 0)
		)
		(polygon
			(pts
				(arc
					(start 48.70323 -349.581978)
					(mid 46.92523 -349.581978)
					(end 48.70323 -349.581978)
				)
			)
		)
	)
	(zone
		(layers "In1.Cu" "In3.Cu" "In5.Cu" "In7.Cu" "In8.Cu" "In9.Cu" "In10.Cu"
			"In12.Cu" "In14.Cu" "In16.Cu"
		)
		(hatch none 0.5)
		(connect_pads
			(clearance 0)
		)
		(min_thickness 0.25)
		(keepout
			(tracks not_allowed)
			(vias allowed)
			(pads allowed)
			(copperpour not_allowed)
			(footprints allowed)
		)
		(placement
			(enabled no)
			(sheetname "")
		)
		(fill yes
			(thermal_gap 0.5)
			(thermal_bridge_width 0.5)
			(island_removal_mode 0)
		)
		(polygon
			(pts
				(arc
					(start 345.57843 -337.012788)
					(mid 343.81821 -337.012788)
					(end 345.57843 -337.012788)
				)
			)
		)
	)
	(zone
		(layers "In1.Cu" "In3.Cu" "In5.Cu" "In7.Cu" "In8.Cu" "In9.Cu" "In10.Cu"
			"In12.Cu" "In14.Cu" "In16.Cu"
		)
		(hatch none 0.5)
		(connect_pads
			(clearance 0)
		)
		(min_thickness 0.25)
		(keepout
			(tracks not_allowed)
			(vias allowed)
			(pads allowed)
			(copperpour not_allowed)
			(footprints allowed)
		)
		(placement
			(enabled no)
			(sheetname "")
		)
		(fill yes
			(thermal_gap 0.5)
			(thermal_bridge_width 0.5)
			(island_removal_mode 0)
		)
		(polygon
			(pts
				(arc
					(start 75.008994 -337.802474)
					(mid 73.230994 -337.802474)
					(end 75.008994 -337.802474)
				)
			)
		)
	)
	(zone
		(layers "In1.Cu" "In3.Cu" "In5.Cu" "In7.Cu" "In8.Cu" "In9.Cu" "In10.Cu"
			"In12.Cu" "In14.Cu" "In16.Cu"
		)
		(hatch none 0.5)
		(connect_pads
			(clearance 0)
		)
		(min_thickness 0.25)
		(keepout
			(tracks not_allowed)
			(vias allowed)
			(pads allowed)
			(copperpour not_allowed)
			(footprints allowed)
		)
		(placement
			(enabled no)
			(sheetname "")
		)
		(fill yes
			(thermal_gap 0.5)
			(thermal_bridge_width 0.5)
			(island_removal_mode 0)
		)
		(polygon
			(pts
				(arc
					(start 75.74915 -350.929448)
					(mid 73.97115 -350.929448)
					(end 75.74915 -350.929448)
				)
			)
		)
	)
	(zone
		(layers "In1.Cu" "In3.Cu" "In5.Cu" "In7.Cu" "In8.Cu" "In9.Cu" "In10.Cu"
			"In12.Cu" "In14.Cu" "In16.Cu"
		)
		(hatch none 0.5)
		(connect_pads
			(clearance 0)
		)
		(min_thickness 0.25)
		(keepout
			(tracks not_allowed)
			(vias allowed)
			(pads allowed)
			(copperpour not_allowed)
			(footprints allowed)
		)
		(placement
			(enabled no)
			(sheetname "")
		)
		(fill yes
			(thermal_gap 0.5)
			(thermal_bridge_width 0.5)
			(island_removal_mode 0)
		)
		(polygon
			(pts
				(arc
					(start 49.227994 -349.142558)
					(mid 47.449994 -349.142558)
					(end 49.227994 -349.142558)
				)
			)
		)
	)
	(zone
		(layers "In1.Cu" "In3.Cu" "In5.Cu" "In7.Cu" "In8.Cu" "In9.Cu" "In10.Cu"
			"In12.Cu" "In14.Cu" "In16.Cu"
		)
		(hatch none 0.5)
		(connect_pads
			(clearance 0)
		)
		(min_thickness 0.25)
		(keepout
			(tracks not_allowed)
			(vias allowed)
			(pads allowed)
			(copperpour not_allowed)
			(footprints allowed)
		)
		(placement
			(enabled no)
			(sheetname "")
		)
		(fill yes
			(thermal_gap 0.5)
			(thermal_bridge_width 0.5)
			(island_removal_mode 0)
		)
		(polygon
			(pts
				(arc
					(start 67.737228 -18.642584)
					(mid 65.959228 -18.642584)
					(end 67.737228 -18.642584)
				)
			)
		)
	)
	(zone
		(layers "In1.Cu" "In3.Cu" "In5.Cu" "In7.Cu" "In8.Cu" "In9.Cu" "In10.Cu"
			"In12.Cu" "In14.Cu" "In16.Cu"
		)
		(hatch none 0.5)
		(connect_pads
			(clearance 0)
		)
		(min_thickness 0.25)
		(keepout
			(tracks not_allowed)
			(vias allowed)
			(pads allowed)
			(copperpour not_allowed)
			(footprints allowed)
		)
		(placement
			(enabled no)
			(sheetname "")
		)
		(fill yes
			(thermal_gap 0.5)
			(thermal_bridge_width 0.5)
			(island_removal_mode 0)
		)
		(polygon
			(pts
				(arc
					(start 90.199464 -335.519268)
					(mid 88.439244 -335.519268)
					(end 90.199464 -335.519268)
				)
			)
		)
	)
	(zone
		(layers "In1.Cu" "In3.Cu" "In5.Cu" "In7.Cu" "In8.Cu" "In9.Cu" "In10.Cu"
			"In12.Cu" "In14.Cu" "In16.Cu"
		)
		(hatch none 0.5)
		(connect_pads
			(clearance 0)
		)
		(min_thickness 0.25)
		(keepout
			(tracks not_allowed)
			(vias allowed)
			(pads allowed)
			(copperpour not_allowed)
			(footprints allowed)
		)
		(placement
			(enabled no)
			(sheetname "")
		)
		(fill yes
			(thermal_gap 0.5)
			(thermal_bridge_width 0.5)
			(island_removal_mode 0)
		)
		(polygon
			(pts
				(arc
					(start 303.881282 -349.577152)
					(mid 302.103282 -349.577152)
					(end 303.881282 -349.577152)
				)
			)
		)
	)
	(zone
		(layers "In1.Cu" "In3.Cu" "In5.Cu" "In7.Cu" "In8.Cu" "In9.Cu" "In10.Cu"
			"In12.Cu" "In14.Cu" "In16.Cu"
		)
		(hatch none 0.5)
		(connect_pads
			(clearance 0)
		)
		(min_thickness 0.25)
		(keepout
			(tracks not_allowed)
			(vias allowed)
			(pads allowed)
			(copperpour not_allowed)
			(footprints allowed)
		)
		(placement
			(enabled no)
			(sheetname "")
		)
		(fill yes
			(thermal_gap 0.5)
			(thermal_bridge_width 0.5)
			(island_removal_mode 0)
		)
		(polygon
			(pts
				(arc
					(start 389.598408 -180.755544)
					(mid 387.838188 -180.755544)
					(end 389.598408 -180.755544)
				)
			)
		)
	)
	(zone
		(layers "In1.Cu" "In3.Cu" "In5.Cu" "In7.Cu" "In8.Cu" "In9.Cu" "In10.Cu"
			"In12.Cu" "In14.Cu" "In16.Cu"
		)
		(hatch none 0.5)
		(connect_pads
			(clearance 0)
		)
		(min_thickness 0.25)
		(keepout
			(tracks not_allowed)
			(vias allowed)
			(pads allowed)
			(copperpour not_allowed)
			(footprints allowed)
		)
		(placement
			(enabled no)
			(sheetname "")
		)
		(fill yes
			(thermal_gap 0.5)
			(thermal_bridge_width 0.5)
			(island_removal_mode 0)
		)
		(polygon
			(pts
				(arc
					(start 322.41236 -338.178648)
					(mid 320.63436 -338.178648)
					(end 322.41236 -338.178648)
				)
			)
		)
	)
	(zone
		(layers "In1.Cu" "In3.Cu" "In5.Cu" "In7.Cu" "In8.Cu" "In9.Cu" "In10.Cu"
			"In12.Cu" "In14.Cu" "In16.Cu"
		)
		(hatch none 0.5)
		(connect_pads
			(clearance 0)
		)
		(min_thickness 0.25)
		(keepout
			(tracks not_allowed)
			(vias allowed)
			(pads allowed)
			(copperpour not_allowed)
			(footprints allowed)
		)
		(placement
			(enabled no)
			(sheetname "")
		)
		(fill yes
			(thermal_gap 0.5)
			(thermal_bridge_width 0.5)
			(island_removal_mode 0)
		)
		(polygon
			(pts
				(arc
					(start 288.53511 -356.584758)
					(mid 286.75711 -356.584758)
					(end 288.53511 -356.584758)
				)
			)
		)
	)
	(zone
		(layers "In1.Cu" "In3.Cu" "In5.Cu" "In7.Cu" "In8.Cu" "In9.Cu" "In10.Cu"
			"In12.Cu" "In14.Cu" "In16.Cu"
		)
		(hatch none 0.5)
		(connect_pads
			(clearance 0)
		)
		(min_thickness 0.25)
		(keepout
			(tracks not_allowed)
			(vias allowed)
			(pads allowed)
			(copperpour not_allowed)
			(footprints allowed)
		)
		(placement
			(enabled no)
			(sheetname "")
		)
		(fill yes
			(thermal_gap 0.5)
			(thermal_bridge_width 0.5)
			(island_removal_mode 0)
		)
		(polygon
			(pts
				(arc
					(start 98.96983 -338.626704)
					(mid 97.19183 -338.626704)
					(end 98.96983 -338.626704)
				)
			)
		)
	)
	(zone
		(layers "In1.Cu" "In3.Cu" "In5.Cu" "In7.Cu" "In8.Cu" "In9.Cu" "In10.Cu"
			"In12.Cu" "In14.Cu" "In16.Cu"
		)
		(hatch none 0.5)
		(connect_pads
			(clearance 0)
		)
		(min_thickness 0.25)
		(keepout
			(tracks not_allowed)
			(vias allowed)
			(pads allowed)
			(copperpour not_allowed)
			(footprints allowed)
		)
		(placement
			(enabled no)
			(sheetname "")
		)
		(fill yes
			(thermal_gap 0.5)
			(thermal_bridge_width 0.5)
			(island_removal_mode 0)
		)
		(polygon
			(pts
				(arc
					(start 112.86363 -169.857674)
					(mid 111.08563 -169.857674)
					(end 112.86363 -169.857674)
				)
			)
		)
	)
	(zone
		(layers "In1.Cu" "In3.Cu" "In5.Cu" "In7.Cu" "In8.Cu" "In9.Cu" "In10.Cu"
			"In12.Cu" "In14.Cu" "In16.Cu"
		)
		(hatch none 0.5)
		(connect_pads
			(clearance 0)
		)
		(min_thickness 0.25)
		(keepout
			(tracks not_allowed)
			(vias allowed)
			(pads allowed)
			(copperpour not_allowed)
			(footprints allowed)
		)
		(placement
			(enabled no)
			(sheetname "")
		)
		(fill yes
			(thermal_gap 0.5)
			(thermal_bridge_width 0.5)
			(island_removal_mode 0)
		)
		(polygon
			(pts
				(arc
					(start 356.265988 -343.473532)
					(mid 354.487988 -343.473532)
					(end 356.265988 -343.473532)
				)
			)
		)
	)
	(zone
		(layers "In1.Cu" "In3.Cu" "In5.Cu" "In7.Cu" "In8.Cu" "In9.Cu" "In10.Cu"
			"In12.Cu" "In14.Cu" "In16.Cu"
		)
		(hatch none 0.5)
		(connect_pads
			(clearance 0)
		)
		(min_thickness 0.25)
		(keepout
			(tracks not_allowed)
			(vias allowed)
			(pads allowed)
			(copperpour not_allowed)
			(footprints allowed)
		)
		(placement
			(enabled no)
			(sheetname "")
		)
		(fill yes
			(thermal_gap 0.5)
			(thermal_bridge_width 0.5)
			(island_removal_mode 0)
		)
		(polygon
			(pts
				(arc
					(start 75.700382 -351.637854)
					(mid 73.922382 -351.637854)
					(end 75.700382 -351.637854)
				)
			)
		)
	)
	(zone
		(layers "In1.Cu" "In3.Cu" "In5.Cu" "In7.Cu" "In8.Cu" "In9.Cu" "In10.Cu"
			"In12.Cu" "In14.Cu" "In16.Cu"
		)
		(hatch none 0.5)
		(connect_pads
			(clearance 0)
		)
		(min_thickness 0.25)
		(keepout
			(tracks not_allowed)
			(vias allowed)
			(pads allowed)
			(copperpour not_allowed)
			(footprints allowed)
		)
		(placement
			(enabled no)
			(sheetname "")
		)
		(fill yes
			(thermal_gap 0.5)
			(thermal_bridge_width 0.5)
			(island_removal_mode 0)
		)
		(polygon
			(pts
				(arc
					(start 353.770438 -167.074596)
					(mid 351.992438 -167.074596)
					(end 353.770438 -167.074596)
				)
			)
		)
	)
	(zone
		(layers "In1.Cu" "In3.Cu" "In5.Cu" "In7.Cu" "In8.Cu" "In9.Cu" "In10.Cu"
			"In12.Cu" "In14.Cu" "In16.Cu"
		)
		(hatch none 0.5)
		(connect_pads
			(clearance 0)
		)
		(min_thickness 0.25)
		(keepout
			(tracks not_allowed)
			(vias allowed)
			(pads allowed)
			(copperpour not_allowed)
			(footprints allowed)
		)
		(placement
			(enabled no)
			(sheetname "")
		)
		(fill yes
			(thermal_gap 0.5)
			(thermal_bridge_width 0.5)
			(island_removal_mode 0)
		)
		(polygon
			(pts
				(arc
					(start 129.60223 -154.465274)
					(mid 127.82423 -154.465274)
					(end 129.60223 -154.465274)
				)
			)
		)
	)
	(zone
		(layers "In1.Cu" "In3.Cu" "In5.Cu" "In7.Cu" "In8.Cu" "In9.Cu" "In10.Cu"
			"In12.Cu" "In14.Cu" "In16.Cu"
		)
		(hatch none 0.5)
		(connect_pads
			(clearance 0)
		)
		(min_thickness 0.25)
		(keepout
			(tracks not_allowed)
			(vias allowed)
			(pads allowed)
			(copperpour not_allowed)
			(footprints allowed)
		)
		(placement
			(enabled no)
			(sheetname "")
		)
		(fill yes
			(thermal_gap 0.5)
			(thermal_bridge_width 0.5)
			(island_removal_mode 0)
		)
		(polygon
			(pts
				(arc
					(start 339.65896 -338.512658)
					(mid 337.88096 -338.512658)
					(end 339.65896 -338.512658)
				)
			)
		)
	)
	(zone
		(layers "In1.Cu" "In3.Cu" "In5.Cu" "In7.Cu" "In8.Cu" "In9.Cu" "In10.Cu"
			"In12.Cu" "In14.Cu" "In16.Cu"
		)
		(hatch none 0.5)
		(connect_pads
			(clearance 0)
		)
		(min_thickness 0.25)
		(keepout
			(tracks not_allowed)
			(vias allowed)
			(pads allowed)
			(copperpour not_allowed)
			(footprints allowed)
		)
		(placement
			(enabled no)
			(sheetname "")
		)
		(fill yes
			(thermal_gap 0.5)
			(thermal_bridge_width 0.5)
			(island_removal_mode 0)
		)
		(polygon
			(pts
				(arc
					(start 39.939214 -347.974158)
					(mid 38.161214 -347.974158)
					(end 39.939214 -347.974158)
				)
			)
		)
	)
	(zone
		(layers "In1.Cu" "In3.Cu" "In5.Cu" "In7.Cu" "In8.Cu" "In9.Cu" "In10.Cu"
			"In12.Cu" "In14.Cu" "In16.Cu"
		)
		(hatch none 0.5)
		(connect_pads
			(clearance 0)
		)
		(min_thickness 0.25)
		(keepout
			(tracks not_allowed)
			(vias allowed)
			(pads allowed)
			(copperpour not_allowed)
			(footprints allowed)
		)
		(placement
			(enabled no)
			(sheetname "")
		)
		(fill yes
			(thermal_gap 0.5)
			(thermal_bridge_width 0.5)
			(island_removal_mode 0)
		)
		(polygon
			(pts
				(arc
					(start 118.448074 -152.022556)
					(mid 116.670074 -152.022556)
					(end 118.448074 -152.022556)
				)
			)
		)
	)
	(zone
		(layers "In1.Cu" "In3.Cu" "In5.Cu" "In7.Cu" "In8.Cu" "In9.Cu" "In10.Cu"
			"In12.Cu" "In14.Cu" "In16.Cu"
		)
		(hatch none 0.5)
		(connect_pads
			(clearance 0)
		)
		(min_thickness 0.25)
		(keepout
			(tracks not_allowed)
			(vias allowed)
			(pads allowed)
			(copperpour not_allowed)
			(footprints allowed)
		)
		(placement
			(enabled no)
			(sheetname "")
		)
		(fill yes
			(thermal_gap 0.5)
			(thermal_bridge_width 0.5)
			(island_removal_mode 0)
		)
		(polygon
			(pts
				(arc
					(start 252.405134 -52.501546)
					(mid 250.627134 -52.501546)
					(end 252.405134 -52.501546)
				)
			)
		)
	)
	(zone
		(layers "In1.Cu" "In3.Cu" "In5.Cu" "In7.Cu" "In8.Cu" "In9.Cu" "In10.Cu"
			"In12.Cu" "In14.Cu" "In16.Cu"
		)
		(hatch none 0.5)
		(connect_pads
			(clearance 0)
		)
		(min_thickness 0.25)
		(keepout
			(tracks not_allowed)
			(vias allowed)
			(pads allowed)
			(copperpour not_allowed)
			(footprints allowed)
		)
		(placement
			(enabled no)
			(sheetname "")
		)
		(fill yes
			(thermal_gap 0.5)
			(thermal_bridge_width 0.5)
			(island_removal_mode 0)
		)
		(polygon
			(pts
				(arc
					(start 91.722194 -337.044284)
					(mid 89.944194 -337.044284)
					(end 91.722194 -337.044284)
				)
			)
		)
	)
	(zone
		(layers "In1.Cu" "In3.Cu" "In5.Cu" "In7.Cu" "In8.Cu" "In9.Cu" "In10.Cu"
			"In12.Cu" "In14.Cu" "In16.Cu"
		)
		(hatch none 0.5)
		(connect_pads
			(clearance 0)
		)
		(min_thickness 0.25)
		(keepout
			(tracks not_allowed)
			(vias allowed)
			(pads allowed)
			(copperpour not_allowed)
			(footprints allowed)
		)
		(placement
			(enabled no)
			(sheetname "")
		)
		(fill yes
			(thermal_gap 0.5)
			(thermal_bridge_width 0.5)
			(island_removal_mode 0)
		)
		(polygon
			(pts
				(arc
					(start 434.158898 -353.12858)
					(mid 432.398678 -353.12858)
					(end 434.158898 -353.12858)
				)
			)
		)
	)
	(zone
		(layers "In1.Cu" "In3.Cu" "In5.Cu" "In7.Cu" "In8.Cu" "In9.Cu" "In10.Cu"
			"In12.Cu" "In14.Cu" "In16.Cu"
		)
		(hatch none 0.5)
		(connect_pads
			(clearance 0)
		)
		(min_thickness 0.25)
		(keepout
			(tracks not_allowed)
			(vias allowed)
			(pads allowed)
			(copperpour not_allowed)
			(footprints allowed)
		)
		(placement
			(enabled no)
			(sheetname "")
		)
		(fill yes
			(thermal_gap 0.5)
			(thermal_bridge_width 0.5)
			(island_removal_mode 0)
		)
		(polygon
			(pts
				(arc
					(start 312.212482 -350.313752)
					(mid 310.434482 -350.313752)
					(end 312.212482 -350.313752)
				)
			)
		)
	)
	(zone
		(layers "In1.Cu" "In3.Cu" "In5.Cu" "In7.Cu" "In8.Cu" "In9.Cu" "In10.Cu"
			"In12.Cu" "In14.Cu" "In16.Cu"
		)
		(hatch none 0.5)
		(connect_pads
			(clearance 0)
		)
		(min_thickness 0.25)
		(keepout
			(tracks not_allowed)
			(vias allowed)
			(pads allowed)
			(copperpour not_allowed)
			(footprints allowed)
		)
		(placement
			(enabled no)
			(sheetname "")
		)
		(fill yes
			(thermal_gap 0.5)
			(thermal_bridge_width 0.5)
			(island_removal_mode 0)
		)
		(polygon
			(pts
				(arc
					(start 441.834524 -11.261852)
					(mid 440.056524 -11.261852)
					(end 441.834524 -11.261852)
				)
			)
		)
	)
	(zone
		(layers "In1.Cu" "In3.Cu" "In5.Cu" "In7.Cu" "In8.Cu" "In9.Cu" "In10.Cu"
			"In12.Cu" "In14.Cu" "In16.Cu"
		)
		(hatch none 0.5)
		(connect_pads
			(clearance 0)
		)
		(min_thickness 0.25)
		(keepout
			(tracks not_allowed)
			(vias allowed)
			(pads allowed)
			(copperpour not_allowed)
			(footprints allowed)
		)
		(placement
			(enabled no)
			(sheetname "")
		)
		(fill yes
			(thermal_gap 0.5)
			(thermal_bridge_width 0.5)
			(island_removal_mode 0)
		)
		(polygon
			(pts
				(arc
					(start 241.102134 -44.040806)
					(mid 239.324134 -44.040806)
					(end 241.102134 -44.040806)
				)
			)
		)
	)
	(zone
		(layers "In1.Cu" "In3.Cu" "In5.Cu" "In7.Cu" "In8.Cu" "In9.Cu" "In10.Cu"
			"In12.Cu" "In14.Cu" "In16.Cu"
		)
		(hatch none 0.5)
		(connect_pads
			(clearance 0)
		)
		(min_thickness 0.25)
		(keepout
			(tracks not_allowed)
			(vias allowed)
			(pads allowed)
			(copperpour not_allowed)
			(footprints allowed)
		)
		(placement
			(enabled no)
			(sheetname "")
		)
		(fill yes
			(thermal_gap 0.5)
			(thermal_bridge_width 0.5)
			(island_removal_mode 0)
		)
		(polygon
			(pts
				(arc
					(start 287.88995 -355.279198)
					(mid 286.11195 -355.279198)
					(end 287.88995 -355.279198)
				)
			)
		)
	)
	(zone
		(layers "In1.Cu" "In3.Cu" "In5.Cu" "In7.Cu" "In8.Cu" "In9.Cu" "In10.Cu"
			"In12.Cu" "In14.Cu" "In16.Cu"
		)
		(hatch none 0.5)
		(connect_pads
			(clearance 0)
		)
		(min_thickness 0.25)
		(keepout
			(tracks not_allowed)
			(vias allowed)
			(pads allowed)
			(copperpour not_allowed)
			(footprints allowed)
		)
		(placement
			(enabled no)
			(sheetname "")
		)
		(fill yes
			(thermal_gap 0.5)
			(thermal_bridge_width 0.5)
			(island_removal_mode 0)
		)
		(polygon
			(pts
				(arc
					(start 121.14403 -163.126674)
					(mid 119.36603 -163.126674)
					(end 121.14403 -163.126674)
				)
			)
		)
	)
	(zone
		(layers "In1.Cu" "In3.Cu" "In5.Cu" "In7.Cu" "In8.Cu" "In9.Cu" "In10.Cu"
			"In12.Cu" "In14.Cu" "In16.Cu"
		)
		(hatch none 0.5)
		(connect_pads
			(clearance 0)
		)
		(min_thickness 0.25)
		(keepout
			(tracks not_allowed)
			(vias allowed)
			(pads allowed)
			(copperpour not_allowed)
			(footprints allowed)
		)
		(placement
			(enabled no)
			(sheetname "")
		)
		(fill yes
			(thermal_gap 0.5)
			(thermal_bridge_width 0.5)
			(island_removal_mode 0)
		)
		(polygon
			(pts
				(arc
					(start 304.964846 -349.518732)
					(mid 303.186846 -349.518732)
					(end 304.964846 -349.518732)
				)
			)
		)
	)
	(zone
		(layers "In1.Cu" "In3.Cu" "In5.Cu" "In7.Cu" "In8.Cu" "In9.Cu" "In10.Cu"
			"In12.Cu" "In14.Cu" "In16.Cu"
		)
		(hatch none 0.5)
		(connect_pads
			(clearance 0)
		)
		(min_thickness 0.25)
		(keepout
			(tracks not_allowed)
			(vias allowed)
			(pads allowed)
			(copperpour not_allowed)
			(footprints allowed)
		)
		(placement
			(enabled no)
			(sheetname "")
		)
		(fill yes
			(thermal_gap 0.5)
			(thermal_bridge_width 0.5)
			(island_removal_mode 0)
		)
		(polygon
			(pts
				(arc
					(start 277.610316 -348.704662)
					(mid 275.850096 -348.704662)
					(end 277.610316 -348.704662)
				)
			)
		)
	)
	(zone
		(layers "In1.Cu" "In3.Cu" "In5.Cu" "In7.Cu" "In8.Cu" "In9.Cu" "In10.Cu"
			"In12.Cu" "In14.Cu" "In16.Cu"
		)
		(hatch none 0.5)
		(connect_pads
			(clearance 0)
		)
		(min_thickness 0.25)
		(keepout
			(tracks not_allowed)
			(vias allowed)
			(pads allowed)
			(copperpour not_allowed)
			(footprints allowed)
		)
		(placement
			(enabled no)
			(sheetname "")
		)
		(fill yes
			(thermal_gap 0.5)
			(thermal_bridge_width 0.5)
			(island_removal_mode 0)
		)
		(polygon
			(pts
				(arc
					(start 58.143394 -349.523558)
					(mid 56.365394 -349.523558)
					(end 58.143394 -349.523558)
				)
			)
		)
	)
	(zone
		(layers "In1.Cu" "In3.Cu" "In5.Cu" "In7.Cu" "In8.Cu" "In9.Cu" "In10.Cu"
			"In12.Cu" "In14.Cu" "In16.Cu"
		)
		(hatch none 0.5)
		(connect_pads
			(clearance 0)
		)
		(min_thickness 0.25)
		(keepout
			(tracks not_allowed)
			(vias allowed)
			(pads allowed)
			(copperpour not_allowed)
			(footprints allowed)
		)
		(placement
			(enabled no)
			(sheetname "")
		)
		(fill yes
			(thermal_gap 0.5)
			(thermal_bridge_width 0.5)
			(island_removal_mode 0)
		)
		(polygon
			(pts
				(arc
					(start 47.992284 -348.709488)
					(mid 46.232064 -348.709488)
					(end 47.992284 -348.709488)
				)
			)
		)
	)
	(zone
		(layers "In1.Cu" "In3.Cu" "In5.Cu" "In7.Cu" "In8.Cu" "In9.Cu" "In10.Cu"
			"In12.Cu" "In14.Cu" "In16.Cu"
		)
		(hatch none 0.5)
		(connect_pads
			(clearance 0)
		)
		(min_thickness 0.25)
		(keepout
			(tracks not_allowed)
			(vias allowed)
			(pads allowed)
			(copperpour not_allowed)
			(footprints allowed)
		)
		(placement
			(enabled no)
			(sheetname "")
		)
		(fill yes
			(thermal_gap 0.5)
			(thermal_bridge_width 0.5)
			(island_removal_mode 0)
		)
		(polygon
			(pts
				(arc
					(start 202.634342 -345.821)
					(mid 200.856342 -345.821)
					(end 202.634342 -345.821)
				)
			)
		)
	)
	(zone
		(layers "In1.Cu" "In3.Cu" "In5.Cu" "In7.Cu" "In8.Cu" "In9.Cu" "In10.Cu"
			"In12.Cu" "In14.Cu" "In16.Cu"
		)
		(hatch none 0.5)
		(connect_pads
			(clearance 0)
		)
		(min_thickness 0.25)
		(keepout
			(tracks not_allowed)
			(vias allowed)
			(pads allowed)
			(copperpour not_allowed)
			(footprints allowed)
		)
		(placement
			(enabled no)
			(sheetname "")
		)
		(fill yes
			(thermal_gap 0.5)
			(thermal_bridge_width 0.5)
			(island_removal_mode 0)
		)
		(polygon
			(pts
				(arc
					(start 73.92543 -338.597494)
					(mid 72.14743 -338.597494)
					(end 73.92543 -338.597494)
				)
			)
		)
	)
	(zone
		(layers "In1.Cu" "In3.Cu" "In5.Cu" "In7.Cu" "In8.Cu" "In9.Cu" "In10.Cu"
			"In12.Cu" "In14.Cu" "In16.Cu"
		)
		(hatch none 0.5)
		(connect_pads
			(clearance 0)
		)
		(min_thickness 0.25)
		(keepout
			(tracks not_allowed)
			(vias allowed)
			(pads allowed)
			(copperpour not_allowed)
			(footprints allowed)
		)
		(placement
			(enabled no)
			(sheetname "")
		)
		(fill yes
			(thermal_gap 0.5)
			(thermal_bridge_width 0.5)
			(island_removal_mode 0)
		)
		(polygon
			(pts
				(arc
					(start 79.99603 -179.560474)
					(mid 78.21803 -179.560474)
					(end 79.99603 -179.560474)
				)
			)
		)
	)
	(zone
		(layers "In1.Cu" "In3.Cu" "In5.Cu" "In7.Cu" "In8.Cu" "In9.Cu" "In10.Cu"
			"In12.Cu" "In14.Cu" "In16.Cu"
		)
		(hatch none 0.5)
		(connect_pads
			(clearance 0)
		)
		(min_thickness 0.25)
		(keepout
			(tracks not_allowed)
			(vias allowed)
			(pads allowed)
			(copperpour not_allowed)
			(footprints allowed)
		)
		(placement
			(enabled no)
			(sheetname "")
		)
		(fill yes
			(thermal_gap 0.5)
			(thermal_bridge_width 0.5)
			(island_removal_mode 0)
		)
		(polygon
			(pts
				(arc
					(start 425.21505 -353.10318)
					(mid 423.45483 -353.10318)
					(end 425.21505 -353.10318)
				)
			)
		)
	)
	(zone
		(layers "In1.Cu" "In3.Cu" "In5.Cu" "In7.Cu" "In8.Cu" "In9.Cu" "In10.Cu"
			"In12.Cu" "In14.Cu" "In16.Cu"
		)
		(hatch none 0.5)
		(connect_pads
			(clearance 0)
		)
		(min_thickness 0.25)
		(keepout
			(tracks not_allowed)
			(vias allowed)
			(pads allowed)
			(copperpour not_allowed)
			(footprints allowed)
		)
		(placement
			(enabled no)
			(sheetname "")
		)
		(fill yes
			(thermal_gap 0.5)
			(thermal_bridge_width 0.5)
			(island_removal_mode 0)
		)
		(polygon
			(pts
				(arc
					(start 388.817358 -155.724352)
					(mid 387.039358 -155.724352)
					(end 388.817358 -155.724352)
				)
			)
		)
	)
	(zone
		(layers "In1.Cu" "In3.Cu" "In5.Cu" "In7.Cu" "In8.Cu" "In9.Cu" "In10.Cu"
			"In12.Cu" "In14.Cu" "In16.Cu"
		)
		(hatch none 0.5)
		(connect_pads
			(clearance 0)
		)
		(min_thickness 0.25)
		(keepout
			(tracks not_allowed)
			(vias allowed)
			(pads allowed)
			(copperpour not_allowed)
			(footprints allowed)
		)
		(placement
			(enabled no)
			(sheetname "")
		)
		(fill yes
			(thermal_gap 0.5)
			(thermal_bridge_width 0.5)
			(island_removal_mode 0)
		)
		(polygon
			(pts
				(arc
					(start 64.60236 -166.94023)
					(mid 62.84214 -166.94023)
					(end 64.60236 -166.94023)
				)
			)
		)
	)
	(zone
		(layers "In1.Cu" "In3.Cu" "In5.Cu" "In7.Cu" "In8.Cu" "In9.Cu" "In10.Cu"
			"In12.Cu" "In14.Cu" "In16.Cu"
		)
		(hatch none 0.5)
		(connect_pads
			(clearance 0)
		)
		(min_thickness 0.25)
		(keepout
			(tracks not_allowed)
			(vias allowed)
			(pads allowed)
			(copperpour not_allowed)
			(footprints allowed)
		)
		(placement
			(enabled no)
			(sheetname "")
		)
		(fill yes
			(thermal_gap 0.5)
			(thermal_bridge_width 0.5)
			(island_removal_mode 0)
		)
		(polygon
			(pts
				(arc
					(start 30.171644 -348.709488)
					(mid 28.411424 -348.709488)
					(end 30.171644 -348.709488)
				)
			)
		)
	)
	(zone
		(layers "In1.Cu" "In3.Cu" "In5.Cu" "In7.Cu" "In8.Cu" "In9.Cu" "In10.Cu"
			"In12.Cu" "In14.Cu" "In16.Cu"
		)
		(hatch none 0.5)
		(connect_pads
			(clearance 0)
		)
		(min_thickness 0.25)
		(keepout
			(tracks not_allowed)
			(vias allowed)
			(pads allowed)
			(copperpour not_allowed)
			(footprints allowed)
		)
		(placement
			(enabled no)
			(sheetname "")
		)
		(fill yes
			(thermal_gap 0.5)
			(thermal_bridge_width 0.5)
			(island_removal_mode 0)
		)
		(polygon
			(pts
				(arc
					(start 387.670802 -179.883054)
					(mid 385.892802 -179.883054)
					(end 387.670802 -179.883054)
				)
			)
		)
	)
	(zone
		(layers "In1.Cu" "In3.Cu" "In5.Cu" "In7.Cu" "In8.Cu" "In9.Cu" "In10.Cu"
			"In12.Cu" "In14.Cu" "In16.Cu"
		)
		(hatch none 0.5)
		(connect_pads
			(clearance 0)
		)
		(min_thickness 0.25)
		(keepout
			(tracks not_allowed)
			(vias allowed)
			(pads allowed)
			(copperpour not_allowed)
			(footprints allowed)
		)
		(placement
			(enabled no)
			(sheetname "")
		)
		(fill yes
			(thermal_gap 0.5)
			(thermal_bridge_width 0.5)
			(island_removal_mode 0)
		)
		(polygon
			(pts
				(arc
					(start 98.538284 -336.319368)
					(mid 96.778064 -336.319368)
					(end 98.538284 -336.319368)
				)
			)
		)
	)
	(zone
		(layers "In1.Cu" "In3.Cu" "In5.Cu" "In7.Cu" "In8.Cu" "In9.Cu" "In10.Cu"
			"In12.Cu" "In14.Cu" "In16.Cu"
		)
		(hatch none 0.5)
		(connect_pads
			(clearance 0)
		)
		(min_thickness 0.25)
		(keepout
			(tracks not_allowed)
			(vias allowed)
			(pads allowed)
			(copperpour not_allowed)
			(footprints allowed)
		)
		(placement
			(enabled no)
			(sheetname "")
		)
		(fill yes
			(thermal_gap 0.5)
			(thermal_bridge_width 0.5)
			(island_removal_mode 0)
		)
		(polygon
			(pts
				(arc
					(start 44.882308 -359.219246)
					(mid 43.104308 -359.219246)
					(end 44.882308 -359.219246)
				)
			)
		)
	)
	(zone
		(layers "In1.Cu" "In3.Cu" "In5.Cu" "In7.Cu" "In8.Cu" "In9.Cu" "In10.Cu"
			"In12.Cu" "In14.Cu" "In16.Cu"
		)
		(hatch none 0.5)
		(connect_pads
			(clearance 0)
		)
		(min_thickness 0.25)
		(keepout
			(tracks not_allowed)
			(vias allowed)
			(pads allowed)
			(copperpour not_allowed)
			(footprints allowed)
		)
		(placement
			(enabled no)
			(sheetname "")
		)
		(fill yes
			(thermal_gap 0.5)
			(thermal_bridge_width 0.5)
			(island_removal_mode 0)
		)
		(polygon
			(pts
				(arc
					(start 63.909194 -165.33114)
					(mid 62.131194 -165.33114)
					(end 63.909194 -165.33114)
				)
			)
		)
	)
	(zone
		(layers "In1.Cu" "In3.Cu" "In5.Cu" "In7.Cu" "In8.Cu" "In9.Cu" "In10.Cu"
			"In12.Cu" "In14.Cu" "In16.Cu"
		)
		(hatch none 0.5)
		(connect_pads
			(clearance 0)
		)
		(min_thickness 0.25)
		(keepout
			(tracks not_allowed)
			(vias allowed)
			(pads allowed)
			(copperpour not_allowed)
			(footprints allowed)
		)
		(placement
			(enabled no)
			(sheetname "")
		)
		(fill yes
			(thermal_gap 0.5)
			(thermal_bridge_width 0.5)
			(island_removal_mode 0)
		)
		(polygon
			(pts
				(arc
					(start 436.037228 -354.32365)
					(mid 434.259228 -354.32365)
					(end 436.037228 -354.32365)
				)
			)
		)
	)
	(zone
		(layers "In1.Cu" "In3.Cu" "In5.Cu" "In7.Cu" "In8.Cu" "In9.Cu" "In10.Cu"
			"In12.Cu" "In14.Cu" "In16.Cu"
		)
		(hatch none 0.5)
		(connect_pads
			(clearance 0)
		)
		(min_thickness 0.25)
		(keepout
			(tracks not_allowed)
			(vias allowed)
			(pads allowed)
			(copperpour not_allowed)
			(footprints allowed)
		)
		(placement
			(enabled no)
			(sheetname "")
		)
		(fill yes
			(thermal_gap 0.5)
			(thermal_bridge_width 0.5)
			(island_removal_mode 0)
		)
		(polygon
			(pts
				(arc
					(start 347.43136 -337.445858)
					(mid 345.65336 -337.445858)
					(end 347.43136 -337.445858)
				)
			)
		)
	)
	(zone
		(layers "In1.Cu" "In3.Cu" "In5.Cu" "In7.Cu" "In8.Cu" "In9.Cu" "In10.Cu"
			"In12.Cu" "In14.Cu" "In16.Cu"
		)
		(hatch none 0.5)
		(connect_pads
			(clearance 0)
		)
		(min_thickness 0.25)
		(keepout
			(tracks not_allowed)
			(vias allowed)
			(pads allowed)
			(copperpour not_allowed)
			(footprints allowed)
		)
		(placement
			(enabled no)
			(sheetname "")
		)
		(fill yes
			(thermal_gap 0.5)
			(thermal_bridge_width 0.5)
			(island_removal_mode 0)
		)
		(polygon
			(pts
				(arc
					(start 379.924056 -182.230776)
					(mid 378.146056 -182.230776)
					(end 379.924056 -182.230776)
				)
			)
		)
	)
	(zone
		(layers "In1.Cu" "In3.Cu" "In5.Cu" "In7.Cu" "In8.Cu" "In9.Cu" "In10.Cu"
			"In12.Cu" "In14.Cu" "In16.Cu"
		)
		(hatch none 0.5)
		(connect_pads
			(clearance 0)
		)
		(min_thickness 0.25)
		(keepout
			(tracks not_allowed)
			(vias allowed)
			(pads allowed)
			(copperpour not_allowed)
			(footprints allowed)
		)
		(placement
			(enabled no)
			(sheetname "")
		)
		(fill yes
			(thermal_gap 0.5)
			(thermal_bridge_width 0.5)
			(island_removal_mode 0)
		)
		(polygon
			(pts
				(arc
					(start 107.02798 -176.183544)
					(mid 105.26776 -176.183544)
					(end 107.02798 -176.183544)
				)
			)
		)
	)
	(zone
		(layers "In1.Cu" "In3.Cu" "In5.Cu" "In7.Cu" "In8.Cu" "In9.Cu" "In10.Cu"
			"In12.Cu" "In14.Cu" "In16.Cu"
		)
		(hatch none 0.5)
		(connect_pads
			(clearance 0)
		)
		(min_thickness 0.25)
		(keepout
			(tracks not_allowed)
			(vias allowed)
			(pads allowed)
			(copperpour not_allowed)
			(footprints allowed)
		)
		(placement
			(enabled no)
			(sheetname "")
		)
		(fill yes
			(thermal_gap 0.5)
			(thermal_bridge_width 0.5)
			(island_removal_mode 0)
		)
		(polygon
			(pts
				(arc
					(start 130.13563 -153.347674)
					(mid 128.35763 -153.347674)
					(end 130.13563 -153.347674)
				)
			)
		)
	)
	(zone
		(layers "In1.Cu" "In3.Cu" "In5.Cu" "In7.Cu" "In8.Cu" "In9.Cu" "In10.Cu"
			"In12.Cu" "In14.Cu" "In16.Cu"
		)
		(hatch none 0.5)
		(connect_pads
			(clearance 0)
		)
		(min_thickness 0.25)
		(keepout
			(tracks not_allowed)
			(vias allowed)
			(pads allowed)
			(copperpour not_allowed)
			(footprints allowed)
		)
		(placement
			(enabled no)
			(sheetname "")
		)
		(fill yes
			(thermal_gap 0.5)
			(thermal_bridge_width 0.5)
			(island_removal_mode 0)
		)
		(polygon
			(pts
				(arc
					(start 250.794266 -51.349148)
					(mid 249.016266 -51.349148)
					(end 250.794266 -51.349148)
				)
			)
		)
	)
	(zone
		(layers "In1.Cu" "In3.Cu" "In5.Cu" "In7.Cu" "In8.Cu" "In9.Cu" "In10.Cu"
			"In12.Cu" "In14.Cu" "In16.Cu"
		)
		(hatch none 0.5)
		(connect_pads
			(clearance 0)
		)
		(min_thickness 0.25)
		(keepout
			(tracks not_allowed)
			(vias allowed)
			(pads allowed)
			(copperpour not_allowed)
			(footprints allowed)
		)
		(placement
			(enabled no)
			(sheetname "")
		)
		(fill yes
			(thermal_gap 0.5)
			(thermal_bridge_width 0.5)
			(island_removal_mode 0)
		)
		(polygon
			(pts
				(arc
					(start 57.05983 -349.581978)
					(mid 55.28183 -349.581978)
					(end 57.05983 -349.581978)
				)
			)
		)
	)
	(zone
		(layers "In1.Cu" "In3.Cu" "In5.Cu" "In7.Cu" "In8.Cu" "In9.Cu" "In10.Cu"
			"In12.Cu" "In14.Cu" "In16.Cu"
		)
		(hatch none 0.5)
		(connect_pads
			(clearance 0)
		)
		(min_thickness 0.25)
		(keepout
			(tracks not_allowed)
			(vias allowed)
			(pads allowed)
			(copperpour not_allowed)
			(footprints allowed)
		)
		(placement
			(enabled no)
			(sheetname "")
		)
		(fill yes
			(thermal_gap 0.5)
			(thermal_bridge_width 0.5)
			(island_removal_mode 0)
		)
		(polygon
			(pts
				(arc
					(start 202.229974 -30.720538)
					(mid 200.451974 -30.720538)
					(end 202.229974 -30.720538)
				)
			)
		)
	)
	(zone
		(layers "In1.Cu" "In3.Cu" "In5.Cu" "In7.Cu" "In8.Cu" "In9.Cu" "In10.Cu"
			"In12.Cu" "In14.Cu" "In16.Cu"
		)
		(hatch none 0.5)
		(connect_pads
			(clearance 0)
		)
		(min_thickness 0.25)
		(keepout
			(tracks not_allowed)
			(vias allowed)
			(pads allowed)
			(copperpour not_allowed)
			(footprints allowed)
		)
		(placement
			(enabled no)
			(sheetname "")
		)
		(fill yes
			(thermal_gap 0.5)
			(thermal_bridge_width 0.5)
			(island_removal_mode 0)
		)
		(polygon
			(pts
				(arc
					(start 380.032768 -180.755544)
					(mid 378.272548 -180.755544)
					(end 380.032768 -180.755544)
				)
			)
		)
	)
	(zone
		(layers "In1.Cu" "In3.Cu" "In5.Cu" "In7.Cu" "In8.Cu" "In9.Cu" "In10.Cu"
			"In12.Cu" "In14.Cu" "In16.Cu"
		)
		(hatch none 0.5)
		(connect_pads
			(clearance 0)
		)
		(min_thickness 0.25)
		(keepout
			(tracks not_allowed)
			(vias allowed)
			(pads allowed)
			(copperpour not_allowed)
			(footprints allowed)
		)
		(placement
			(enabled no)
			(sheetname "")
		)
		(fill yes
			(thermal_gap 0.5)
			(thermal_bridge_width 0.5)
			(island_removal_mode 0)
		)
		(polygon
			(pts
				(arc
					(start 343.676224 -352.215196)
					(mid 341.898224 -352.215196)
					(end 343.676224 -352.215196)
				)
			)
		)
	)
	(zone
		(layers "In1.Cu" "In3.Cu" "In5.Cu" "In7.Cu" "In8.Cu" "In9.Cu" "In10.Cu"
			"In12.Cu" "In14.Cu" "In16.Cu"
		)
		(hatch none 0.5)
		(connect_pads
			(clearance 0)
		)
		(min_thickness 0.25)
		(keepout
			(tracks not_allowed)
			(vias allowed)
			(pads allowed)
			(copperpour not_allowed)
			(footprints allowed)
		)
		(placement
			(enabled no)
			(sheetname "")
		)
		(fill yes
			(thermal_gap 0.5)
			(thermal_bridge_width 0.5)
			(island_removal_mode 0)
		)
		(polygon
			(pts
				(arc
					(start 119.083074 -152.657556)
					(mid 117.305074 -152.657556)
					(end 119.083074 -152.657556)
				)
			)
		)
	)
	(zone
		(layers "In1.Cu" "In3.Cu" "In5.Cu" "In7.Cu" "In8.Cu" "In9.Cu" "In10.Cu"
			"In12.Cu" "In14.Cu" "In16.Cu"
		)
		(hatch none 0.5)
		(connect_pads
			(clearance 0)
		)
		(min_thickness 0.25)
		(keepout
			(tracks not_allowed)
			(vias allowed)
			(pads allowed)
			(copperpour not_allowed)
			(footprints allowed)
		)
		(placement
			(enabled no)
			(sheetname "")
		)
		(fill yes
			(thermal_gap 0.5)
			(thermal_bridge_width 0.5)
			(island_removal_mode 0)
		)
		(polygon
			(pts
				(arc
					(start 339.10016 -337.395058)
					(mid 337.32216 -337.395058)
					(end 339.10016 -337.395058)
				)
			)
		)
	)
	(zone
		(layers "In1.Cu" "In3.Cu" "In5.Cu" "In7.Cu" "In8.Cu" "In9.Cu" "In10.Cu"
			"In12.Cu" "In14.Cu" "In16.Cu"
		)
		(hatch none 0.5)
		(connect_pads
			(clearance 0)
		)
		(min_thickness 0.25)
		(keepout
			(tracks not_allowed)
			(vias allowed)
			(pads allowed)
			(copperpour not_allowed)
			(footprints allowed)
		)
		(placement
			(enabled no)
			(sheetname "")
		)
		(fill yes
			(thermal_gap 0.5)
			(thermal_bridge_width 0.5)
			(island_removal_mode 0)
		)
		(polygon
			(pts
				(arc
					(start 301.935896 -348.704662)
					(mid 300.175676 -348.704662)
					(end 301.935896 -348.704662)
				)
			)
		)
	)
	(zone
		(layers "In1.Cu" "In3.Cu" "In5.Cu" "In7.Cu" "In8.Cu" "In9.Cu" "In10.Cu"
			"In12.Cu" "In14.Cu" "In16.Cu"
		)
		(hatch none 0.5)
		(connect_pads
			(clearance 0)
		)
		(min_thickness 0.25)
		(keepout
			(tracks not_allowed)
			(vias allowed)
			(pads allowed)
			(copperpour not_allowed)
			(footprints allowed)
		)
		(placement
			(enabled no)
			(sheetname "")
		)
		(fill yes
			(thermal_gap 0.5)
			(thermal_bridge_width 0.5)
			(island_removal_mode 0)
		)
		(polygon
			(pts
				(arc
					(start 313.296046 -348.782132)
					(mid 311.518046 -348.782132)
					(end 313.296046 -348.782132)
				)
			)
		)
	)
	(zone
		(layers "In1.Cu" "In3.Cu" "In5.Cu" "In7.Cu" "In8.Cu" "In9.Cu" "In10.Cu"
			"In12.Cu" "In14.Cu" "In16.Cu"
		)
		(hatch none 0.5)
		(connect_pads
			(clearance 0)
		)
		(min_thickness 0.25)
		(keepout
			(tracks not_allowed)
			(vias allowed)
			(pads allowed)
			(copperpour not_allowed)
			(footprints allowed)
		)
		(placement
			(enabled no)
			(sheetname "")
		)
		(fill yes
			(thermal_gap 0.5)
			(thermal_bridge_width 0.5)
			(island_removal_mode 0)
		)
		(polygon
			(pts
				(arc
					(start 187.685172 -362.234988)
					(mid 185.907172 -362.234988)
					(end 187.685172 -362.234988)
				)
			)
		)
	)
	(zone
		(layers "In1.Cu" "In3.Cu" "In5.Cu" "In7.Cu" "In8.Cu" "In9.Cu" "In10.Cu"
			"In12.Cu" "In14.Cu" "In16.Cu"
		)
		(hatch none 0.5)
		(connect_pads
			(clearance 0)
		)
		(min_thickness 0.25)
		(keepout
			(tracks not_allowed)
			(vias allowed)
			(pads allowed)
			(copperpour not_allowed)
			(footprints allowed)
		)
		(placement
			(enabled no)
			(sheetname "")
		)
		(fill yes
			(thermal_gap 0.5)
			(thermal_bridge_width 0.5)
			(island_removal_mode 0)
		)
		(polygon
			(pts
				(arc
					(start 427.6852 -353.53625)
					(mid 425.9072 -353.53625)
					(end 427.6852 -353.53625)
				)
			)
		)
	)
	(zone
		(layers "In1.Cu" "In3.Cu" "In5.Cu" "In7.Cu" "In8.Cu" "In9.Cu" "In10.Cu"
			"In12.Cu" "In14.Cu" "In16.Cu"
		)
		(hatch none 0.5)
		(connect_pads
			(clearance 0)
		)
		(min_thickness 0.25)
		(keepout
			(tracks not_allowed)
			(vias allowed)
			(pads allowed)
			(copperpour not_allowed)
			(footprints allowed)
		)
		(placement
			(enabled no)
			(sheetname "")
		)
		(fill yes
			(thermal_gap 0.5)
			(thermal_bridge_width 0.5)
			(island_removal_mode 0)
		)
		(polygon
			(pts
				(arc
					(start 81.85658 -180.755544)
					(mid 80.09636 -180.755544)
					(end 81.85658 -180.755544)
				)
			)
		)
	)
	(zone
		(layers "In1.Cu" "In3.Cu" "In5.Cu" "In7.Cu" "In8.Cu" "In9.Cu" "In10.Cu"
			"In12.Cu" "In14.Cu" "In16.Cu"
		)
		(hatch none 0.5)
		(connect_pads
			(clearance 0)
		)
		(min_thickness 0.25)
		(keepout
			(tracks not_allowed)
			(vias allowed)
			(pads allowed)
			(copperpour not_allowed)
			(footprints allowed)
		)
		(placement
			(enabled no)
			(sheetname "")
		)
		(fill yes
			(thermal_gap 0.5)
			(thermal_bridge_width 0.5)
			(island_removal_mode 0)
		)
		(polygon
			(pts
				(arc
					(start 40.39743 -350.318578)
					(mid 38.61943 -350.318578)
					(end 40.39743 -350.318578)
				)
			)
		)
	)
	(zone
		(layers "In1.Cu" "In3.Cu" "In5.Cu" "In7.Cu" "In8.Cu" "In9.Cu" "In10.Cu"
			"In12.Cu" "In14.Cu" "In16.Cu"
		)
		(hatch none 0.5)
		(connect_pads
			(clearance 0)
		)
		(min_thickness 0.25)
		(keepout
			(tracks not_allowed)
			(vias allowed)
			(pads allowed)
			(copperpour not_allowed)
			(footprints allowed)
		)
		(placement
			(enabled no)
			(sheetname "")
		)
		(fill yes
			(thermal_gap 0.5)
			(thermal_bridge_width 0.5)
			(island_removal_mode 0)
		)
		(polygon
			(pts
				(arc
					(start 51.111658 -393.292838)
					(mid 51.416458 -393.597638)
					(end 51.721258 -393.292838)
				)
				(arc
					(start 51.721258 -392.429238)
					(mid 51.416458 -392.124438)
					(end 51.111658 -392.429238)
				)
			)
		)
	)
	(zone
		(layers "In1.Cu" "In3.Cu" "In5.Cu" "In7.Cu" "In8.Cu" "In9.Cu" "In10.Cu"
			"In12.Cu" "In14.Cu" "In16.Cu"
		)
		(hatch none 0.5)
		(connect_pads
			(clearance 0)
		)
		(min_thickness 0.25)
		(keepout
			(tracks not_allowed)
			(vias allowed)
			(pads allowed)
			(copperpour not_allowed)
			(footprints allowed)
		)
		(placement
			(enabled no)
			(sheetname "")
		)
		(fill yes
			(thermal_gap 0.5)
			(thermal_bridge_width 0.5)
			(island_removal_mode 0)
		)
		(polygon
			(pts
				(arc
					(start 346.573856 -160.633156)
					(mid 344.795856 -160.633156)
					(end 346.573856 -160.633156)
				)
			)
		)
	)
	(zone
		(layers "In1.Cu" "In3.Cu" "In5.Cu" "In7.Cu" "In8.Cu" "In9.Cu" "In10.Cu"
			"In12.Cu" "In14.Cu" "In16.Cu"
		)
		(hatch none 0.5)
		(connect_pads
			(clearance 0)
		)
		(min_thickness 0.25)
		(keepout
			(tracks not_allowed)
			(vias allowed)
			(pads allowed)
			(copperpour not_allowed)
			(footprints allowed)
		)
		(placement
			(enabled no)
			(sheetname "")
		)
		(fill yes
			(thermal_gap 0.5)
			(thermal_bridge_width 0.5)
			(island_removal_mode 0)
		)
		(polygon
			(pts
				(arc
					(start 238.518954 -44.025566)
					(mid 236.740954 -44.025566)
					(end 238.518954 -44.025566)
				)
			)
		)
	)
	(zone
		(layers "In1.Cu" "In3.Cu" "In5.Cu" "In7.Cu" "In8.Cu" "In9.Cu" "In10.Cu"
			"In12.Cu" "In14.Cu" "In16.Cu"
		)
		(hatch none 0.5)
		(connect_pads
			(clearance 0)
		)
		(min_thickness 0.25)
		(keepout
			(tracks not_allowed)
			(vias allowed)
			(pads allowed)
			(copperpour not_allowed)
			(footprints allowed)
		)
		(placement
			(enabled no)
			(sheetname "")
		)
		(fill yes
			(thermal_gap 0.5)
			(thermal_bridge_width 0.5)
			(island_removal_mode 0)
		)
		(polygon
			(pts
				(arc
					(start 353.211638 -166.693596)
					(mid 351.433638 -166.693596)
					(end 353.211638 -166.693596)
				)
			)
		)
	)
	(zone
		(layers "In1.Cu" "In3.Cu" "In5.Cu" "In7.Cu" "In8.Cu" "In9.Cu" "In10.Cu"
			"In12.Cu" "In14.Cu" "In16.Cu"
		)
		(hatch none 0.5)
		(connect_pads
			(clearance 0)
		)
		(min_thickness 0.25)
		(keepout
			(tracks not_allowed)
			(vias allowed)
			(pads allowed)
			(copperpour not_allowed)
			(footprints allowed)
		)
		(placement
			(enabled no)
			(sheetname "")
		)
		(fill yes
			(thermal_gap 0.5)
			(thermal_bridge_width 0.5)
			(island_removal_mode 0)
		)
		(polygon
			(pts
				(arc
					(start 442.45149 -25.461976)
					(mid 440.67349 -25.461976)
					(end 442.45149 -25.461976)
				)
			)
		)
	)
	(zone
		(layers "In1.Cu" "In3.Cu" "In5.Cu" "In7.Cu" "In8.Cu" "In9.Cu" "In10.Cu"
			"In12.Cu" "In14.Cu" "In16.Cu"
		)
		(hatch none 0.5)
		(connect_pads
			(clearance 0)
		)
		(min_thickness 0.25)
		(keepout
			(tracks not_allowed)
			(vias allowed)
			(pads allowed)
			(copperpour not_allowed)
			(footprints allowed)
		)
		(placement
			(enabled no)
			(sheetname "")
		)
		(fill yes
			(thermal_gap 0.5)
			(thermal_bridge_width 0.5)
			(island_removal_mode 0)
		)
		(polygon
			(pts
				(arc
					(start 81.23936 -180.755544)
					(mid 79.47914 -180.755544)
					(end 81.23936 -180.755544)
				)
			)
		)
	)
	(zone
		(layers "In1.Cu" "In3.Cu" "In5.Cu" "In7.Cu" "In8.Cu" "In9.Cu" "In10.Cu"
			"In12.Cu" "In14.Cu" "In16.Cu"
		)
		(hatch none 0.5)
		(connect_pads
			(clearance 0)
		)
		(min_thickness 0.25)
		(keepout
			(tracks not_allowed)
			(vias allowed)
			(pads allowed)
			(copperpour not_allowed)
			(footprints allowed)
		)
		(placement
			(enabled no)
			(sheetname "")
		)
		(fill yes
			(thermal_gap 0.5)
			(thermal_bridge_width 0.5)
			(island_removal_mode 0)
		)
		(polygon
			(pts
				(arc
					(start 379.339602 -179.146454)
					(mid 377.561602 -179.146454)
					(end 379.339602 -179.146454)
				)
			)
		)
	)
	(zone
		(layers "In1.Cu" "In3.Cu" "In5.Cu" "In7.Cu" "In8.Cu" "In9.Cu" "In10.Cu"
			"In12.Cu" "In14.Cu" "In16.Cu"
		)
		(hatch none 0.5)
		(connect_pads
			(clearance 0)
		)
		(min_thickness 0.25)
		(keepout
			(tracks not_allowed)
			(vias allowed)
			(pads allowed)
			(copperpour not_allowed)
			(footprints allowed)
		)
		(placement
			(enabled no)
			(sheetname "")
		)
		(fill yes
			(thermal_gap 0.5)
			(thermal_bridge_width 0.5)
			(island_removal_mode 0)
		)
		(polygon
			(pts
				(arc
					(start 329.807824 -335.517236)
					(mid 328.029824 -335.517236)
					(end 329.807824 -335.517236)
				)
			)
		)
	)
	(zone
		(layers "In1.Cu" "In3.Cu" "In5.Cu" "In7.Cu" "In8.Cu" "In9.Cu" "In10.Cu"
			"In12.Cu" "In14.Cu" "In16.Cu"
		)
		(hatch none 0.5)
		(connect_pads
			(clearance 0)
		)
		(min_thickness 0.25)
		(keepout
			(tracks not_allowed)
			(vias allowed)
			(pads allowed)
			(copperpour not_allowed)
			(footprints allowed)
		)
		(placement
			(enabled no)
			(sheetname "")
		)
		(fill yes
			(thermal_gap 0.5)
			(thermal_bridge_width 0.5)
			(island_removal_mode 0)
		)
		(polygon
			(pts
				(arc
					(start 65.915794 -349.142558)
					(mid 64.137794 -349.142558)
					(end 65.915794 -349.142558)
				)
			)
		)
	)
	(zone
		(layers "In1.Cu" "In3.Cu" "In5.Cu" "In7.Cu" "In8.Cu" "In9.Cu" "In10.Cu"
			"In12.Cu" "In14.Cu" "In16.Cu"
		)
		(hatch none 0.5)
		(connect_pads
			(clearance 0)
		)
		(min_thickness 0.25)
		(keepout
			(tracks not_allowed)
			(vias allowed)
			(pads allowed)
			(copperpour not_allowed)
			(footprints allowed)
		)
		(placement
			(enabled no)
			(sheetname "")
		)
		(fill yes
			(thermal_gap 0.5)
			(thermal_bridge_width 0.5)
			(island_removal_mode 0)
		)
		(polygon
			(pts
				(arc
					(start 105.19283 -175.750474)
					(mid 103.41483 -175.750474)
					(end 105.19283 -175.750474)
				)
			)
		)
	)
	(zone
		(layers "In1.Cu" "In3.Cu" "In5.Cu" "In7.Cu" "In8.Cu" "In9.Cu" "In10.Cu"
			"In12.Cu" "In14.Cu" "In16.Cu"
		)
		(hatch none 0.5)
		(connect_pads
			(clearance 0)
		)
		(min_thickness 0.25)
		(keepout
			(tracks not_allowed)
			(vias allowed)
			(pads allowed)
			(copperpour not_allowed)
			(footprints allowed)
		)
		(placement
			(enabled no)
			(sheetname "")
		)
		(fill yes
			(thermal_gap 0.5)
			(thermal_bridge_width 0.5)
			(island_removal_mode 0)
		)
		(polygon
			(pts
				(arc
					(start 83.121754 -348.191074)
					(mid 81.343754 -348.191074)
					(end 83.121754 -348.191074)
				)
			)
		)
	)
	(zone
		(layers "In1.Cu" "In3.Cu" "In5.Cu" "In7.Cu" "In8.Cu" "In9.Cu" "In10.Cu"
			"In12.Cu" "In14.Cu" "In16.Cu"
		)
		(hatch none 0.5)
		(connect_pads
			(clearance 0)
		)
		(min_thickness 0.25)
		(keepout
			(tracks not_allowed)
			(vias allowed)
			(pads allowed)
			(copperpour not_allowed)
			(footprints allowed)
		)
		(placement
			(enabled no)
			(sheetname "")
		)
		(fill yes
			(thermal_gap 0.5)
			(thermal_bridge_width 0.5)
			(island_removal_mode 0)
		)
		(polygon
			(pts
				(arc
					(start 58.311796 -393.292838)
					(mid 58.616596 -393.597638)
					(end 58.921396 -393.292838)
				)
				(arc
					(start 58.921396 -392.429238)
					(mid 58.616596 -392.124438)
					(end 58.311796 -392.429238)
				)
			)
		)
	)
	(zone
		(layers "In1.Cu" "In3.Cu" "In5.Cu" "In7.Cu" "In8.Cu" "In9.Cu" "In10.Cu"
			"In12.Cu" "In14.Cu" "In16.Cu"
		)
		(hatch none 0.5)
		(connect_pads
			(clearance 0)
		)
		(min_thickness 0.25)
		(keepout
			(tracks not_allowed)
			(vias allowed)
			(pads allowed)
			(copperpour not_allowed)
			(footprints allowed)
		)
		(placement
			(enabled no)
			(sheetname "")
		)
		(fill yes
			(thermal_gap 0.5)
			(thermal_bridge_width 0.5)
			(island_removal_mode 0)
		)
		(polygon
			(pts
				(arc
					(start 91.547442 -346.639896)
					(mid 89.769442 -346.639896)
					(end 91.547442 -346.639896)
				)
			)
		)
	)
	(zone
		(layers "In1.Cu" "In3.Cu" "In5.Cu" "In7.Cu" "In8.Cu" "In9.Cu" "In10.Cu"
			"In12.Cu" "In14.Cu" "In16.Cu"
		)
		(hatch none 0.5)
		(connect_pads
			(clearance 0)
		)
		(min_thickness 0.25)
		(keepout
			(tracks not_allowed)
			(vias allowed)
			(pads allowed)
			(copperpour not_allowed)
			(footprints allowed)
		)
		(placement
			(enabled no)
			(sheetname "")
		)
		(fill yes
			(thermal_gap 0.5)
			(thermal_bridge_width 0.5)
			(island_removal_mode 0)
		)
		(polygon
			(pts
				(arc
					(start 56.616854 -347.997018)
					(mid 54.838854 -347.997018)
					(end 56.616854 -347.997018)
				)
			)
		)
	)
	(zone
		(layers "In1.Cu" "In3.Cu" "In5.Cu" "In7.Cu" "In8.Cu" "In9.Cu" "In10.Cu"
			"In12.Cu" "In14.Cu" "In16.Cu"
		)
		(hatch none 0.5)
		(connect_pads
			(clearance 0)
		)
		(min_thickness 0.25)
		(keepout
			(tracks not_allowed)
			(vias allowed)
			(pads allowed)
			(copperpour not_allowed)
			(footprints allowed)
		)
		(placement
			(enabled no)
			(sheetname "")
		)
		(fill yes
			(thermal_gap 0.5)
			(thermal_bridge_width 0.5)
			(island_removal_mode 0)
		)
		(polygon
			(pts
				(arc
					(start 388.182358 -157.001972)
					(mid 386.404358 -157.001972)
					(end 388.182358 -157.001972)
				)
			)
		)
	)
	(zone
		(layers "In1.Cu" "In3.Cu" "In5.Cu" "In7.Cu" "In8.Cu" "In9.Cu" "In10.Cu"
			"In12.Cu" "In14.Cu" "In16.Cu"
		)
		(hatch none 0.5)
		(connect_pads
			(clearance 0)
		)
		(min_thickness 0.25)
		(keepout
			(tracks not_allowed)
			(vias allowed)
			(pads allowed)
			(copperpour not_allowed)
			(footprints allowed)
		)
		(placement
			(enabled no)
			(sheetname "")
		)
		(fill yes
			(thermal_gap 0.5)
			(thermal_bridge_width 0.5)
			(island_removal_mode 0)
		)
		(polygon
			(pts
				(arc
					(start 386.587238 -180.678074)
					(mid 384.809238 -180.678074)
					(end 386.587238 -180.678074)
				)
			)
		)
	)
	(zone
		(layers "In1.Cu" "In3.Cu" "In5.Cu" "In7.Cu" "In8.Cu" "In9.Cu" "In10.Cu"
			"In12.Cu" "In14.Cu" "In16.Cu"
		)
		(hatch none 0.5)
		(connect_pads
			(clearance 0)
		)
		(min_thickness 0.25)
		(keepout
			(tracks not_allowed)
			(vias allowed)
			(pads allowed)
			(copperpour not_allowed)
			(footprints allowed)
		)
		(placement
			(enabled no)
			(sheetname "")
		)
		(fill yes
			(thermal_gap 0.5)
			(thermal_bridge_width 0.5)
			(island_removal_mode 0)
		)
		(polygon
			(pts
				(arc
					(start 338.169504 -335.517236)
					(mid 336.391504 -335.517236)
					(end 338.169504 -335.517236)
				)
			)
		)
	)
	(zone
		(layers "In1.Cu" "In3.Cu" "In5.Cu" "In7.Cu" "In8.Cu" "In9.Cu" "In10.Cu"
			"In12.Cu" "In14.Cu" "In16.Cu"
		)
		(hatch none 0.5)
		(connect_pads
			(clearance 0)
		)
		(min_thickness 0.25)
		(keepout
			(tracks not_allowed)
			(vias allowed)
			(pads allowed)
			(copperpour not_allowed)
			(footprints allowed)
		)
		(placement
			(enabled no)
			(sheetname "")
		)
		(fill yes
			(thermal_gap 0.5)
			(thermal_bridge_width 0.5)
			(island_removal_mode 0)
		)
		(polygon
			(pts
				(arc
					(start 369.85321 -179.204874)
					(mid 368.07521 -179.204874)
					(end 369.85321 -179.204874)
				)
			)
		)
	)
	(zone
		(layers "In1.Cu" "In3.Cu" "In5.Cu" "In7.Cu" "In8.Cu" "In9.Cu" "In10.Cu"
			"In12.Cu" "In14.Cu" "In16.Cu"
		)
		(hatch none 0.5)
		(connect_pads
			(clearance 0)
		)
		(min_thickness 0.25)
		(keepout
			(tracks not_allowed)
			(vias allowed)
			(pads allowed)
			(copperpour not_allowed)
			(footprints allowed)
		)
		(placement
			(enabled no)
			(sheetname "")
		)
		(fill yes
			(thermal_gap 0.5)
			(thermal_bridge_width 0.5)
			(island_removal_mode 0)
		)
		(polygon
			(pts
				(arc
					(start 129.60223 -152.992074)
					(mid 127.82423 -152.992074)
					(end 129.60223 -152.992074)
				)
			)
		)
	)
	(zone
		(layers "In1.Cu" "In3.Cu" "In5.Cu" "In7.Cu" "In8.Cu" "In9.Cu" "In10.Cu"
			"In12.Cu" "In14.Cu" "In16.Cu"
		)
		(hatch none 0.5)
		(connect_pads
			(clearance 0)
		)
		(min_thickness 0.25)
		(keepout
			(tracks not_allowed)
			(vias allowed)
			(pads allowed)
			(copperpour not_allowed)
			(footprints allowed)
		)
		(placement
			(enabled no)
			(sheetname "")
		)
		(fill yes
			(thermal_gap 0.5)
			(thermal_bridge_width 0.5)
			(island_removal_mode 0)
		)
		(polygon
			(pts
				(arc
					(start 63.38443 -166.50716)
					(mid 61.60643 -166.50716)
					(end 63.38443 -166.50716)
				)
			)
		)
	)
	(zone
		(layers "In1.Cu" "In3.Cu" "In5.Cu" "In7.Cu" "In8.Cu" "In9.Cu" "In10.Cu"
			"In12.Cu" "In14.Cu" "In16.Cu"
		)
		(hatch none 0.5)
		(connect_pads
			(clearance 0)
		)
		(min_thickness 0.25)
		(keepout
			(tracks not_allowed)
			(vias allowed)
			(pads allowed)
			(copperpour not_allowed)
			(footprints allowed)
		)
		(placement
			(enabled no)
			(sheetname "")
		)
		(fill yes
			(thermal_gap 0.5)
			(thermal_bridge_width 0.5)
			(island_removal_mode 0)
		)
		(polygon
			(pts
				(arc
					(start 193.985134 -16.416528)
					(mid 192.207134 -16.416528)
					(end 193.985134 -16.416528)
				)
			)
		)
	)
	(zone
		(layers "In1.Cu" "In3.Cu" "In5.Cu" "In7.Cu" "In8.Cu" "In9.Cu" "In10.Cu"
			"In12.Cu" "In14.Cu" "In16.Cu"
		)
		(hatch none 0.5)
		(connect_pads
			(clearance 0)
		)
		(min_thickness 0.25)
		(keepout
			(tracks not_allowed)
			(vias allowed)
			(pads allowed)
			(copperpour not_allowed)
			(footprints allowed)
		)
		(placement
			(enabled no)
			(sheetname "")
		)
		(fill yes
			(thermal_gap 0.5)
			(thermal_bridge_width 0.5)
			(island_removal_mode 0)
		)
		(polygon
			(pts
				(arc
					(start 395.535658 -173.987714)
					(mid 393.757658 -173.987714)
					(end 395.535658 -173.987714)
				)
			)
		)
	)
	(zone
		(layers "In1.Cu" "In3.Cu" "In5.Cu" "In7.Cu" "In8.Cu" "In9.Cu" "In10.Cu"
			"In12.Cu" "In14.Cu" "In16.Cu"
		)
		(hatch none 0.5)
		(connect_pads
			(clearance 0)
		)
		(min_thickness 0.25)
		(keepout
			(tracks not_allowed)
			(vias allowed)
			(pads allowed)
			(copperpour not_allowed)
			(footprints allowed)
		)
		(placement
			(enabled no)
			(sheetname "")
		)
		(fill yes
			(thermal_gap 0.5)
			(thermal_bridge_width 0.5)
			(island_removal_mode 0)
		)
		(polygon
			(pts
				(arc
					(start 195.287646 -353.742244)
					(mid 193.509646 -353.742244)
					(end 195.287646 -353.742244)
				)
			)
		)
	)
	(zone
		(layers "In1.Cu" "In3.Cu" "In5.Cu" "In7.Cu" "In8.Cu" "In9.Cu" "In10.Cu"
			"In12.Cu" "In14.Cu" "In16.Cu"
		)
		(hatch none 0.5)
		(connect_pads
			(clearance 0)
		)
		(min_thickness 0.25)
		(keepout
			(tracks not_allowed)
			(vias allowed)
			(pads allowed)
			(copperpour not_allowed)
			(footprints allowed)
		)
		(placement
			(enabled no)
			(sheetname "")
		)
		(fill yes
			(thermal_gap 0.5)
			(thermal_bridge_width 0.5)
			(island_removal_mode 0)
		)
		(polygon
			(pts
				(arc
					(start 91.188794 -338.161884)
					(mid 89.410794 -338.161884)
					(end 91.188794 -338.161884)
				)
			)
		)
	)
	(zone
		(layers "In1.Cu" "In3.Cu" "In5.Cu" "In7.Cu" "In8.Cu" "In9.Cu" "In10.Cu"
			"In12.Cu" "In14.Cu" "In16.Cu"
		)
		(hatch none 0.5)
		(connect_pads
			(clearance 0)
		)
		(min_thickness 0.25)
		(keepout
			(tracks not_allowed)
			(vias allowed)
			(pads allowed)
			(copperpour not_allowed)
			(footprints allowed)
		)
		(placement
			(enabled no)
			(sheetname "")
		)
		(fill yes
			(thermal_gap 0.5)
			(thermal_bridge_width 0.5)
			(island_removal_mode 0)
		)
		(polygon
			(pts
				(arc
					(start 80.02143 -180.322474)
					(mid 78.24343 -180.322474)
					(end 80.02143 -180.322474)
				)
			)
		)
	)
	(zone
		(layers "In1.Cu" "In3.Cu" "In5.Cu" "In7.Cu" "In8.Cu" "In9.Cu" "In10.Cu"
			"In12.Cu" "In14.Cu" "In16.Cu"
		)
		(hatch none 0.5)
		(connect_pads
			(clearance 0)
		)
		(min_thickness 0.25)
		(keepout
			(tracks not_allowed)
			(vias allowed)
			(pads allowed)
			(copperpour not_allowed)
			(footprints allowed)
		)
		(placement
			(enabled no)
			(sheetname "")
		)
		(fill yes
			(thermal_gap 0.5)
			(thermal_bridge_width 0.5)
			(island_removal_mode 0)
		)
		(polygon
			(pts
				(arc
					(start 329.807824 -336.253836)
					(mid 328.029824 -336.253836)
					(end 329.807824 -336.253836)
				)
			)
		)
	)
	(zone
		(layers "In1.Cu" "In3.Cu" "In5.Cu" "In7.Cu" "In8.Cu" "In9.Cu" "In10.Cu"
			"In12.Cu" "In14.Cu" "In16.Cu"
		)
		(hatch none 0.5)
		(connect_pads
			(clearance 0)
		)
		(min_thickness 0.25)
		(keepout
			(tracks not_allowed)
			(vias allowed)
			(pads allowed)
			(copperpour not_allowed)
			(footprints allowed)
		)
		(placement
			(enabled no)
			(sheetname "")
		)
		(fill yes
			(thermal_gap 0.5)
			(thermal_bridge_width 0.5)
			(island_removal_mode 0)
		)
		(polygon
			(pts
				(arc
					(start 99.636834 -339.736684)
					(mid 97.858834 -339.736684)
					(end 99.636834 -339.736684)
				)
			)
		)
	)
	(zone
		(layers "In1.Cu" "In3.Cu" "In5.Cu" "In7.Cu" "In8.Cu" "In9.Cu" "In10.Cu"
			"In12.Cu" "In14.Cu" "In16.Cu"
		)
		(hatch none 0.5)
		(connect_pads
			(clearance 0)
		)
		(min_thickness 0.25)
		(keepout
			(tracks not_allowed)
			(vias allowed)
			(pads allowed)
			(copperpour not_allowed)
			(footprints allowed)
		)
		(placement
			(enabled no)
			(sheetname "")
		)
		(fill yes
			(thermal_gap 0.5)
			(thermal_bridge_width 0.5)
			(island_removal_mode 0)
		)
		(polygon
			(pts
				(arc
					(start 297.69689 -358.769666)
					(mid 294.90289 -358.769666)
					(end 297.69689 -358.769666)
				)
			)
		)
	)
	(zone
		(layers "In1.Cu" "In3.Cu" "In5.Cu" "In7.Cu" "In8.Cu" "In9.Cu" "In10.Cu"
			"In12.Cu" "In14.Cu" "In16.Cu"
		)
		(hatch none 0.5)
		(connect_pads
			(clearance 0)
		)
		(min_thickness 0.25)
		(keepout
			(tracks not_allowed)
			(vias allowed)
			(pads allowed)
			(copperpour not_allowed)
			(footprints allowed)
		)
		(placement
			(enabled no)
			(sheetname "")
		)
		(fill yes
			(thermal_gap 0.5)
			(thermal_bridge_width 0.5)
			(island_removal_mode 0)
		)
		(polygon
			(pts
				(arc
					(start 342.826848 -353.010216)
					(mid 341.048848 -353.010216)
					(end 342.826848 -353.010216)
				)
			)
		)
	)
	(zone
		(layers "In1.Cu" "In3.Cu" "In5.Cu" "In7.Cu" "In8.Cu" "In9.Cu" "In10.Cu"
			"In12.Cu" "In14.Cu" "In16.Cu"
		)
		(hatch none 0.5)
		(connect_pads
			(clearance 0)
		)
		(min_thickness 0.25)
		(keepout
			(tracks not_allowed)
			(vias allowed)
			(pads allowed)
			(copperpour not_allowed)
			(footprints allowed)
		)
		(placement
			(enabled no)
			(sheetname "")
		)
		(fill yes
			(thermal_gap 0.5)
			(thermal_bridge_width 0.5)
			(island_removal_mode 0)
		)
		(polygon
			(pts
				(arc
					(start 363.276388 -175.859186)
					(mid 361.516168 -175.859186)
					(end 363.276388 -175.859186)
				)
			)
		)
	)
	(zone
		(layers "In1.Cu" "In3.Cu" "In5.Cu" "In7.Cu" "In8.Cu" "In9.Cu" "In10.Cu"
			"In12.Cu" "In14.Cu" "In16.Cu"
		)
		(hatch none 0.5)
		(connect_pads
			(clearance 0)
		)
		(min_thickness 0.25)
		(keepout
			(tracks not_allowed)
			(vias allowed)
			(pads allowed)
			(copperpour not_allowed)
			(footprints allowed)
		)
		(placement
			(enabled no)
			(sheetname "")
		)
		(fill yes
			(thermal_gap 0.5)
			(thermal_bridge_width 0.5)
			(island_removal_mode 0)
		)
		(polygon
			(pts
				(arc
					(start 238.529114 -44.716446)
					(mid 236.751114 -44.716446)
					(end 238.529114 -44.716446)
				)
			)
		)
	)
	(zone
		(layers "In1.Cu" "In3.Cu" "In5.Cu" "In7.Cu" "In8.Cu" "In9.Cu" "In10.Cu"
			"In12.Cu" "In14.Cu" "In16.Cu"
		)
		(hatch none 0.5)
		(connect_pads
			(clearance 0)
		)
		(min_thickness 0.25)
		(keepout
			(tracks not_allowed)
			(vias allowed)
			(pads allowed)
			(copperpour not_allowed)
			(footprints allowed)
		)
		(placement
			(enabled no)
			(sheetname "")
		)
		(fill yes
			(thermal_gap 0.5)
			(thermal_bridge_width 0.5)
			(island_removal_mode 0)
		)
		(polygon
			(pts
				(arc
					(start 289.80511 -355.949758)
					(mid 288.02711 -355.949758)
					(end 289.80511 -355.949758)
				)
			)
		)
	)
	(zone
		(layers "In1.Cu" "In3.Cu" "In5.Cu" "In7.Cu" "In8.Cu" "In9.Cu" "In10.Cu"
			"In12.Cu" "In14.Cu" "In16.Cu"
		)
		(hatch none 0.5)
		(connect_pads
			(clearance 0)
		)
		(min_thickness 0.25)
		(keepout
			(tracks not_allowed)
			(vias allowed)
			(pads allowed)
			(copperpour not_allowed)
			(footprints allowed)
		)
		(placement
			(enabled no)
			(sheetname "")
		)
		(fill yes
			(thermal_gap 0.5)
			(thermal_bridge_width 0.5)
			(island_removal_mode 0)
		)
		(polygon
			(pts
				(arc
					(start 62.82563 -166.86276)
					(mid 61.04763 -166.86276)
					(end 62.82563 -166.86276)
				)
			)
		)
	)
	(zone
		(layers "In1.Cu" "In3.Cu" "In5.Cu" "In7.Cu" "In8.Cu" "In9.Cu" "In10.Cu"
			"In12.Cu" "In14.Cu" "In16.Cu"
		)
		(hatch none 0.5)
		(connect_pads
			(clearance 0)
		)
		(min_thickness 0.25)
		(keepout
			(tracks not_allowed)
			(vias allowed)
			(pads allowed)
			(copperpour not_allowed)
			(footprints allowed)
		)
		(placement
			(enabled no)
			(sheetname "")
		)
		(fill yes
			(thermal_gap 0.5)
			(thermal_bridge_width 0.5)
			(island_removal_mode 0)
		)
		(polygon
			(pts
				(arc
					(start 387.146038 -180.322474)
					(mid 385.368038 -180.322474)
					(end 387.146038 -180.322474)
				)
			)
		)
	)
	(zone
		(layers "In1.Cu" "In3.Cu" "In5.Cu" "In7.Cu" "In8.Cu" "In9.Cu" "In10.Cu"
			"In12.Cu" "In14.Cu" "In16.Cu"
		)
		(hatch none 0.5)
		(connect_pads
			(clearance 0)
		)
		(min_thickness 0.25)
		(keepout
			(tracks not_allowed)
			(vias allowed)
			(pads allowed)
			(copperpour not_allowed)
			(footprints allowed)
		)
		(placement
			(enabled no)
			(sheetname "")
		)
		(fill yes
			(thermal_gap 0.5)
			(thermal_bridge_width 0.5)
			(island_removal_mode 0)
		)
		(polygon
			(pts
				(arc
					(start 73.92543 -337.860894)
					(mid 72.14743 -337.860894)
					(end 73.92543 -337.860894)
				)
			)
		)
	)
	(zone
		(layers "In1.Cu" "In3.Cu" "In5.Cu" "In7.Cu" "In8.Cu" "In9.Cu" "In10.Cu"
			"In12.Cu" "In14.Cu" "In16.Cu"
		)
		(hatch none 0.5)
		(connect_pads
			(clearance 0)
		)
		(min_thickness 0.25)
		(keepout
			(tracks not_allowed)
			(vias allowed)
			(pads allowed)
			(copperpour not_allowed)
			(footprints allowed)
		)
		(placement
			(enabled no)
			(sheetname "")
		)
		(fill yes
			(thermal_gap 0.5)
			(thermal_bridge_width 0.5)
			(island_removal_mode 0)
		)
		(polygon
			(pts
				(arc
					(start 403.325838 -165.791388)
					(mid 401.547838 -165.791388)
					(end 403.325838 -165.791388)
				)
			)
		)
	)
	(zone
		(layers "In1.Cu" "In3.Cu" "In5.Cu" "In7.Cu" "In8.Cu" "In9.Cu" "In10.Cu"
			"In12.Cu" "In14.Cu" "In16.Cu"
		)
		(hatch none 0.5)
		(connect_pads
			(clearance 0)
		)
		(min_thickness 0.25)
		(keepout
			(tracks not_allowed)
			(vias allowed)
			(pads allowed)
			(copperpour not_allowed)
			(footprints allowed)
		)
		(placement
			(enabled no)
			(sheetname "")
		)
		(fill yes
			(thermal_gap 0.5)
			(thermal_bridge_width 0.5)
			(island_removal_mode 0)
		)
		(polygon
			(pts
				(arc
					(start 339.65896 -337.776058)
					(mid 337.88096 -337.776058)
					(end 339.65896 -337.776058)
				)
			)
		)
	)
	(zone
		(layers "In1.Cu" "In3.Cu" "In5.Cu" "In7.Cu" "In8.Cu" "In9.Cu" "In10.Cu"
			"In12.Cu" "In14.Cu" "In16.Cu"
		)
		(hatch none 0.5)
		(connect_pads
			(clearance 0)
		)
		(min_thickness 0.25)
		(keepout
			(tracks not_allowed)
			(vias allowed)
			(pads allowed)
			(copperpour not_allowed)
			(footprints allowed)
		)
		(placement
			(enabled no)
			(sheetname "")
		)
		(fill yes
			(thermal_gap 0.5)
			(thermal_bridge_width 0.5)
			(island_removal_mode 0)
		)
		(polygon
			(pts
				(arc
					(start 119.718074 -152.022556)
					(mid 117.940074 -152.022556)
					(end 119.718074 -152.022556)
				)
			)
		)
	)
	(zone
		(layers "In1.Cu" "In3.Cu" "In5.Cu" "In7.Cu" "In8.Cu" "In9.Cu" "In10.Cu"
			"In12.Cu" "In14.Cu" "In16.Cu"
		)
		(hatch none 0.5)
		(connect_pads
			(clearance 0)
		)
		(min_thickness 0.25)
		(keepout
			(tracks not_allowed)
			(vias allowed)
			(pads allowed)
			(copperpour not_allowed)
			(footprints allowed)
		)
		(placement
			(enabled no)
			(sheetname "")
		)
		(fill yes
			(thermal_gap 0.5)
			(thermal_bridge_width 0.5)
			(island_removal_mode 0)
		)
		(polygon
			(pts
				(arc
					(start 89.83345 -162.812476)
					(mid 88.05545 -162.812476)
					(end 89.83345 -162.812476)
				)
			)
		)
	)
	(zone
		(layers "In1.Cu" "In3.Cu" "In5.Cu" "In7.Cu" "In8.Cu" "In9.Cu" "In10.Cu"
			"In12.Cu" "In14.Cu" "In16.Cu"
		)
		(hatch none 0.5)
		(connect_pads
			(clearance 0)
		)
		(min_thickness 0.25)
		(keepout
			(tracks not_allowed)
			(vias allowed)
			(pads allowed)
			(copperpour not_allowed)
			(footprints allowed)
		)
		(placement
			(enabled no)
			(sheetname "")
		)
		(fill yes
			(thermal_gap 0.5)
			(thermal_bridge_width 0.5)
			(island_removal_mode 0)
		)
		(polygon
			(pts
				(arc
					(start 311.501536 -348.704662)
					(mid 309.741316 -348.704662)
					(end 311.501536 -348.704662)
				)
			)
		)
	)
	(zone
		(layers "In1.Cu" "In3.Cu" "In5.Cu" "In7.Cu" "In8.Cu" "In9.Cu" "In10.Cu"
			"In12.Cu" "In14.Cu" "In16.Cu"
		)
		(hatch none 0.5)
		(connect_pads
			(clearance 0)
		)
		(min_thickness 0.25)
		(keepout
			(tracks not_allowed)
			(vias allowed)
			(pads allowed)
			(copperpour not_allowed)
			(footprints allowed)
		)
		(placement
			(enabled no)
			(sheetname "")
		)
		(fill yes
			(thermal_gap 0.5)
			(thermal_bridge_width 0.5)
			(island_removal_mode 0)
		)
		(polygon
			(pts
				(arc
					(start 80.810862 -18.238724)
					(mid 79.032862 -18.238724)
					(end 80.810862 -18.238724)
				)
			)
		)
	)
	(zone
		(layers "In1.Cu" "In3.Cu" "In5.Cu" "In7.Cu" "In8.Cu" "In9.Cu" "In10.Cu"
			"In12.Cu" "In14.Cu" "In16.Cu"
		)
		(hatch none 0.5)
		(connect_pads
			(clearance 0)
		)
		(min_thickness 0.25)
		(keepout
			(tracks not_allowed)
			(vias allowed)
			(pads allowed)
			(copperpour not_allowed)
			(footprints allowed)
		)
		(placement
			(enabled no)
			(sheetname "")
		)
		(fill yes
			(thermal_gap 0.5)
			(thermal_bridge_width 0.5)
			(island_removal_mode 0)
		)
		(polygon
			(pts
				(arc
					(start 48.81753 -356.822502)
					(mid 47.03953 -356.822502)
					(end 48.81753 -356.822502)
				)
			)
		)
	)
	(zone
		(layers "In1.Cu" "In3.Cu" "In5.Cu" "In7.Cu" "In8.Cu" "In9.Cu" "In10.Cu"
			"In12.Cu" "In14.Cu" "In16.Cu"
		)
		(hatch none 0.5)
		(connect_pads
			(clearance 0)
		)
		(min_thickness 0.25)
		(keepout
			(tracks not_allowed)
			(vias allowed)
			(pads allowed)
			(copperpour not_allowed)
			(footprints allowed)
		)
		(placement
			(enabled no)
			(sheetname "")
		)
		(fill yes
			(thermal_gap 0.5)
			(thermal_bridge_width 0.5)
			(island_removal_mode 0)
		)
		(polygon
			(pts
				(arc
					(start 185.108088 -353.283774)
					(mid 183.347868 -353.283774)
					(end 185.108088 -353.283774)
				)
			)
		)
	)
	(zone
		(layers "In1.Cu" "In3.Cu" "In5.Cu" "In7.Cu" "In8.Cu" "In9.Cu" "In10.Cu"
			"In12.Cu" "In14.Cu" "In16.Cu"
		)
		(hatch none 0.5)
		(connect_pads
			(clearance 0)
		)
		(min_thickness 0.25)
		(keepout
			(tracks not_allowed)
			(vias allowed)
			(pads allowed)
			(copperpour not_allowed)
			(footprints allowed)
		)
		(placement
			(enabled no)
			(sheetname "")
		)
		(fill yes
			(thermal_gap 0.5)
			(thermal_bridge_width 0.5)
			(island_removal_mode 0)
		)
		(polygon
			(pts
				(arc
					(start 209.397854 -37.366448)
					(mid 207.619854 -37.366448)
					(end 209.397854 -37.366448)
				)
			)
		)
	)
	(zone
		(layers "In1.Cu" "In3.Cu" "In5.Cu" "In7.Cu" "In8.Cu" "In9.Cu" "In10.Cu"
			"In12.Cu" "In14.Cu" "In16.Cu"
		)
		(hatch none 0.5)
		(connect_pads
			(clearance 0)
		)
		(min_thickness 0.25)
		(keepout
			(tracks not_allowed)
			(vias allowed)
			(pads allowed)
			(copperpour not_allowed)
			(footprints allowed)
		)
		(placement
			(enabled no)
			(sheetname "")
		)
		(fill yes
			(thermal_gap 0.5)
			(thermal_bridge_width 0.5)
			(island_removal_mode 0)
		)
		(polygon
			(pts
				(arc
					(start 96.81083 -180.271674)
					(mid 95.03283 -180.271674)
					(end 96.81083 -180.271674)
				)
			)
		)
	)
	(zone
		(layers "In1.Cu" "In3.Cu" "In5.Cu" "In7.Cu" "In8.Cu" "In9.Cu" "In10.Cu"
			"In12.Cu" "In14.Cu" "In16.Cu"
		)
		(hatch none 0.5)
		(connect_pads
			(clearance 0)
		)
		(min_thickness 0.25)
		(keepout
			(tracks not_allowed)
			(vias allowed)
			(pads allowed)
			(copperpour not_allowed)
			(footprints allowed)
		)
		(placement
			(enabled no)
			(sheetname "")
		)
		(fill yes
			(thermal_gap 0.5)
			(thermal_bridge_width 0.5)
			(island_removal_mode 0)
		)
		(polygon
			(pts
				(arc
					(start 342.914224 -352.215196)
					(mid 341.136224 -352.215196)
					(end 342.914224 -352.215196)
				)
			)
		)
	)
	(zone
		(layers "In1.Cu" "In3.Cu" "In5.Cu" "In7.Cu" "In8.Cu" "In9.Cu" "In10.Cu"
			"In12.Cu" "In14.Cu" "In16.Cu"
		)
		(hatch none 0.5)
		(connect_pads
			(clearance 0)
		)
		(min_thickness 0.25)
		(keepout
			(tracks not_allowed)
			(vias allowed)
			(pads allowed)
			(copperpour not_allowed)
			(footprints allowed)
		)
		(placement
			(enabled no)
			(sheetname "")
		)
		(fill yes
			(thermal_gap 0.5)
			(thermal_bridge_width 0.5)
			(island_removal_mode 0)
		)
		(polygon
			(pts
				(arc
					(start 403.859238 -165.410388)
					(mid 402.081238 -165.410388)
					(end 403.859238 -165.410388)
				)
			)
		)
	)
	(zone
		(layers "In1.Cu" "In3.Cu" "In5.Cu" "In7.Cu" "In8.Cu" "In9.Cu" "In10.Cu"
			"In12.Cu" "In14.Cu" "In16.Cu"
		)
		(hatch none 0.5)
		(connect_pads
			(clearance 0)
		)
		(min_thickness 0.25)
		(keepout
			(tracks not_allowed)
			(vias allowed)
			(pads allowed)
			(copperpour not_allowed)
			(footprints allowed)
		)
		(placement
			(enabled no)
			(sheetname "")
		)
		(fill yes
			(thermal_gap 0.5)
			(thermal_bridge_width 0.5)
			(island_removal_mode 0)
		)
		(polygon
			(pts
				(arc
					(start 345.989402 -158.278576)
					(mid 344.211402 -158.278576)
					(end 345.989402 -158.278576)
				)
			)
		)
	)
	(zone
		(layers "In1.Cu" "In3.Cu" "In5.Cu" "In7.Cu" "In8.Cu" "In9.Cu" "In10.Cu"
			"In12.Cu" "In14.Cu" "In16.Cu"
		)
		(hatch none 0.5)
		(connect_pads
			(clearance 0)
		)
		(min_thickness 0.25)
		(keepout
			(tracks not_allowed)
			(vias allowed)
			(pads allowed)
			(copperpour not_allowed)
			(footprints allowed)
		)
		(placement
			(enabled no)
			(sheetname "")
		)
		(fill yes
			(thermal_gap 0.5)
			(thermal_bridge_width 0.5)
			(island_removal_mode 0)
		)
		(polygon
			(pts
				(arc
					(start 72.222614 -174.764954)
					(mid 70.444614 -174.764954)
					(end 72.222614 -174.764954)
				)
			)
		)
	)
	(zone
		(layers "In1.Cu" "In3.Cu" "In5.Cu" "In7.Cu" "In8.Cu" "In9.Cu" "In10.Cu"
			"In12.Cu" "In14.Cu" "In16.Cu"
		)
		(hatch none 0.5)
		(connect_pads
			(clearance 0)
		)
		(min_thickness 0.25)
		(keepout
			(tracks not_allowed)
			(vias allowed)
			(pads allowed)
			(copperpour not_allowed)
			(footprints allowed)
		)
		(placement
			(enabled no)
			(sheetname "")
		)
		(fill yes
			(thermal_gap 0.5)
			(thermal_bridge_width 0.5)
			(island_removal_mode 0)
		)
		(polygon
			(pts
				(arc
					(start 185.725308 -353.283774)
					(mid 183.965088 -353.283774)
					(end 185.725308 -353.283774)
				)
			)
		)
	)
	(zone
		(layers "In1.Cu" "In3.Cu" "In5.Cu" "In7.Cu" "In8.Cu" "In9.Cu" "In10.Cu"
			"In12.Cu" "In14.Cu" "In16.Cu"
		)
		(hatch none 0.5)
		(connect_pads
			(clearance 0)
		)
		(min_thickness 0.25)
		(keepout
			(tracks not_allowed)
			(vias allowed)
			(pads allowed)
			(copperpour not_allowed)
			(footprints allowed)
		)
		(placement
			(enabled no)
			(sheetname "")
		)
		(fill yes
			(thermal_gap 0.5)
			(thermal_bridge_width 0.5)
			(island_removal_mode 0)
		)
		(polygon
			(pts
				(arc
					(start 341.390224 -352.215196)
					(mid 339.612224 -352.215196)
					(end 341.390224 -352.215196)
				)
			)
		)
	)
	(zone
		(layers "In1.Cu" "In3.Cu" "In5.Cu" "In7.Cu" "In8.Cu" "In9.Cu" "In10.Cu"
			"In12.Cu" "In14.Cu" "In16.Cu"
		)
		(hatch none 0.5)
		(connect_pads
			(clearance 0)
		)
		(min_thickness 0.25)
		(keepout
			(tracks not_allowed)
			(vias allowed)
			(pads allowed)
			(copperpour not_allowed)
			(footprints allowed)
		)
		(placement
			(enabled no)
			(sheetname "")
		)
		(fill yes
			(thermal_gap 0.5)
			(thermal_bridge_width 0.5)
			(island_removal_mode 0)
		)
		(polygon
			(pts
				(arc
					(start 131.194048 -155.20416)
					(mid 129.416048 -155.20416)
					(end 131.194048 -155.20416)
				)
			)
		)
	)
	(zone
		(layers "In1.Cu" "In3.Cu" "In5.Cu" "In7.Cu" "In8.Cu" "In9.Cu" "In10.Cu"
			"In12.Cu" "In14.Cu" "In16.Cu"
		)
		(hatch none 0.5)
		(connect_pads
			(clearance 0)
		)
		(min_thickness 0.25)
		(keepout
			(tracks not_allowed)
			(vias allowed)
			(pads allowed)
			(copperpour not_allowed)
			(footprints allowed)
		)
		(placement
			(enabled no)
			(sheetname "")
		)
		(fill yes
			(thermal_gap 0.5)
			(thermal_bridge_width 0.5)
			(island_removal_mode 0)
		)
		(polygon
			(pts
				(arc
					(start 52.311808 -393.292838)
					(mid 52.616608 -393.597638)
					(end 52.921408 -393.292838)
				)
				(arc
					(start 52.921408 -392.429238)
					(mid 52.616608 -392.124438)
					(end 52.311808 -392.429238)
				)
			)
		)
	)
	(zone
		(layers "In1.Cu" "In3.Cu" "In5.Cu" "In7.Cu" "In8.Cu" "In9.Cu" "In10.Cu"
			"In12.Cu" "In14.Cu" "In16.Cu"
		)
		(hatch none 0.5)
		(connect_pads
			(clearance 0)
		)
		(min_thickness 0.25)
		(keepout
			(tracks not_allowed)
			(vias allowed)
			(pads allowed)
			(copperpour not_allowed)
			(footprints allowed)
		)
		(placement
			(enabled no)
			(sheetname "")
		)
		(fill yes
			(thermal_gap 0.5)
			(thermal_bridge_width 0.5)
			(island_removal_mode 0)
		)
		(polygon
			(pts
				(arc
					(start 388.817358 -155.089352)
					(mid 387.039358 -155.089352)
					(end 388.817358 -155.089352)
				)
			)
		)
	)
	(zone
		(layers "In1.Cu" "In3.Cu" "In5.Cu" "In7.Cu" "In8.Cu" "In9.Cu" "In10.Cu"
			"In12.Cu" "In14.Cu" "In16.Cu"
		)
		(hatch none 0.5)
		(connect_pads
			(clearance 0)
		)
		(min_thickness 0.25)
		(keepout
			(tracks not_allowed)
			(vias allowed)
			(pads allowed)
			(copperpour not_allowed)
			(footprints allowed)
		)
		(placement
			(enabled no)
			(sheetname "")
		)
		(fill yes
			(thermal_gap 0.5)
			(thermal_bridge_width 0.5)
			(island_removal_mode 0)
		)
		(polygon
			(pts
				(arc
					(start 85.773006 -349.531432)
					(mid 83.995006 -349.531432)
					(end 85.773006 -349.531432)
				)
			)
		)
	)
	(zone
		(layers "In1.Cu" "In3.Cu" "In5.Cu" "In7.Cu" "In8.Cu" "In9.Cu" "In10.Cu"
			"In12.Cu" "In14.Cu" "In16.Cu"
		)
		(hatch none 0.5)
		(connect_pads
			(clearance 0)
		)
		(min_thickness 0.25)
		(keepout
			(tracks not_allowed)
			(vias allowed)
			(pads allowed)
			(copperpour not_allowed)
			(footprints allowed)
		)
		(placement
			(enabled no)
			(sheetname "")
		)
		(fill yes
			(thermal_gap 0.5)
			(thermal_bridge_width 0.5)
			(island_removal_mode 0)
		)
		(polygon
			(pts
				(arc
					(start 404.993856 -168.082214)
					(mid 403.215856 -168.082214)
					(end 404.993856 -168.082214)
				)
			)
		)
	)
	(zone
		(layers "In1.Cu" "In3.Cu" "In5.Cu" "In7.Cu" "In8.Cu" "In9.Cu" "In10.Cu"
			"In12.Cu" "In14.Cu" "In16.Cu"
		)
		(hatch none 0.5)
		(connect_pads
			(clearance 0)
		)
		(min_thickness 0.25)
		(keepout
			(tracks not_allowed)
			(vias allowed)
			(pads allowed)
			(copperpour not_allowed)
			(footprints allowed)
		)
		(placement
			(enabled no)
			(sheetname "")
		)
		(fill yes
			(thermal_gap 0.5)
			(thermal_bridge_width 0.5)
			(island_removal_mode 0)
		)
		(polygon
			(pts
				(arc
					(start 344.905838 -157.600396)
					(mid 343.127838 -157.600396)
					(end 344.905838 -157.600396)
				)
			)
		)
	)
	(zone
		(layers "In1.Cu" "In3.Cu" "In5.Cu" "In7.Cu" "In8.Cu" "In9.Cu" "In10.Cu"
			"In12.Cu" "In14.Cu" "In16.Cu"
		)
		(hatch none 0.5)
		(connect_pads
			(clearance 0)
		)
		(min_thickness 0.25)
		(keepout
			(tracks not_allowed)
			(vias allowed)
			(pads allowed)
			(copperpour not_allowed)
			(footprints allowed)
		)
		(placement
			(enabled no)
			(sheetname "")
		)
		(fill yes
			(thermal_gap 0.5)
			(thermal_bridge_width 0.5)
			(island_removal_mode 0)
		)
		(polygon
			(pts
				(arc
					(start 200.324974 -30.720538)
					(mid 198.546974 -30.720538)
					(end 200.324974 -30.720538)
				)
			)
		)
	)
	(zone
		(layers "In1.Cu" "In3.Cu" "In5.Cu" "In7.Cu" "In8.Cu" "In9.Cu" "In10.Cu"
			"In12.Cu" "In14.Cu" "In16.Cu"
		)
		(hatch none 0.5)
		(connect_pads
			(clearance 0)
		)
		(min_thickness 0.25)
		(keepout
			(tracks not_allowed)
			(vias allowed)
			(pads allowed)
			(copperpour not_allowed)
			(footprints allowed)
		)
		(placement
			(enabled no)
			(sheetname "")
		)
		(fill yes
			(thermal_gap 0.5)
			(thermal_bridge_width 0.5)
			(island_removal_mode 0)
		)
		(polygon
			(pts
				(arc
					(start 60.711842 -393.292838)
					(mid 61.016642 -393.597638)
					(end 61.321442 -393.292838)
				)
				(arc
					(start 61.321442 -392.429238)
					(mid 61.016642 -392.124438)
					(end 60.711842 -392.429238)
				)
			)
		)
	)
	(zone
		(layers "In1.Cu" "In3.Cu" "In5.Cu" "In7.Cu" "In8.Cu" "In9.Cu" "In10.Cu"
			"In12.Cu" "In14.Cu" "In16.Cu"
		)
		(hatch none 0.5)
		(connect_pads
			(clearance 0)
		)
		(min_thickness 0.25)
		(keepout
			(tracks not_allowed)
			(vias allowed)
			(pads allowed)
			(copperpour not_allowed)
			(footprints allowed)
		)
		(placement
			(enabled no)
			(sheetname "")
		)
		(fill yes
			(thermal_gap 0.5)
			(thermal_bridge_width 0.5)
			(island_removal_mode 0)
		)
		(polygon
			(pts
				(arc
					(start 99.2632 -180.704744)
					(mid 97.50298 -180.704744)
					(end 99.2632 -180.704744)
				)
			)
		)
	)
	(zone
		(layers "In1.Cu" "In3.Cu" "In5.Cu" "In7.Cu" "In8.Cu" "In9.Cu" "In10.Cu"
			"In12.Cu" "In14.Cu" "In16.Cu"
		)
		(hatch none 0.5)
		(connect_pads
			(clearance 0)
		)
		(min_thickness 0.25)
		(keepout
			(tracks not_allowed)
			(vias allowed)
			(pads allowed)
			(copperpour not_allowed)
			(footprints allowed)
		)
		(placement
			(enabled no)
			(sheetname "")
		)
		(fill yes
			(thermal_gap 0.5)
			(thermal_bridge_width 0.5)
			(island_removal_mode 0)
		)
		(polygon
			(pts
				(arc
					(start 338.575396 -337.834478)
					(mid 336.797396 -337.834478)
					(end 338.575396 -337.834478)
				)
			)
		)
	)
	(zone
		(layers "In1.Cu" "In3.Cu" "In5.Cu" "In7.Cu" "In8.Cu" "In9.Cu" "In10.Cu"
			"In12.Cu" "In14.Cu" "In16.Cu"
		)
		(hatch none 0.5)
		(connect_pads
			(clearance 0)
		)
		(min_thickness 0.25)
		(keepout
			(tracks not_allowed)
			(vias allowed)
			(pads allowed)
			(copperpour not_allowed)
			(footprints allowed)
		)
		(placement
			(enabled no)
			(sheetname "")
		)
		(fill yes
			(thermal_gap 0.5)
			(thermal_bridge_width 0.5)
			(island_removal_mode 0)
		)
		(polygon
			(pts
				(arc
					(start 280.022046 -348.782132)
					(mid 278.244046 -348.782132)
					(end 280.022046 -348.782132)
				)
			)
		)
	)
	(zone
		(layers "In1.Cu" "In3.Cu" "In5.Cu" "In7.Cu" "In8.Cu" "In9.Cu" "In10.Cu"
			"In12.Cu" "In14.Cu" "In16.Cu"
		)
		(hatch none 0.5)
		(connect_pads
			(clearance 0)
		)
		(min_thickness 0.25)
		(keepout
			(tracks not_allowed)
			(vias allowed)
			(pads allowed)
			(copperpour not_allowed)
			(footprints allowed)
		)
		(placement
			(enabled no)
			(sheetname "")
		)
		(fill yes
			(thermal_gap 0.5)
			(thermal_bridge_width 0.5)
			(island_removal_mode 0)
		)
		(polygon
			(pts
				(arc
					(start 71.13905 -174.823374)
					(mid 69.36105 -174.823374)
					(end 71.13905 -174.823374)
				)
			)
		)
	)
	(zone
		(layers "In1.Cu" "In3.Cu" "In5.Cu" "In7.Cu" "In8.Cu" "In9.Cu" "In10.Cu"
			"In12.Cu" "In14.Cu" "In16.Cu"
		)
		(hatch none 0.5)
		(connect_pads
			(clearance 0)
		)
		(min_thickness 0.25)
		(keepout
			(tracks not_allowed)
			(vias allowed)
			(pads allowed)
			(copperpour not_allowed)
			(footprints allowed)
		)
		(placement
			(enabled no)
			(sheetname "")
		)
		(fill yes
			(thermal_gap 0.5)
			(thermal_bridge_width 0.5)
			(island_removal_mode 0)
		)
		(polygon
			(pts
				(arc
					(start 32.667194 -349.904558)
					(mid 30.889194 -349.904558)
					(end 32.667194 -349.904558)
				)
			)
		)
	)
	(zone
		(layers "In1.Cu" "In3.Cu" "In5.Cu" "In7.Cu" "In8.Cu" "In9.Cu" "In10.Cu"
			"In12.Cu" "In14.Cu" "In16.Cu"
		)
		(hatch none 0.5)
		(connect_pads
			(clearance 0)
		)
		(min_thickness 0.25)
		(keepout
			(tracks not_allowed)
			(vias allowed)
			(pads allowed)
			(copperpour not_allowed)
			(footprints allowed)
		)
		(placement
			(enabled no)
			(sheetname "")
		)
		(fill yes
			(thermal_gap 0.5)
			(thermal_bridge_width 0.5)
			(island_removal_mode 0)
		)
		(polygon
			(pts
				(arc
					(start 71.13905 -175.559974)
					(mid 69.36105 -175.559974)
					(end 71.13905 -175.559974)
				)
			)
		)
	)
	(zone
		(layers "In1.Cu" "In3.Cu" "In5.Cu" "In7.Cu" "In8.Cu" "In9.Cu" "In10.Cu"
			"In12.Cu" "In14.Cu" "In16.Cu"
		)
		(hatch none 0.5)
		(connect_pads
			(clearance 0)
		)
		(min_thickness 0.25)
		(keepout
			(tracks not_allowed)
			(vias allowed)
			(pads allowed)
			(copperpour not_allowed)
			(footprints allowed)
		)
		(placement
			(enabled no)
			(sheetname "")
		)
		(fill yes
			(thermal_gap 0.5)
			(thermal_bridge_width 0.5)
			(island_removal_mode 0)
		)
		(polygon
			(pts
				(arc
					(start 362.050838 -175.349916)
					(mid 360.272838 -175.349916)
					(end 362.050838 -175.349916)
				)
			)
		)
	)
	(zone
		(layers "In1.Cu" "In3.Cu" "In5.Cu" "In7.Cu" "In8.Cu" "In9.Cu" "In10.Cu"
			"In12.Cu" "In14.Cu" "In16.Cu"
		)
		(hatch none 0.5)
		(connect_pads
			(clearance 0)
		)
		(min_thickness 0.25)
		(keepout
			(tracks not_allowed)
			(vias allowed)
			(pads allowed)
			(copperpour not_allowed)
			(footprints allowed)
		)
		(placement
			(enabled no)
			(sheetname "")
		)
		(fill yes
			(thermal_gap 0.5)
			(thermal_bridge_width 0.5)
			(island_removal_mode 0)
		)
		(polygon
			(pts
				(arc
					(start 107.87507 -341.804244)
					(mid 106.09707 -341.804244)
					(end 107.87507 -341.804244)
				)
			)
		)
	)
	(zone
		(layers "In1.Cu" "In3.Cu" "In5.Cu" "In7.Cu" "In8.Cu" "In9.Cu" "In10.Cu"
			"In12.Cu" "In14.Cu" "In16.Cu"
		)
		(hatch none 0.5)
		(connect_pads
			(clearance 0)
		)
		(min_thickness 0.25)
		(keepout
			(tracks not_allowed)
			(vias allowed)
			(pads allowed)
			(copperpour not_allowed)
			(footprints allowed)
		)
		(placement
			(enabled no)
			(sheetname "")
		)
		(fill yes
			(thermal_gap 0.5)
			(thermal_bridge_width 0.5)
			(island_removal_mode 0)
		)
		(polygon
			(pts
				(arc
					(start 200.645014 -30.133798)
					(mid 198.867014 -30.133798)
					(end 200.645014 -30.133798)
				)
			)
		)
	)
	(zone
		(layers "In1.Cu" "In3.Cu" "In5.Cu" "In7.Cu" "In8.Cu" "In9.Cu" "In10.Cu"
			"In12.Cu" "In14.Cu" "In16.Cu"
		)
		(hatch none 0.5)
		(connect_pads
			(clearance 0)
		)
		(min_thickness 0.25)
		(keepout
			(tracks not_allowed)
			(vias allowed)
			(pads allowed)
			(copperpour not_allowed)
			(footprints allowed)
		)
		(placement
			(enabled no)
			(sheetname "")
		)
		(fill yes
			(thermal_gap 0.5)
			(thermal_bridge_width 0.5)
			(island_removal_mode 0)
		)
		(polygon
			(pts
				(arc
					(start 193.350134 -16.416528)
					(mid 191.572134 -16.416528)
					(end 193.350134 -16.416528)
				)
			)
		)
	)
	(zone
		(layers "In1.Cu" "In3.Cu" "In5.Cu" "In7.Cu" "In8.Cu" "In9.Cu" "In10.Cu"
			"In12.Cu" "In14.Cu" "In16.Cu"
		)
		(hatch none 0.5)
		(connect_pads
			(clearance 0)
		)
		(min_thickness 0.25)
		(keepout
			(tracks not_allowed)
			(vias allowed)
			(pads allowed)
			(copperpour not_allowed)
			(footprints allowed)
		)
		(placement
			(enabled no)
			(sheetname "")
		)
		(fill yes
			(thermal_gap 0.5)
			(thermal_bridge_width 0.5)
			(island_removal_mode 0)
		)
		(polygon
			(pts
				(arc
					(start 90.872056 -345.261184)
					(mid 89.094056 -345.261184)
					(end 90.872056 -345.261184)
				)
			)
		)
	)
	(zone
		(layers "In1.Cu" "In3.Cu" "In5.Cu" "In7.Cu" "In8.Cu" "In9.Cu" "In10.Cu"
			"In12.Cu" "In14.Cu" "In16.Cu"
		)
		(hatch none 0.5)
		(connect_pads
			(clearance 0)
		)
		(min_thickness 0.25)
		(keepout
			(tracks not_allowed)
			(vias allowed)
			(pads allowed)
			(copperpour not_allowed)
			(footprints allowed)
		)
		(placement
			(enabled no)
			(sheetname "")
		)
		(fill yes
			(thermal_gap 0.5)
			(thermal_bridge_width 0.5)
			(island_removal_mode 0)
		)
		(polygon
			(pts
				(arc
					(start 194.051936 -353.309174)
					(mid 192.291716 -353.309174)
					(end 194.051936 -353.309174)
				)
			)
		)
	)
	(zone
		(layers "In1.Cu" "In3.Cu" "In5.Cu" "In7.Cu" "In8.Cu" "In9.Cu" "In10.Cu"
			"In12.Cu" "In14.Cu" "In16.Cu"
		)
		(hatch none 0.5)
		(connect_pads
			(clearance 0)
		)
		(min_thickness 0.25)
		(keepout
			(tracks not_allowed)
			(vias allowed)
			(pads allowed)
			(copperpour not_allowed)
			(footprints allowed)
		)
		(placement
			(enabled no)
			(sheetname "")
		)
		(fill yes
			(thermal_gap 0.5)
			(thermal_bridge_width 0.5)
			(island_removal_mode 0)
		)
		(polygon
			(pts
				(arc
					(start 248.714514 -40.94988)
					(mid 246.936514 -40.94988)
					(end 248.714514 -40.94988)
				)
			)
		)
	)
	(zone
		(layers "In1.Cu" "In3.Cu" "In5.Cu" "In7.Cu" "In8.Cu" "In9.Cu" "In10.Cu"
			"In12.Cu" "In14.Cu" "In16.Cu"
		)
		(hatch none 0.5)
		(connect_pads
			(clearance 0)
		)
		(min_thickness 0.25)
		(keepout
			(tracks not_allowed)
			(vias allowed)
			(pads allowed)
			(copperpour not_allowed)
			(footprints allowed)
		)
		(placement
			(enabled no)
			(sheetname "")
		)
		(fill yes
			(thermal_gap 0.5)
			(thermal_bridge_width 0.5)
			(island_removal_mode 0)
		)
		(polygon
			(pts
				(arc
					(start 340.628224 -352.215196)
					(mid 338.850224 -352.215196)
					(end 340.628224 -352.215196)
				)
			)
		)
	)
	(zone
		(layers "In1.Cu" "In3.Cu" "In5.Cu" "In7.Cu" "In8.Cu" "In9.Cu" "In10.Cu"
			"In12.Cu" "In14.Cu" "In16.Cu"
		)
		(hatch none 0.5)
		(connect_pads
			(clearance 0)
		)
		(min_thickness 0.25)
		(keepout
			(tracks not_allowed)
			(vias allowed)
			(pads allowed)
			(copperpour not_allowed)
			(footprints allowed)
		)
		(placement
			(enabled no)
			(sheetname "")
		)
		(fill yes
			(thermal_gap 0.5)
			(thermal_bridge_width 0.5)
			(island_removal_mode 0)
		)
		(polygon
			(pts
				(arc
					(start 83.111086 -350.393)
					(mid 81.333086 -350.393)
					(end 83.111086 -350.393)
				)
			)
		)
	)
	(zone
		(layers "In1.Cu" "In3.Cu" "In5.Cu" "In7.Cu" "In8.Cu" "In9.Cu" "In10.Cu"
			"In12.Cu" "In14.Cu" "In16.Cu"
		)
		(hatch none 0.5)
		(connect_pads
			(clearance 0)
		)
		(min_thickness 0.25)
		(keepout
			(tracks not_allowed)
			(vias allowed)
			(pads allowed)
			(copperpour not_allowed)
			(footprints allowed)
		)
		(placement
			(enabled no)
			(sheetname "")
		)
		(fill yes
			(thermal_gap 0.5)
			(thermal_bridge_width 0.5)
			(island_removal_mode 0)
		)
		(polygon
			(pts
				(arc
					(start 65.941194 -349.904558)
					(mid 64.163194 -349.904558)
					(end 65.941194 -349.904558)
				)
			)
		)
	)
	(zone
		(layers "In1.Cu" "In3.Cu" "In5.Cu" "In7.Cu" "In8.Cu" "In9.Cu" "In10.Cu"
			"In12.Cu" "In14.Cu" "In16.Cu"
		)
		(hatch none 0.5)
		(connect_pads
			(clearance 0)
		)
		(min_thickness 0.25)
		(keepout
			(tracks not_allowed)
			(vias allowed)
			(pads allowed)
			(copperpour not_allowed)
			(footprints allowed)
		)
		(placement
			(enabled no)
			(sheetname "")
		)
		(fill yes
			(thermal_gap 0.5)
			(thermal_bridge_width 0.5)
			(island_removal_mode 0)
		)
		(polygon
			(pts
				(arc
					(start 63.111634 -393.292838)
					(mid 63.416434 -393.597638)
					(end 63.721234 -393.292838)
				)
				(arc
					(start 63.721234 -392.429238)
					(mid 63.416434 -392.124438)
					(end 63.111634 -392.429238)
				)
			)
		)
	)
	(zone
		(layers "In1.Cu" "In3.Cu" "In5.Cu" "In7.Cu" "In8.Cu" "In9.Cu" "In10.Cu"
			"In12.Cu" "In14.Cu" "In16.Cu"
		)
		(hatch none 0.5)
		(connect_pads
			(clearance 0)
		)
		(min_thickness 0.25)
		(keepout
			(tracks not_allowed)
			(vias allowed)
			(pads allowed)
			(copperpour not_allowed)
			(footprints allowed)
		)
		(placement
			(enabled no)
			(sheetname "")
		)
		(fill yes
			(thermal_gap 0.5)
			(thermal_bridge_width 0.5)
			(island_removal_mode 0)
		)
		(polygon
			(pts
				(arc
					(start 65.39103 -350.318578)
					(mid 63.61303 -350.318578)
					(end 65.39103 -350.318578)
				)
			)
		)
	)
	(zone
		(layers "In1.Cu" "In3.Cu" "In5.Cu" "In7.Cu" "In8.Cu" "In9.Cu" "In10.Cu"
			"In12.Cu" "In14.Cu" "In16.Cu"
		)
		(hatch none 0.5)
		(connect_pads
			(clearance 0)
		)
		(min_thickness 0.25)
		(keepout
			(tracks not_allowed)
			(vias allowed)
			(pads allowed)
			(copperpour not_allowed)
			(footprints allowed)
		)
		(placement
			(enabled no)
			(sheetname "")
		)
		(fill yes
			(thermal_gap 0.5)
			(thermal_bridge_width 0.5)
			(island_removal_mode 0)
		)
		(polygon
			(pts
				(arc
					(start 65.8368 -166.94023)
					(mid 64.07658 -166.94023)
					(end 65.8368 -166.94023)
				)
			)
		)
	)
	(zone
		(layers "In1.Cu" "In3.Cu" "In5.Cu" "In7.Cu" "In8.Cu" "In9.Cu" "In10.Cu"
			"In12.Cu" "In14.Cu" "In16.Cu"
		)
		(hatch none 0.5)
		(connect_pads
			(clearance 0)
		)
		(min_thickness 0.25)
		(keepout
			(tracks not_allowed)
			(vias allowed)
			(pads allowed)
			(copperpour not_allowed)
			(footprints allowed)
		)
		(placement
			(enabled no)
			(sheetname "")
		)
		(fill yes
			(thermal_gap 0.5)
			(thermal_bridge_width 0.5)
			(island_removal_mode 0)
		)
		(polygon
			(pts
				(arc
					(start 365.311944 -422.692576)
					(mid 365.326823 -422.728497)
					(end 365.362744 -422.743376)
				)
				(arc
					(start 370.261388 -422.743376)
					(mid 370.297309 -422.728497)
					(end 370.312188 -422.692576)
				)
				(xy 370.312188 -421.18026) (xy 370.116354 -421.18026) (xy 370.116354 -420.7383) (xy 370.312188 -420.7383)
				(arc
					(start 370.312188 -415.898584)
					(mid 370.297309 -415.862663)
					(end 370.261388 -415.847784)
				)
				(arc
					(start 365.362744 -415.847784)
					(mid 365.326823 -415.862663)
					(end 365.311944 -415.898584)
				)
			)
		)
	)
	(zone
		(layers "In1.Cu" "In3.Cu" "In5.Cu" "In7.Cu" "In8.Cu" "In9.Cu" "In10.Cu"
			"In12.Cu" "In14.Cu" "In16.Cu"
		)
		(hatch none 0.5)
		(connect_pads
			(clearance 0)
		)
		(min_thickness 0.25)
		(keepout
			(tracks not_allowed)
			(vias allowed)
			(pads allowed)
			(copperpour not_allowed)
			(footprints allowed)
		)
		(placement
			(enabled no)
			(sheetname "")
		)
		(fill yes
			(thermal_gap 0.5)
			(thermal_bridge_width 0.5)
			(island_removal_mode 0)
		)
		(polygon
			(pts
				(arc
					(start 245.407942 -43.246802)
					(mid 243.629942 -43.246802)
					(end 245.407942 -43.246802)
				)
			)
		)
	)
	(zone
		(layers "In1.Cu" "In3.Cu" "In5.Cu" "In7.Cu" "In8.Cu" "In9.Cu" "In10.Cu"
			"In12.Cu" "In14.Cu" "In16.Cu"
		)
		(hatch none 0.5)
		(connect_pads
			(clearance 0)
		)
		(min_thickness 0.25)
		(keepout
			(tracks not_allowed)
			(vias allowed)
			(pads allowed)
			(copperpour not_allowed)
			(footprints allowed)
		)
		(placement
			(enabled no)
			(sheetname "")
		)
		(fill yes
			(thermal_gap 0.5)
			(thermal_bridge_width 0.5)
			(island_removal_mode 0)
		)
		(polygon
			(pts
				(arc
					(start 436.358538 -361.496102)
					(mid 434.580538 -361.496102)
					(end 436.358538 -361.496102)
				)
			)
		)
	)
	(zone
		(layers "In1.Cu" "In3.Cu" "In5.Cu" "In7.Cu" "In8.Cu" "In9.Cu" "In10.Cu"
			"In12.Cu" "In14.Cu" "In16.Cu"
		)
		(hatch none 0.5)
		(connect_pads
			(clearance 0)
		)
		(min_thickness 0.25)
		(keepout
			(tracks not_allowed)
			(vias allowed)
			(pads allowed)
			(copperpour not_allowed)
			(footprints allowed)
		)
		(placement
			(enabled no)
			(sheetname "")
		)
		(fill yes
			(thermal_gap 0.5)
			(thermal_bridge_width 0.5)
			(island_removal_mode 0)
		)
		(polygon
			(pts
				(arc
					(start 370.216684 -165.19398)
					(mid 368.438684 -165.19398)
					(end 370.216684 -165.19398)
				)
			)
		)
	)
	(zone
		(layers "In1.Cu" "In3.Cu" "In5.Cu" "In7.Cu" "In8.Cu" "In9.Cu" "In10.Cu"
			"In12.Cu" "In14.Cu" "In16.Cu"
		)
		(hatch none 0.5)
		(connect_pads
			(clearance 0)
		)
		(min_thickness 0.25)
		(keepout
			(tracks not_allowed)
			(vias allowed)
			(pads allowed)
			(copperpour not_allowed)
			(footprints allowed)
		)
		(placement
			(enabled no)
			(sheetname "")
		)
		(fill yes
			(thermal_gap 0.5)
			(thermal_bridge_width 0.5)
			(island_removal_mode 0)
		)
		(polygon
			(pts
				(arc
					(start 131.194048 -155.94076)
					(mid 129.416048 -155.94076)
					(end 131.194048 -155.94076)
				)
			)
		)
	)
	(zone
		(layers "In1.Cu" "In3.Cu" "In5.Cu" "In7.Cu" "In8.Cu" "In9.Cu" "In10.Cu"
			"In12.Cu" "In14.Cu" "In16.Cu"
		)
		(hatch none 0.5)
		(connect_pads
			(clearance 0)
		)
		(min_thickness 0.25)
		(keepout
			(tracks not_allowed)
			(vias allowed)
			(pads allowed)
			(copperpour not_allowed)
			(footprints allowed)
		)
		(placement
			(enabled no)
			(sheetname "")
		)
		(fill yes
			(thermal_gap 0.5)
			(thermal_bridge_width 0.5)
			(island_removal_mode 0)
		)
		(polygon
			(pts
				(arc
					(start 87.85987 -180.610002)
					(mid 86.08187 -180.610002)
					(end 87.85987 -180.610002)
				)
			)
		)
	)
	(zone
		(layers "In1.Cu" "In3.Cu" "In5.Cu" "In7.Cu" "In8.Cu" "In9.Cu" "In10.Cu"
			"In12.Cu" "In14.Cu" "In16.Cu"
		)
		(hatch none 0.5)
		(connect_pads
			(clearance 0)
		)
		(min_thickness 0.25)
		(keepout
			(tracks not_allowed)
			(vias allowed)
			(pads allowed)
			(copperpour not_allowed)
			(footprints allowed)
		)
		(placement
			(enabled no)
			(sheetname "")
		)
		(fill yes
			(thermal_gap 0.5)
			(thermal_bridge_width 0.5)
			(island_removal_mode 0)
		)
		(polygon
			(pts
				(arc
					(start 88.693244 -336.966814)
					(mid 86.933024 -336.966814)
					(end 88.693244 -336.966814)
				)
			)
		)
	)
	(zone
		(layers "In1.Cu" "In3.Cu" "In5.Cu" "In7.Cu" "In8.Cu" "In9.Cu" "In10.Cu"
			"In12.Cu" "In14.Cu" "In16.Cu"
		)
		(hatch none 0.5)
		(connect_pads
			(clearance 0)
		)
		(min_thickness 0.25)
		(keepout
			(tracks not_allowed)
			(vias allowed)
			(pads allowed)
			(copperpour not_allowed)
			(footprints allowed)
		)
		(placement
			(enabled no)
			(sheetname "")
		)
		(fill yes
			(thermal_gap 0.5)
			(thermal_bridge_width 0.5)
			(island_removal_mode 0)
		)
		(polygon
			(pts
				(arc
					(start 184.490868 -353.283774)
					(mid 182.730648 -353.283774)
					(end 184.490868 -353.283774)
				)
			)
		)
	)
	(zone
		(layers "In1.Cu" "In3.Cu" "In5.Cu" "In7.Cu" "In8.Cu" "In9.Cu" "In10.Cu"
			"In12.Cu" "In14.Cu" "In16.Cu"
		)
		(hatch none 0.5)
		(connect_pads
			(clearance 0)
		)
		(min_thickness 0.25)
		(keepout
			(tracks not_allowed)
			(vias allowed)
			(pads allowed)
			(copperpour not_allowed)
			(footprints allowed)
		)
		(placement
			(enabled no)
			(sheetname "")
		)
		(fill yes
			(thermal_gap 0.5)
			(thermal_bridge_width 0.5)
			(island_removal_mode 0)
		)
		(polygon
			(pts
				(arc
					(start 368.268504 -163.89858)
					(mid 366.490504 -163.89858)
					(end 368.268504 -163.89858)
				)
			)
		)
	)
	(zone
		(layers "In1.Cu" "In3.Cu" "In5.Cu" "In7.Cu" "In8.Cu" "In9.Cu" "In10.Cu"
			"In12.Cu" "In14.Cu" "In16.Cu"
		)
		(hatch none 0.5)
		(connect_pads
			(clearance 0)
		)
		(min_thickness 0.25)
		(keepout
			(tracks not_allowed)
			(vias allowed)
			(pads allowed)
			(copperpour not_allowed)
			(footprints allowed)
		)
		(placement
			(enabled no)
			(sheetname "")
		)
		(fill yes
			(thermal_gap 0.5)
			(thermal_bridge_width 0.5)
			(island_removal_mode 0)
		)
		(polygon
			(pts
				(arc
					(start 437.120538 -360.734102)
					(mid 435.342538 -360.734102)
					(end 437.120538 -360.734102)
				)
			)
		)
	)
	(zone
		(layers "In1.Cu" "In3.Cu" "In5.Cu" "In7.Cu" "In8.Cu" "In9.Cu" "In10.Cu"
			"In12.Cu" "In14.Cu" "In16.Cu"
		)
		(hatch none 0.5)
		(connect_pads
			(clearance 0)
		)
		(min_thickness 0.25)
		(keepout
			(tracks not_allowed)
			(vias allowed)
			(pads allowed)
			(copperpour not_allowed)
			(footprints allowed)
		)
		(placement
			(enabled no)
			(sheetname "")
		)
		(fill yes
			(thermal_gap 0.5)
			(thermal_bridge_width 0.5)
			(island_removal_mode 0)
		)
		(polygon
			(pts
				(arc
					(start 65.21958 -166.94023)
					(mid 63.45936 -166.94023)
					(end 65.21958 -166.94023)
				)
			)
		)
	)
	(zone
		(layers "In1.Cu" "In3.Cu" "In5.Cu" "In7.Cu" "In8.Cu" "In9.Cu" "In10.Cu"
			"In12.Cu" "In14.Cu" "In16.Cu"
		)
		(hatch none 0.5)
		(connect_pads
			(clearance 0)
		)
		(min_thickness 0.25)
		(keepout
			(tracks not_allowed)
			(vias allowed)
			(pads allowed)
			(copperpour not_allowed)
			(footprints allowed)
		)
		(placement
			(enabled no)
			(sheetname "")
		)
		(fill yes
			(thermal_gap 0.5)
			(thermal_bridge_width 0.5)
			(island_removal_mode 0)
		)
		(polygon
			(pts
				(arc
					(start 64.468248 -167.68572)
					(mid 62.690248 -167.68572)
					(end 64.468248 -167.68572)
				)
			)
		)
	)
	(zone
		(layers "In1.Cu" "In3.Cu" "In5.Cu" "In7.Cu" "In8.Cu" "In9.Cu" "In10.Cu"
			"In12.Cu" "In14.Cu" "In16.Cu"
		)
		(hatch none 0.5)
		(connect_pads
			(clearance 0)
		)
		(min_thickness 0.25)
		(keepout
			(tracks not_allowed)
			(vias allowed)
			(pads allowed)
			(copperpour not_allowed)
			(footprints allowed)
		)
		(placement
			(enabled no)
			(sheetname "")
		)
		(fill yes
			(thermal_gap 0.5)
			(thermal_bridge_width 0.5)
			(island_removal_mode 0)
		)
		(polygon
			(pts
				(arc
					(start 85.78342 -348.15272)
					(mid 84.00542 -348.15272)
					(end 85.78342 -348.15272)
				)
			)
		)
	)
	(zone
		(layers "In1.Cu" "In3.Cu" "In5.Cu" "In7.Cu" "In8.Cu" "In9.Cu" "In10.Cu"
			"In12.Cu" "In14.Cu" "In16.Cu"
		)
		(hatch none 0.5)
		(connect_pads
			(clearance 0)
		)
		(min_thickness 0.25)
		(keepout
			(tracks not_allowed)
			(vias allowed)
			(pads allowed)
			(copperpour not_allowed)
			(footprints allowed)
		)
		(placement
			(enabled no)
			(sheetname "")
		)
		(fill yes
			(thermal_gap 0.5)
			(thermal_bridge_width 0.5)
			(island_removal_mode 0)
		)
		(polygon
			(pts
				(arc
					(start 74.450194 -337.421474)
					(mid 72.672194 -337.421474)
					(end 74.450194 -337.421474)
				)
			)
		)
	)
	(zone
		(layers "In1.Cu" "In3.Cu" "In5.Cu" "In7.Cu" "In8.Cu" "In9.Cu" "In10.Cu"
			"In12.Cu" "In14.Cu" "In16.Cu"
		)
		(hatch none 0.5)
		(connect_pads
			(clearance 0)
		)
		(min_thickness 0.25)
		(keepout
			(tracks not_allowed)
			(vias allowed)
			(pads allowed)
			(copperpour not_allowed)
			(footprints allowed)
		)
		(placement
			(enabled no)
			(sheetname "")
		)
		(fill yes
			(thermal_gap 0.5)
			(thermal_bridge_width 0.5)
			(island_removal_mode 0)
		)
		(polygon
			(pts
				(arc
					(start 368.933984 -163.89858)
					(mid 367.155984 -163.89858)
					(end 368.933984 -163.89858)
				)
			)
		)
	)
	(zone
		(layers "In1.Cu" "In3.Cu" "In5.Cu" "In7.Cu" "In8.Cu" "In9.Cu" "In10.Cu"
			"In12.Cu" "In14.Cu" "In16.Cu"
		)
		(hatch none 0.5)
		(connect_pads
			(clearance 0)
		)
		(min_thickness 0.25)
		(keepout
			(tracks not_allowed)
			(vias allowed)
			(pads allowed)
			(copperpour not_allowed)
			(footprints allowed)
		)
		(placement
			(enabled no)
			(sheetname "")
		)
		(fill yes
			(thermal_gap 0.5)
			(thermal_bridge_width 0.5)
			(island_removal_mode 0)
		)
		(polygon
			(pts
				(arc
					(start 89.19845 -163.447476)
					(mid 87.42045 -163.447476)
					(end 89.19845 -163.447476)
				)
			)
		)
	)
	(zone
		(layers "In1.Cu" "In3.Cu" "In5.Cu" "In7.Cu" "In8.Cu" "In9.Cu" "In10.Cu"
			"In12.Cu" "In14.Cu" "In16.Cu"
		)
		(hatch none 0.5)
		(connect_pads
			(clearance 0)
		)
		(min_thickness 0.25)
		(keepout
			(tracks not_allowed)
			(vias allowed)
			(pads allowed)
			(copperpour not_allowed)
			(footprints allowed)
		)
		(placement
			(enabled no)
			(sheetname "")
		)
		(fill yes
			(thermal_gap 0.5)
			(thermal_bridge_width 0.5)
			(island_removal_mode 0)
		)
		(polygon
			(pts
				(arc
					(start 48.255174 -348.017338)
					(mid 46.477174 -348.017338)
					(end 48.255174 -348.017338)
				)
			)
		)
	)
	(zone
		(layers "In1.Cu" "In3.Cu" "In5.Cu" "In7.Cu" "In8.Cu" "In9.Cu" "In10.Cu"
			"In12.Cu" "In14.Cu" "In16.Cu"
		)
		(hatch none 0.5)
		(connect_pads
			(clearance 0)
		)
		(min_thickness 0.25)
		(keepout
			(tracks not_allowed)
			(vias allowed)
			(pads allowed)
			(copperpour not_allowed)
			(footprints allowed)
		)
		(placement
			(enabled no)
			(sheetname "")
		)
		(fill yes
			(thermal_gap 0.5)
			(thermal_bridge_width 0.5)
			(island_removal_mode 0)
		)
		(polygon
			(pts
				(arc
					(start 428.244 -353.91725)
					(mid 426.466 -353.91725)
					(end 428.244 -353.91725)
				)
			)
		)
	)
	(zone
		(layers "In1.Cu" "In3.Cu" "In5.Cu" "In7.Cu" "In8.Cu" "In9.Cu" "In10.Cu"
			"In12.Cu" "In14.Cu" "In16.Cu"
		)
		(hatch none 0.5)
		(connect_pads
			(clearance 0)
		)
		(min_thickness 0.25)
		(keepout
			(tracks not_allowed)
			(vias allowed)
			(pads allowed)
			(copperpour not_allowed)
			(footprints allowed)
		)
		(placement
			(enabled no)
			(sheetname "")
		)
		(fill yes
			(thermal_gap 0.5)
			(thermal_bridge_width 0.5)
			(island_removal_mode 0)
		)
		(polygon
			(pts
				(arc
					(start 411.707838 -160.965388)
					(mid 409.929838 -160.965388)
					(end 411.707838 -160.965388)
				)
			)
		)
	)
	(zone
		(layers "In1.Cu" "In3.Cu" "In5.Cu" "In7.Cu" "In8.Cu" "In9.Cu" "In10.Cu"
			"In12.Cu" "In14.Cu" "In16.Cu"
		)
		(hatch none 0.5)
		(connect_pads
			(clearance 0)
		)
		(min_thickness 0.25)
		(keepout
			(tracks not_allowed)
			(vias allowed)
			(pads allowed)
			(copperpour not_allowed)
			(footprints allowed)
		)
		(placement
			(enabled no)
			(sheetname "")
		)
		(fill yes
			(thermal_gap 0.5)
			(thermal_bridge_width 0.5)
			(island_removal_mode 0)
		)
		(polygon
			(pts
				(arc
					(start 89.83345 -163.447476)
					(mid 88.05545 -163.447476)
					(end 89.83345 -163.447476)
				)
			)
		)
	)
	(zone
		(layers "In1.Cu" "In3.Cu" "In5.Cu" "In7.Cu" "In8.Cu" "In9.Cu" "In10.Cu"
			"In12.Cu" "In14.Cu" "In16.Cu"
		)
		(hatch none 0.5)
		(connect_pads
			(clearance 0)
		)
		(min_thickness 0.25)
		(keepout
			(tracks not_allowed)
			(vias allowed)
			(pads allowed)
			(copperpour not_allowed)
			(footprints allowed)
		)
		(placement
			(enabled no)
			(sheetname "")
		)
		(fill yes
			(thermal_gap 0.5)
			(thermal_bridge_width 0.5)
			(island_removal_mode 0)
		)
		(polygon
			(pts
				(arc
					(start 288.52495 -355.279198)
					(mid 286.74695 -355.279198)
					(end 288.52495 -355.279198)
				)
			)
		)
	)
	(zone
		(layers "In1.Cu" "In3.Cu" "In5.Cu" "In7.Cu" "In8.Cu" "In9.Cu" "In10.Cu"
			"In12.Cu" "In14.Cu" "In16.Cu"
		)
		(hatch none 0.5)
		(connect_pads
			(clearance 0)
		)
		(min_thickness 0.25)
		(keepout
			(tracks not_allowed)
			(vias allowed)
			(pads allowed)
			(copperpour not_allowed)
			(footprints allowed)
		)
		(placement
			(enabled no)
			(sheetname "")
		)
		(fill yes
			(thermal_gap 0.5)
			(thermal_bridge_width 0.5)
			(island_removal_mode 0)
		)
		(polygon
			(pts
				(arc
					(start 279.463246 -349.137732)
					(mid 277.685246 -349.137732)
					(end 279.463246 -349.137732)
				)
			)
		)
	)
	(zone
		(layers "In1.Cu" "In3.Cu" "In5.Cu" "In7.Cu" "In8.Cu" "In9.Cu" "In10.Cu"
			"In12.Cu" "In14.Cu" "In16.Cu"
		)
		(hatch none 0.5)
		(connect_pads
			(clearance 0)
		)
		(min_thickness 0.25)
		(keepout
			(tracks not_allowed)
			(vias allowed)
			(pads allowed)
			(copperpour not_allowed)
			(footprints allowed)
		)
		(placement
			(enabled no)
			(sheetname "")
		)
		(fill yes
			(thermal_gap 0.5)
			(thermal_bridge_width 0.5)
			(island_removal_mode 0)
		)
		(polygon
			(pts
				(arc
					(start 91.10853 -164.107876)
					(mid 89.33053 -164.107876)
					(end 91.10853 -164.107876)
				)
			)
		)
	)
	(zone
		(layers "In1.Cu" "In3.Cu" "In5.Cu" "In7.Cu" "In8.Cu" "In9.Cu" "In10.Cu"
			"In12.Cu" "In14.Cu" "In16.Cu"
		)
		(hatch none 0.5)
		(connect_pads
			(clearance 0)
		)
		(min_thickness 0.25)
		(keepout
			(tracks not_allowed)
			(vias allowed)
			(pads allowed)
			(copperpour not_allowed)
			(footprints allowed)
		)
		(placement
			(enabled no)
			(sheetname "")
		)
		(fill yes
			(thermal_gap 0.5)
			(thermal_bridge_width 0.5)
			(island_removal_mode 0)
		)
		(polygon
			(pts
				(arc
					(start 406.337008 -166.605458)
					(mid 404.576788 -166.605458)
					(end 406.337008 -166.605458)
				)
			)
		)
	)
	(zone
		(layers "In1.Cu" "In3.Cu" "In5.Cu" "In7.Cu" "In8.Cu" "In9.Cu" "In10.Cu"
			"In12.Cu" "In14.Cu" "In16.Cu"
		)
		(hatch none 0.5)
		(connect_pads
			(clearance 0)
		)
		(min_thickness 0.25)
		(keepout
			(tracks not_allowed)
			(vias allowed)
			(pads allowed)
			(copperpour not_allowed)
			(footprints allowed)
		)
		(placement
			(enabled no)
			(sheetname "")
		)
		(fill yes
			(thermal_gap 0.5)
			(thermal_bridge_width 0.5)
			(island_removal_mode 0)
		)
		(polygon
			(pts
				(arc
					(start 55.731664 -348.709488)
					(mid 53.971444 -348.709488)
					(end 55.731664 -348.709488)
				)
			)
		)
	)
	(zone
		(layers "In1.Cu" "In3.Cu" "In5.Cu" "In7.Cu" "In8.Cu" "In9.Cu" "In10.Cu"
			"In12.Cu" "In14.Cu" "In16.Cu"
		)
		(hatch none 0.5)
		(connect_pads
			(clearance 0)
		)
		(min_thickness 0.25)
		(keepout
			(tracks not_allowed)
			(vias allowed)
			(pads allowed)
			(copperpour not_allowed)
			(footprints allowed)
		)
		(placement
			(enabled no)
			(sheetname "")
		)
		(fill yes
			(thermal_gap 0.5)
			(thermal_bridge_width 0.5)
			(island_removal_mode 0)
		)
		(polygon
			(pts
				(arc
					(start 49.911762 -393.292838)
					(mid 50.216562 -393.597638)
					(end 50.521362 -393.292838)
				)
				(arc
					(start 50.521362 -392.429238)
					(mid 50.216562 -392.124438)
					(end 49.911762 -392.429238)
				)
			)
		)
	)
	(zone
		(layers "In1.Cu" "In3.Cu" "In5.Cu" "In7.Cu" "In8.Cu" "In9.Cu" "In10.Cu"
			"In12.Cu" "In14.Cu" "In16.Cu"
		)
		(hatch none 0.5)
		(connect_pads
			(clearance 0)
		)
		(min_thickness 0.25)
		(keepout
			(tracks not_allowed)
			(vias allowed)
			(pads allowed)
			(copperpour not_allowed)
			(footprints allowed)
		)
		(placement
			(enabled no)
			(sheetname "")
		)
		(fill yes
			(thermal_gap 0.5)
			(thermal_bridge_width 0.5)
			(island_removal_mode 0)
		)
		(polygon
			(pts
				(arc
					(start 445.055244 -24.741632)
					(mid 443.277244 -24.741632)
					(end 445.055244 -24.741632)
				)
			)
		)
	)
	(zone
		(layers "In1.Cu" "In3.Cu" "In5.Cu" "In7.Cu" "In8.Cu" "In9.Cu" "In10.Cu"
			"In12.Cu" "In14.Cu" "In16.Cu"
		)
		(hatch none 0.5)
		(connect_pads
			(clearance 0)
		)
		(min_thickness 0.25)
		(keepout
			(tracks not_allowed)
			(vias allowed)
			(pads allowed)
			(copperpour not_allowed)
			(footprints allowed)
		)
		(placement
			(enabled no)
			(sheetname "")
		)
		(fill yes
			(thermal_gap 0.5)
			(thermal_bridge_width 0.5)
			(island_removal_mode 0)
		)
		(polygon
			(pts
				(arc
					(start 65.39103 -349.581978)
					(mid 63.61303 -349.581978)
					(end 65.39103 -349.581978)
				)
			)
		)
	)
	(zone
		(layers "In1.Cu" "In3.Cu" "In5.Cu" "In7.Cu" "In8.Cu" "In9.Cu" "In10.Cu"
			"In12.Cu" "In14.Cu" "In16.Cu"
		)
		(hatch none 0.5)
		(connect_pads
			(clearance 0)
		)
		(min_thickness 0.25)
		(keepout
			(tracks not_allowed)
			(vias allowed)
			(pads allowed)
			(copperpour not_allowed)
			(footprints allowed)
		)
		(placement
			(enabled no)
			(sheetname "")
		)
		(fill yes
			(thermal_gap 0.5)
			(thermal_bridge_width 0.5)
			(island_removal_mode 0)
		)
		(polygon
			(pts
				(arc
					(start 347.45676 -339.731858)
					(mid 345.67876 -339.731858)
					(end 347.45676 -339.731858)
				)
			)
		)
	)
	(zone
		(layers "In1.Cu" "In3.Cu" "In5.Cu" "In7.Cu" "In8.Cu" "In9.Cu" "In10.Cu"
			"In12.Cu" "In14.Cu" "In16.Cu"
		)
		(hatch none 0.5)
		(connect_pads
			(clearance 0)
		)
		(min_thickness 0.25)
		(keepout
			(tracks not_allowed)
			(vias allowed)
			(pads allowed)
			(copperpour not_allowed)
			(footprints allowed)
		)
		(placement
			(enabled no)
			(sheetname "")
		)
		(fill yes
			(thermal_gap 0.5)
			(thermal_bridge_width 0.5)
			(island_removal_mode 0)
		)
		(polygon
			(pts
				(arc
					(start 296.608246 -348.782132)
					(mid 294.830246 -348.782132)
					(end 296.608246 -348.782132)
				)
			)
		)
	)
	(zone
		(layers "In1.Cu" "In3.Cu" "In5.Cu" "In7.Cu" "In8.Cu" "In9.Cu" "In10.Cu"
			"In12.Cu" "In14.Cu" "In16.Cu"
		)
		(hatch none 0.5)
		(connect_pads
			(clearance 0)
		)
		(min_thickness 0.25)
		(keepout
			(tracks not_allowed)
			(vias allowed)
			(pads allowed)
			(copperpour not_allowed)
			(footprints allowed)
		)
		(placement
			(enabled no)
			(sheetname "")
		)
		(fill yes
			(thermal_gap 0.5)
			(thermal_bridge_width 0.5)
			(island_removal_mode 0)
		)
		(polygon
			(pts
				(arc
					(start 288.302446 -350.255332)
					(mid 286.524446 -350.255332)
					(end 288.302446 -350.255332)
				)
			)
		)
	)
	(zone
		(layers "In1.Cu" "In3.Cu" "In5.Cu" "In7.Cu" "In8.Cu" "In9.Cu" "In10.Cu"
			"In12.Cu" "In14.Cu" "In16.Cu"
		)
		(hatch none 0.5)
		(connect_pads
			(clearance 0)
		)
		(min_thickness 0.25)
		(keepout
			(tracks not_allowed)
			(vias allowed)
			(pads allowed)
			(copperpour not_allowed)
			(footprints allowed)
		)
		(placement
			(enabled no)
			(sheetname "")
		)
		(fill yes
			(thermal_gap 0.5)
			(thermal_bridge_width 0.5)
			(island_removal_mode 0)
		)
		(polygon
			(pts
				(arc
					(start 201.280014 -30.133798)
					(mid 199.502014 -30.133798)
					(end 201.280014 -30.133798)
				)
			)
		)
	)
	(zone
		(layers "In1.Cu" "In3.Cu" "In5.Cu" "In7.Cu" "In8.Cu" "In9.Cu" "In10.Cu"
			"In12.Cu" "In14.Cu" "In16.Cu"
		)
		(hatch none 0.5)
		(connect_pads
			(clearance 0)
		)
		(min_thickness 0.25)
		(keepout
			(tracks not_allowed)
			(vias allowed)
			(pads allowed)
			(copperpour not_allowed)
			(footprints allowed)
		)
		(placement
			(enabled no)
			(sheetname "")
		)
		(fill yes
			(thermal_gap 0.5)
			(thermal_bridge_width 0.5)
			(island_removal_mode 0)
		)
		(polygon
			(pts
				(arc
					(start 98.538284 -335.582768)
					(mid 96.778064 -335.582768)
					(end 98.538284 -335.582768)
				)
			)
		)
	)
	(zone
		(layers "In1.Cu" "In3.Cu" "In5.Cu" "In7.Cu" "In8.Cu" "In9.Cu" "In10.Cu"
			"In12.Cu" "In14.Cu" "In16.Cu"
		)
		(hatch none 0.5)
		(connect_pads
			(clearance 0)
		)
		(min_thickness 0.25)
		(keepout
			(tracks not_allowed)
			(vias allowed)
			(pads allowed)
			(copperpour not_allowed)
			(footprints allowed)
		)
		(placement
			(enabled no)
			(sheetname "")
		)
		(fill yes
			(thermal_gap 0.5)
			(thermal_bridge_width 0.5)
			(island_removal_mode 0)
		)
		(polygon
			(pts
				(arc
					(start 361.492038 -174.968916)
					(mid 359.714038 -174.968916)
					(end 361.492038 -174.968916)
				)
			)
		)
	)
	(zone
		(layers "In1.Cu" "In3.Cu" "In5.Cu" "In7.Cu" "In8.Cu" "In9.Cu" "In10.Cu"
			"In12.Cu" "In14.Cu" "In16.Cu"
		)
		(hatch none 0.5)
		(connect_pads
			(clearance 0)
		)
		(min_thickness 0.25)
		(keepout
			(tracks not_allowed)
			(vias allowed)
			(pads allowed)
			(copperpour not_allowed)
			(footprints allowed)
		)
		(placement
			(enabled no)
			(sheetname "")
		)
		(fill yes
			(thermal_gap 0.5)
			(thermal_bridge_width 0.5)
			(island_removal_mode 0)
		)
		(polygon
			(pts
				(arc
					(start 186.436254 -354.156264)
					(mid 184.658254 -354.156264)
					(end 186.436254 -354.156264)
				)
			)
		)
	)
	(zone
		(layers "In1.Cu" "In3.Cu" "In5.Cu" "In7.Cu" "In8.Cu" "In9.Cu" "In10.Cu"
			"In12.Cu" "In14.Cu" "In16.Cu"
		)
		(hatch none 0.5)
		(connect_pads
			(clearance 0)
		)
		(min_thickness 0.25)
		(keepout
			(tracks not_allowed)
			(vias allowed)
			(pads allowed)
			(copperpour not_allowed)
			(footprints allowed)
		)
		(placement
			(enabled no)
			(sheetname "")
		)
		(fill yes
			(thermal_gap 0.5)
			(thermal_bridge_width 0.5)
			(island_removal_mode 0)
		)
		(polygon
			(pts
				(arc
					(start 440.28233 -13.043916)
					(mid 438.50433 -13.043916)
					(end 440.28233 -13.043916)
				)
			)
		)
	)
	(zone
		(layers "In1.Cu" "In3.Cu" "In5.Cu" "In7.Cu" "In8.Cu" "In9.Cu" "In10.Cu"
			"In12.Cu" "In14.Cu" "In16.Cu"
		)
		(hatch none 0.5)
		(connect_pads
			(clearance 0)
		)
		(min_thickness 0.25)
		(keepout
			(tracks not_allowed)
			(vias allowed)
			(pads allowed)
			(copperpour not_allowed)
			(footprints allowed)
		)
		(placement
			(enabled no)
			(sheetname "")
		)
		(fill yes
			(thermal_gap 0.5)
			(thermal_bridge_width 0.5)
			(island_removal_mode 0)
		)
		(polygon
			(pts
				(arc
					(start 280.022046 -349.518732)
					(mid 278.244046 -349.518732)
					(end 280.022046 -349.518732)
				)
			)
		)
	)
	(zone
		(layers "In1.Cu" "In3.Cu" "In5.Cu" "In7.Cu" "In8.Cu" "In9.Cu" "In10.Cu"
			"In12.Cu" "In14.Cu" "In16.Cu"
		)
		(hatch none 0.5)
		(connect_pads
			(clearance 0)
		)
		(min_thickness 0.25)
		(keepout
			(tracks not_allowed)
			(vias allowed)
			(pads allowed)
			(copperpour not_allowed)
			(footprints allowed)
		)
		(placement
			(enabled no)
			(sheetname "")
		)
		(fill yes
			(thermal_gap 0.5)
			(thermal_bridge_width 0.5)
			(island_removal_mode 0)
		)
		(polygon
			(pts
				(arc
					(start 413.375856 -163.256214)
					(mid 411.597856 -163.256214)
					(end 413.375856 -163.256214)
				)
			)
		)
	)
	(zone
		(layers "In1.Cu" "In3.Cu" "In5.Cu" "In7.Cu" "In8.Cu" "In9.Cu" "In10.Cu"
			"In12.Cu" "In14.Cu" "In16.Cu"
		)
		(hatch none 0.5)
		(connect_pads
			(clearance 0)
		)
		(min_thickness 0.25)
		(keepout
			(tracks not_allowed)
			(vias allowed)
			(pads allowed)
			(copperpour not_allowed)
			(footprints allowed)
		)
		(placement
			(enabled no)
			(sheetname "")
		)
		(fill yes
			(thermal_gap 0.5)
			(thermal_bridge_width 0.5)
			(island_removal_mode 0)
		)
		(polygon
			(pts
				(arc
					(start 106.225848 -176.92116)
					(mid 104.447848 -176.92116)
					(end 106.225848 -176.92116)
				)
			)
		)
	)
	(zone
		(layers "In1.Cu" "In3.Cu" "In5.Cu" "In7.Cu" "In8.Cu" "In9.Cu" "In10.Cu"
			"In12.Cu" "In14.Cu" "In16.Cu"
		)
		(hatch none 0.5)
		(connect_pads
			(clearance 0)
		)
		(min_thickness 0.25)
		(keepout
			(tracks not_allowed)
			(vias allowed)
			(pads allowed)
			(copperpour not_allowed)
			(footprints allowed)
		)
		(placement
			(enabled no)
			(sheetname "")
		)
		(fill yes
			(thermal_gap 0.5)
			(thermal_bridge_width 0.5)
			(island_removal_mode 0)
		)
		(polygon
			(pts
				(arc
					(start 310.884316 -348.704662)
					(mid 309.124096 -348.704662)
					(end 310.884316 -348.704662)
				)
			)
		)
	)
	(zone
		(layers "In1.Cu" "In3.Cu" "In5.Cu" "In7.Cu" "In8.Cu" "In9.Cu" "In10.Cu"
			"In12.Cu" "In14.Cu" "In16.Cu"
		)
		(hatch none 0.5)
		(connect_pads
			(clearance 0)
		)
		(min_thickness 0.25)
		(keepout
			(tracks not_allowed)
			(vias allowed)
			(pads allowed)
			(copperpour not_allowed)
			(footprints allowed)
		)
		(placement
			(enabled no)
			(sheetname "")
		)
		(fill yes
			(thermal_gap 0.5)
			(thermal_bridge_width 0.5)
			(island_removal_mode 0)
		)
		(polygon
			(pts
				(arc
					(start 99.519994 -338.212684)
					(mid 97.741994 -338.212684)
					(end 99.519994 -338.212684)
				)
			)
		)
	)
	(zone
		(layers "In1.Cu" "In3.Cu" "In5.Cu" "In7.Cu" "In8.Cu" "In9.Cu" "In10.Cu"
			"In12.Cu" "In14.Cu" "In16.Cu"
		)
		(hatch none 0.5)
		(connect_pads
			(clearance 0)
		)
		(min_thickness 0.25)
		(keepout
			(tracks not_allowed)
			(vias allowed)
			(pads allowed)
			(copperpour not_allowed)
			(footprints allowed)
		)
		(placement
			(enabled no)
			(sheetname "")
		)
		(fill yes
			(thermal_gap 0.5)
			(thermal_bridge_width 0.5)
			(island_removal_mode 0)
		)
		(polygon
			(pts
				(arc
					(start 340.628224 -351.453196)
					(mid 338.850224 -351.453196)
					(end 340.628224 -351.453196)
				)
			)
		)
	)
	(zone
		(layers "In1.Cu" "In3.Cu" "In5.Cu" "In7.Cu" "In8.Cu" "In9.Cu" "In10.Cu"
			"In12.Cu" "In14.Cu" "In16.Cu"
		)
		(hatch none 0.5)
		(connect_pads
			(clearance 0)
		)
		(min_thickness 0.25)
		(keepout
			(tracks not_allowed)
			(vias allowed)
			(pads allowed)
			(copperpour not_allowed)
			(footprints allowed)
		)
		(placement
			(enabled no)
			(sheetname "")
		)
		(fill yes
			(thermal_gap 0.5)
			(thermal_bridge_width 0.5)
			(island_removal_mode 0)
		)
		(polygon
			(pts
				(arc
					(start 200.010014 -30.133798)
					(mid 198.232014 -30.133798)
					(end 200.010014 -30.133798)
				)
			)
		)
	)
	(zone
		(layers "In1.Cu" "In3.Cu" "In5.Cu" "In7.Cu" "In8.Cu" "In9.Cu" "In10.Cu"
			"In12.Cu" "In14.Cu" "In16.Cu"
		)
		(hatch none 0.5)
		(connect_pads
			(clearance 0)
		)
		(min_thickness 0.25)
		(keepout
			(tracks not_allowed)
			(vias allowed)
			(pads allowed)
			(copperpour not_allowed)
			(footprints allowed)
		)
		(placement
			(enabled no)
			(sheetname "")
		)
		(fill yes
			(thermal_gap 0.5)
			(thermal_bridge_width 0.5)
			(island_removal_mode 0)
		)
		(polygon
			(pts
				(arc
					(start 312.737246 -349.137732)
					(mid 310.959246 -349.137732)
					(end 312.737246 -349.137732)
				)
			)
		)
	)
	(zone
		(layers "In1.Cu" "In3.Cu" "In5.Cu" "In7.Cu" "In8.Cu" "In9.Cu" "In10.Cu"
			"In12.Cu" "In14.Cu" "In16.Cu"
		)
		(hatch none 0.5)
		(connect_pads
			(clearance 0)
		)
		(min_thickness 0.25)
		(keepout
			(tracks not_allowed)
			(vias allowed)
			(pads allowed)
			(copperpour not_allowed)
			(footprints allowed)
		)
		(placement
			(enabled no)
			(sheetname "")
		)
		(fill yes
			(thermal_gap 0.5)
			(thermal_bridge_width 0.5)
			(island_removal_mode 0)
		)
		(polygon
			(pts
				(arc
					(start 71.69785 -175.204374)
					(mid 69.91985 -175.204374)
					(end 71.69785 -175.204374)
				)
			)
		)
	)
	(zone
		(layers "In1.Cu" "In3.Cu" "In5.Cu" "In7.Cu" "In8.Cu" "In9.Cu" "In10.Cu"
			"In12.Cu" "In14.Cu" "In16.Cu"
		)
		(hatch none 0.5)
		(connect_pads
			(clearance 0)
		)
		(min_thickness 0.25)
		(keepout
			(tracks not_allowed)
			(vias allowed)
			(pads allowed)
			(copperpour not_allowed)
			(footprints allowed)
		)
		(placement
			(enabled no)
			(sheetname "")
		)
		(fill yes
			(thermal_gap 0.5)
			(thermal_bridge_width 0.5)
			(island_removal_mode 0)
		)
		(polygon
			(pts
				(arc
					(start 122.227594 -161.595054)
					(mid 120.449594 -161.595054)
					(end 122.227594 -161.595054)
				)
			)
		)
	)
	(zone
		(layers "In1.Cu" "In3.Cu" "In5.Cu" "In7.Cu" "In8.Cu" "In9.Cu" "In10.Cu"
			"In12.Cu" "In14.Cu" "In16.Cu"
		)
		(hatch none 0.5)
		(connect_pads
			(clearance 0)
		)
		(min_thickness 0.25)
		(keepout
			(tracks not_allowed)
			(vias allowed)
			(pads allowed)
			(copperpour not_allowed)
			(footprints allowed)
		)
		(placement
			(enabled no)
			(sheetname "")
		)
		(fill yes
			(thermal_gap 0.5)
			(thermal_bridge_width 0.5)
			(island_removal_mode 0)
		)
		(polygon
			(pts
				(arc
					(start 451.559676 -16.010382)
					(mid 449.781676 -16.010382)
					(end 451.559676 -16.010382)
				)
			)
		)
	)
	(zone
		(layers "In1.Cu" "In3.Cu" "In5.Cu" "In7.Cu" "In8.Cu" "In9.Cu" "In10.Cu"
			"In12.Cu" "In14.Cu" "In16.Cu"
		)
		(hatch none 0.5)
		(connect_pads
			(clearance 0)
		)
		(min_thickness 0.25)
		(keepout
			(tracks not_allowed)
			(vias allowed)
			(pads allowed)
			(copperpour not_allowed)
			(footprints allowed)
		)
		(placement
			(enabled no)
			(sheetname "")
		)
		(fill yes
			(thermal_gap 0.5)
			(thermal_bridge_width 0.5)
			(island_removal_mode 0)
		)
		(polygon
			(pts
				(arc
					(start 398.013428 -175.182784)
					(mid 396.253208 -175.182784)
					(end 398.013428 -175.182784)
				)
			)
		)
	)
	(zone
		(layers "In1.Cu" "In3.Cu" "In5.Cu" "In7.Cu" "In8.Cu" "In9.Cu" "In10.Cu"
			"In12.Cu" "In14.Cu" "In16.Cu"
		)
		(hatch none 0.5)
		(connect_pads
			(clearance 0)
		)
		(min_thickness 0.25)
		(keepout
			(tracks not_allowed)
			(vias allowed)
			(pads allowed)
			(copperpour not_allowed)
			(footprints allowed)
		)
		(placement
			(enabled no)
			(sheetname "")
		)
		(fill yes
			(thermal_gap 0.5)
			(thermal_bridge_width 0.5)
			(island_removal_mode 0)
		)
		(polygon
			(pts
				(arc
					(start 443.260734 -20.983702)
					(mid 441.482734 -20.983702)
					(end 443.260734 -20.983702)
				)
			)
		)
	)
	(zone
		(layers "In1.Cu" "In3.Cu" "In5.Cu" "In7.Cu" "In8.Cu" "In9.Cu" "In10.Cu"
			"In12.Cu" "In14.Cu" "In16.Cu"
		)
		(hatch none 0.5)
		(connect_pads
			(clearance 0)
		)
		(min_thickness 0.25)
		(keepout
			(tracks not_allowed)
			(vias allowed)
			(pads allowed)
			(copperpour not_allowed)
			(footprints allowed)
		)
		(placement
			(enabled no)
			(sheetname "")
		)
		(fill yes
			(thermal_gap 0.5)
			(thermal_bridge_width 0.5)
			(island_removal_mode 0)
		)
		(polygon
			(pts
				(arc
					(start 353.854258 -341.922862)
					(mid 352.094038 -341.922862)
					(end 353.854258 -341.922862)
				)
			)
		)
	)
	(zone
		(layers "In1.Cu" "In3.Cu" "In5.Cu" "In7.Cu" "In8.Cu" "In9.Cu" "In10.Cu"
			"In12.Cu" "In14.Cu" "In16.Cu"
		)
		(hatch none 0.5)
		(connect_pads
			(clearance 0)
		)
		(min_thickness 0.25)
		(keepout
			(tracks not_allowed)
			(vias allowed)
			(pads allowed)
			(copperpour not_allowed)
			(footprints allowed)
		)
		(placement
			(enabled no)
			(sheetname "")
		)
		(fill yes
			(thermal_gap 0.5)
			(thermal_bridge_width 0.5)
			(island_removal_mode 0)
		)
		(polygon
			(pts
				(arc
					(start 90.874088 -345.96959)
					(mid 89.096088 -345.96959)
					(end 90.874088 -345.96959)
				)
			)
		)
	)
	(zone
		(layers "In1.Cu" "In3.Cu" "In5.Cu" "In7.Cu" "In8.Cu" "In9.Cu" "In10.Cu"
			"In12.Cu" "In14.Cu" "In16.Cu"
		)
		(hatch none 0.5)
		(connect_pads
			(clearance 0)
		)
		(min_thickness 0.25)
		(keepout
			(tracks not_allowed)
			(vias allowed)
			(pads allowed)
			(copperpour not_allowed)
			(footprints allowed)
		)
		(placement
			(enabled no)
			(sheetname "")
		)
		(fill yes
			(thermal_gap 0.5)
			(thermal_bridge_width 0.5)
			(island_removal_mode 0)
		)
		(polygon
			(pts
				(arc
					(start 340.62797 -352.973132)
					(mid 338.84997 -352.973132)
					(end 340.62797 -352.973132)
				)
			)
		)
	)
	(zone
		(layers "In1.Cu" "In3.Cu" "In5.Cu" "In7.Cu" "In8.Cu" "In9.Cu" "In10.Cu"
			"In12.Cu" "In14.Cu" "In16.Cu"
		)
		(hatch none 0.5)
		(connect_pads
			(clearance 0)
		)
		(min_thickness 0.25)
		(keepout
			(tracks not_allowed)
			(vias allowed)
			(pads allowed)
			(copperpour not_allowed)
			(footprints allowed)
		)
		(placement
			(enabled no)
			(sheetname "")
		)
		(fill yes
			(thermal_gap 0.5)
			(thermal_bridge_width 0.5)
			(island_removal_mode 0)
		)
		(polygon
			(pts
				(arc
					(start 65.51168 -393.292838)
					(mid 65.81648 -393.597638)
					(end 66.12128 -393.292838)
				)
				(arc
					(start 66.12128 -392.429238)
					(mid 65.81648 -392.124438)
					(end 65.51168 -392.429238)
				)
			)
		)
	)
	(zone
		(layers "In1.Cu" "In3.Cu" "In5.Cu" "In7.Cu" "In8.Cu" "In9.Cu" "In10.Cu"
			"In12.Cu" "In14.Cu" "In16.Cu"
		)
		(hatch none 0.5)
		(connect_pads
			(clearance 0)
		)
		(min_thickness 0.25)
		(keepout
			(tracks not_allowed)
			(vias allowed)
			(pads allowed)
			(copperpour not_allowed)
			(footprints allowed)
		)
		(placement
			(enabled no)
			(sheetname "")
		)
		(fill yes
			(thermal_gap 0.5)
			(thermal_bridge_width 0.5)
			(island_removal_mode 0)
		)
		(polygon
			(pts
				(arc
					(start 89.38133 -182.13324)
					(mid 87.60333 -182.13324)
					(end 89.38133 -182.13324)
				)
			)
		)
	)
	(zone
		(layers "In1.Cu" "In3.Cu" "In5.Cu" "In7.Cu" "In8.Cu" "In9.Cu" "In10.Cu"
			"In12.Cu" "In14.Cu" "In16.Cu"
		)
		(hatch none 0.5)
		(connect_pads
			(clearance 0)
		)
		(min_thickness 0.25)
		(keepout
			(tracks not_allowed)
			(vias allowed)
			(pads allowed)
			(copperpour not_allowed)
			(footprints allowed)
		)
		(placement
			(enabled no)
			(sheetname "")
		)
		(fill yes
			(thermal_gap 0.5)
			(thermal_bridge_width 0.5)
			(island_removal_mode 0)
		)
		(polygon
			(pts
				(arc
					(start 91.12885 -162.822636)
					(mid 89.35085 -162.822636)
					(end 91.12885 -162.822636)
				)
			)
		)
	)
	(zone
		(layers "In1.Cu" "In3.Cu" "In5.Cu" "In7.Cu" "In8.Cu" "In9.Cu" "In10.Cu"
			"In12.Cu" "In14.Cu" "In16.Cu"
		)
		(hatch none 0.5)
		(connect_pads
			(clearance 0)
		)
		(min_thickness 0.25)
		(keepout
			(tracks not_allowed)
			(vias allowed)
			(pads allowed)
			(copperpour not_allowed)
			(footprints allowed)
		)
		(placement
			(enabled no)
			(sheetname "")
		)
		(fill yes
			(thermal_gap 0.5)
			(thermal_bridge_width 0.5)
			(island_removal_mode 0)
		)
		(polygon
			(pts
				(arc
					(start 39.686484 -348.709488)
					(mid 37.926264 -348.709488)
					(end 39.686484 -348.709488)
				)
			)
		)
	)
	(zone
		(layers "In1.Cu" "In3.Cu" "In5.Cu" "In7.Cu" "In8.Cu" "In9.Cu" "In10.Cu"
			"In12.Cu" "In14.Cu" "In16.Cu"
		)
		(hatch none 0.5)
		(connect_pads
			(clearance 0)
		)
		(min_thickness 0.25)
		(keepout
			(tracks not_allowed)
			(vias allowed)
			(pads allowed)
			(copperpour not_allowed)
			(footprints allowed)
		)
		(placement
			(enabled no)
			(sheetname "")
		)
		(fill yes
			(thermal_gap 0.5)
			(thermal_bridge_width 0.5)
			(island_removal_mode 0)
		)
		(polygon
			(pts
				(arc
					(start 388.255256 -181.494176)
					(mid 386.477256 -181.494176)
					(end 388.255256 -181.494176)
				)
			)
		)
	)
	(zone
		(layers "In1.Cu" "In3.Cu" "In5.Cu" "In7.Cu" "In8.Cu" "In9.Cu" "In10.Cu"
			"In12.Cu" "In14.Cu" "In16.Cu"
		)
		(hatch none 0.5)
		(connect_pads
			(clearance 0)
		)
		(min_thickness 0.25)
		(keepout
			(tracks not_allowed)
			(vias allowed)
			(pads allowed)
			(copperpour not_allowed)
			(footprints allowed)
		)
		(placement
			(enabled no)
			(sheetname "")
		)
		(fill yes
			(thermal_gap 0.5)
			(thermal_bridge_width 0.5)
			(island_removal_mode 0)
		)
		(polygon
			(pts
				(arc
					(start 50.242978 -358.108504)
					(mid 48.464978 -358.108504)
					(end 50.242978 -358.108504)
				)
			)
		)
	)
	(zone
		(layers "In1.Cu" "In3.Cu" "In5.Cu" "In7.Cu" "In8.Cu" "In9.Cu" "In10.Cu"
			"In12.Cu" "In14.Cu" "In16.Cu"
		)
		(hatch none 0.5)
		(connect_pads
			(clearance 0)
		)
		(min_thickness 0.25)
		(keepout
			(tracks not_allowed)
			(vias allowed)
			(pads allowed)
			(copperpour not_allowed)
			(footprints allowed)
		)
		(placement
			(enabled no)
			(sheetname "")
		)
		(fill yes
			(thermal_gap 0.5)
			(thermal_bridge_width 0.5)
			(island_removal_mode 0)
		)
		(polygon
			(pts
				(arc
					(start 370.203984 -163.89858)
					(mid 368.425984 -163.89858)
					(end 370.203984 -163.89858)
				)
			)
		)
	)
	(zone
		(layers "In1.Cu" "In3.Cu" "In5.Cu" "In7.Cu" "In8.Cu" "In9.Cu" "In10.Cu"
			"In12.Cu" "In14.Cu" "In16.Cu"
		)
		(hatch none 0.5)
		(connect_pads
			(clearance 0)
		)
		(min_thickness 0.25)
		(keepout
			(tracks not_allowed)
			(vias allowed)
			(pads allowed)
			(copperpour not_allowed)
			(footprints allowed)
		)
		(placement
			(enabled no)
			(sheetname "")
		)
		(fill yes
			(thermal_gap 0.5)
			(thermal_bridge_width 0.5)
			(island_removal_mode 0)
		)
		(polygon
			(pts
				(arc
					(start 278.938482 -349.577152)
					(mid 277.160482 -349.577152)
					(end 278.938482 -349.577152)
				)
			)
		)
	)
	(zone
		(layers "In1.Cu" "In3.Cu" "In5.Cu" "In7.Cu" "In8.Cu" "In9.Cu" "In10.Cu"
			"In12.Cu" "In14.Cu" "In16.Cu"
		)
		(hatch none 0.5)
		(connect_pads
			(clearance 0)
		)
		(min_thickness 0.25)
		(keepout
			(tracks not_allowed)
			(vias allowed)
			(pads allowed)
			(copperpour not_allowed)
			(footprints allowed)
		)
		(placement
			(enabled no)
			(sheetname "")
		)
		(fill yes
			(thermal_gap 0.5)
			(thermal_bridge_width 0.5)
			(island_removal_mode 0)
		)
		(polygon
			(pts
				(arc
					(start 97.869248 -182.13324)
					(mid 96.091248 -182.13324)
					(end 97.869248 -182.13324)
				)
			)
		)
	)
	(zone
		(layers "In1.Cu" "In3.Cu" "In5.Cu" "In7.Cu" "In8.Cu" "In9.Cu" "In10.Cu"
			"In12.Cu" "In14.Cu" "In16.Cu"
		)
		(hatch none 0.5)
		(connect_pads
			(clearance 0)
		)
		(min_thickness 0.25)
		(keepout
			(tracks not_allowed)
			(vias allowed)
			(pads allowed)
			(copperpour not_allowed)
			(footprints allowed)
		)
		(placement
			(enabled no)
			(sheetname "")
		)
		(fill yes
			(thermal_gap 0.5)
			(thermal_bridge_width 0.5)
			(island_removal_mode 0)
		)
		(polygon
			(pts
				(arc
					(start 442.243718 -19.21256)
					(mid 440.465718 -19.21256)
					(end 442.243718 -19.21256)
				)
			)
		)
	)
	(zone
		(layers "In1.Cu" "In3.Cu" "In5.Cu" "In7.Cu" "In8.Cu" "In9.Cu" "In10.Cu"
			"In12.Cu" "In14.Cu" "In16.Cu"
		)
		(hatch none 0.5)
		(connect_pads
			(clearance 0)
		)
		(min_thickness 0.25)
		(keepout
			(tracks not_allowed)
			(vias allowed)
			(pads allowed)
			(copperpour not_allowed)
			(footprints allowed)
		)
		(placement
			(enabled no)
			(sheetname "")
		)
		(fill yes
			(thermal_gap 0.5)
			(thermal_bridge_width 0.5)
			(island_removal_mode 0)
		)
		(polygon
			(pts
				(arc
					(start 50.92573 -356.822502)
					(mid 49.14773 -356.822502)
					(end 50.92573 -356.822502)
				)
			)
		)
	)
	(zone
		(layers "In1.Cu" "In3.Cu" "In5.Cu" "In7.Cu" "In8.Cu" "In9.Cu" "In10.Cu"
			"In12.Cu" "In14.Cu" "In16.Cu"
		)
		(hatch none 0.5)
		(connect_pads
			(clearance 0)
		)
		(min_thickness 0.25)
		(keepout
			(tracks not_allowed)
			(vias allowed)
			(pads allowed)
			(copperpour not_allowed)
			(footprints allowed)
		)
		(placement
			(enabled no)
			(sheetname "")
		)
		(fill yes
			(thermal_gap 0.5)
			(thermal_bridge_width 0.5)
			(island_removal_mode 0)
		)
		(polygon
			(pts
				(arc
					(start 280.022046 -350.255332)
					(mid 278.244046 -350.255332)
					(end 280.022046 -350.255332)
				)
			)
		)
	)
	(zone
		(layers "In1.Cu" "In3.Cu" "In5.Cu" "In7.Cu" "In8.Cu" "In9.Cu" "In10.Cu"
			"In12.Cu" "In14.Cu" "In16.Cu"
		)
		(hatch none 0.5)
		(connect_pads
			(clearance 0)
		)
		(min_thickness 0.25)
		(keepout
			(tracks not_allowed)
			(vias allowed)
			(pads allowed)
			(copperpour not_allowed)
			(footprints allowed)
		)
		(placement
			(enabled no)
			(sheetname "")
		)
		(fill yes
			(thermal_gap 0.5)
			(thermal_bridge_width 0.5)
			(island_removal_mode 0)
		)
		(polygon
			(pts
				(arc
					(start 287.218882 -349.577152)
					(mid 285.440882 -349.577152)
					(end 287.218882 -349.577152)
				)
			)
		)
	)
	(zone
		(layers "In1.Cu" "In3.Cu" "In5.Cu" "In7.Cu" "In8.Cu" "In9.Cu" "In10.Cu"
			"In12.Cu" "In14.Cu" "In16.Cu"
		)
		(hatch none 0.5)
		(connect_pads
			(clearance 0)
		)
		(min_thickness 0.25)
		(keepout
			(tracks not_allowed)
			(vias allowed)
			(pads allowed)
			(copperpour not_allowed)
			(footprints allowed)
		)
		(placement
			(enabled no)
			(sheetname "")
		)
		(fill yes
			(thermal_gap 0.5)
			(thermal_bridge_width 0.5)
			(island_removal_mode 0)
		)
		(polygon
			(pts
				(arc
					(start 436.570628 -353.94265)
					(mid 434.792628 -353.94265)
					(end 436.570628 -353.94265)
				)
			)
		)
	)
	(zone
		(layers "In1.Cu" "In3.Cu" "In5.Cu" "In7.Cu" "In8.Cu" "In9.Cu" "In10.Cu"
			"In12.Cu" "In14.Cu" "In16.Cu"
		)
		(hatch none 0.5)
		(connect_pads
			(clearance 0)
		)
		(min_thickness 0.25)
		(keepout
			(tracks not_allowed)
			(vias allowed)
			(pads allowed)
			(copperpour not_allowed)
			(footprints allowed)
		)
		(placement
			(enabled no)
			(sheetname "")
		)
		(fill yes
			(thermal_gap 0.5)
			(thermal_bridge_width 0.5)
			(island_removal_mode 0)
		)
		(polygon
			(pts
				(arc
					(start 66.474594 -350.260158)
					(mid 64.696594 -350.260158)
					(end 66.474594 -350.260158)
				)
			)
		)
	)
	(zone
		(layers "In1.Cu" "In3.Cu" "In5.Cu" "In7.Cu" "In8.Cu" "In9.Cu" "In10.Cu"
			"In12.Cu" "In14.Cu" "In16.Cu"
		)
		(hatch none 0.5)
		(connect_pads
			(clearance 0)
		)
		(min_thickness 0.25)
		(keepout
			(tracks not_allowed)
			(vias allowed)
			(pads allowed)
			(copperpour not_allowed)
			(footprints allowed)
		)
		(placement
			(enabled no)
			(sheetname "")
		)
		(fill yes
			(thermal_gap 0.5)
			(thermal_bridge_width 0.5)
			(island_removal_mode 0)
		)
		(polygon
			(pts
				(arc
					(start 354.879656 -168.982136)
					(mid 353.101656 -168.982136)
					(end 354.879656 -168.982136)
				)
			)
		)
	)
	(zone
		(layers "In1.Cu" "In3.Cu" "In5.Cu" "In7.Cu" "In8.Cu" "In9.Cu" "In10.Cu"
			"In12.Cu" "In14.Cu" "In16.Cu"
		)
		(hatch none 0.5)
		(connect_pads
			(clearance 0)
		)
		(min_thickness 0.25)
		(keepout
			(tracks not_allowed)
			(vias allowed)
			(pads allowed)
			(copperpour not_allowed)
			(footprints allowed)
		)
		(placement
			(enabled no)
			(sheetname "")
		)
		(fill yes
			(thermal_gap 0.5)
			(thermal_bridge_width 0.5)
			(island_removal_mode 0)
		)
		(polygon
			(pts
				(arc
					(start 90.63863 -338.575904)
					(mid 88.86063 -338.575904)
					(end 90.63863 -338.575904)
				)
			)
		)
	)
	(zone
		(layers "In1.Cu" "In3.Cu" "In5.Cu" "In7.Cu" "In8.Cu" "In9.Cu" "In10.Cu"
			"In12.Cu" "In14.Cu" "In16.Cu"
		)
		(hatch none 0.5)
		(connect_pads
			(clearance 0)
		)
		(min_thickness 0.25)
		(keepout
			(tracks not_allowed)
			(vias allowed)
			(pads allowed)
			(copperpour not_allowed)
			(footprints allowed)
		)
		(placement
			(enabled no)
			(sheetname "")
		)
		(fill yes
			(thermal_gap 0.5)
			(thermal_bridge_width 0.5)
			(island_removal_mode 0)
		)
		(polygon
			(pts
				(arc
					(start 239.181894 -44.040806)
					(mid 237.403894 -44.040806)
					(end 239.181894 -44.040806)
				)
			)
		)
	)
	(zone
		(layers "In1.Cu" "In3.Cu" "In5.Cu" "In7.Cu" "In8.Cu" "In9.Cu" "In10.Cu"
			"In12.Cu" "In14.Cu" "In16.Cu"
		)
		(hatch none 0.5)
		(connect_pads
			(clearance 0)
		)
		(min_thickness 0.25)
		(keepout
			(tracks not_allowed)
			(vias allowed)
			(pads allowed)
			(copperpour not_allowed)
			(footprints allowed)
		)
		(placement
			(enabled no)
			(sheetname "")
		)
		(fill yes
			(thermal_gap 0.5)
			(thermal_bridge_width 0.5)
			(island_removal_mode 0)
		)
		(polygon
			(pts
				(arc
					(start 121.14403 -162.390074)
					(mid 119.36603 -162.390074)
					(end 121.14403 -162.390074)
				)
			)
		)
	)
	(zone
		(layers "In1.Cu" "In3.Cu" "In5.Cu" "In7.Cu" "In8.Cu" "In9.Cu" "In10.Cu"
			"In12.Cu" "In14.Cu" "In16.Cu"
		)
		(hatch none 0.5)
		(connect_pads
			(clearance 0)
		)
		(min_thickness 0.25)
		(keepout
			(tracks not_allowed)
			(vias allowed)
			(pads allowed)
			(copperpour not_allowed)
			(footprints allowed)
		)
		(placement
			(enabled no)
			(sheetname "")
		)
		(fill yes
			(thermal_gap 0.5)
			(thermal_bridge_width 0.5)
			(island_removal_mode 0)
		)
		(polygon
			(pts
				(arc
					(start 202.634342 -344.0684)
					(mid 200.856342 -344.0684)
					(end 202.634342 -344.0684)
				)
			)
		)
	)
	(zone
		(layers "In1.Cu" "In3.Cu" "In5.Cu" "In7.Cu" "In8.Cu" "In9.Cu" "In10.Cu"
			"In12.Cu" "In14.Cu" "In16.Cu"
		)
		(hatch none 0.5)
		(connect_pads
			(clearance 0)
		)
		(min_thickness 0.25)
		(keepout
			(tracks not_allowed)
			(vias allowed)
			(pads allowed)
			(copperpour not_allowed)
			(footprints allowed)
		)
		(placement
			(enabled no)
			(sheetname "")
		)
		(fill yes
			(thermal_gap 0.5)
			(thermal_bridge_width 0.5)
			(island_removal_mode 0)
		)
		(polygon
			(pts
				(arc
					(start 369.568984 -163.89858)
					(mid 367.790984 -163.89858)
					(end 369.568984 -163.89858)
				)
			)
		)
	)
	(zone
		(layers "In1.Cu" "In3.Cu" "In5.Cu" "In7.Cu" "In8.Cu" "In9.Cu" "In10.Cu"
			"In12.Cu" "In14.Cu" "In16.Cu"
		)
		(hatch none 0.5)
		(connect_pads
			(clearance 0)
		)
		(min_thickness 0.25)
		(keepout
			(tracks not_allowed)
			(vias allowed)
			(pads allowed)
			(copperpour not_allowed)
			(footprints allowed)
		)
		(placement
			(enabled no)
			(sheetname "")
		)
		(fill yes
			(thermal_gap 0.5)
			(thermal_bridge_width 0.5)
			(island_removal_mode 0)
		)
		(polygon
			(pts
				(arc
					(start 47.375064 -348.709488)
					(mid 45.614844 -348.709488)
					(end 47.375064 -348.709488)
				)
			)
		)
	)
	(zone
		(layers "In1.Cu" "In3.Cu" "In5.Cu" "In7.Cu" "In8.Cu" "In9.Cu" "In10.Cu"
			"In12.Cu" "In14.Cu" "In16.Cu"
		)
		(hatch none 0.5)
		(connect_pads
			(clearance 0)
		)
		(min_thickness 0.25)
		(keepout
			(tracks not_allowed)
			(vias allowed)
			(pads allowed)
			(copperpour not_allowed)
			(footprints allowed)
		)
		(placement
			(enabled no)
			(sheetname "")
		)
		(fill yes
			(thermal_gap 0.5)
			(thermal_bridge_width 0.5)
			(island_removal_mode 0)
		)
		(polygon
			(pts
				(arc
					(start 328.889614 -336.976466)
					(mid 327.129394 -336.976466)
					(end 328.889614 -336.976466)
				)
			)
		)
	)
	(zone
		(layers "In1.Cu" "In3.Cu" "In5.Cu" "In7.Cu" "In8.Cu" "In9.Cu" "In10.Cu"
			"In12.Cu" "In14.Cu" "In16.Cu"
		)
		(hatch none 0.5)
		(connect_pads
			(clearance 0)
		)
		(min_thickness 0.25)
		(keepout
			(tracks not_allowed)
			(vias allowed)
			(pads allowed)
			(copperpour not_allowed)
			(footprints allowed)
		)
		(placement
			(enabled no)
			(sheetname "")
		)
		(fill yes
			(thermal_gap 0.5)
			(thermal_bridge_width 0.5)
			(island_removal_mode 0)
		)
		(polygon
			(pts
				(arc
					(start 132.6134 -154.542744)
					(mid 130.85318 -154.542744)
					(end 132.6134 -154.542744)
				)
			)
		)
	)
	(zone
		(layers "In1.Cu" "In3.Cu" "In5.Cu" "In7.Cu" "In8.Cu" "In9.Cu" "In10.Cu"
			"In12.Cu" "In14.Cu" "In16.Cu"
		)
		(hatch none 0.5)
		(connect_pads
			(clearance 0)
		)
		(min_thickness 0.25)
		(keepout
			(tracks not_allowed)
			(vias allowed)
			(pads allowed)
			(copperpour not_allowed)
			(footprints allowed)
		)
		(placement
			(enabled no)
			(sheetname "")
		)
		(fill yes
			(thermal_gap 0.5)
			(thermal_bridge_width 0.5)
			(island_removal_mode 0)
		)
		(polygon
			(pts
				(arc
					(start 368.933984 -164.53358)
					(mid 367.155984 -164.53358)
					(end 368.933984 -164.53358)
				)
			)
		)
	)
	(zone
		(layers "In1.Cu" "In3.Cu" "In5.Cu" "In7.Cu" "In8.Cu" "In9.Cu" "In10.Cu"
			"In12.Cu" "In14.Cu" "In16.Cu"
		)
		(hatch none 0.5)
		(connect_pads
			(clearance 0)
		)
		(min_thickness 0.25)
		(keepout
			(tracks not_allowed)
			(vias allowed)
			(pads allowed)
			(copperpour not_allowed)
			(footprints allowed)
		)
		(placement
			(enabled no)
			(sheetname "")
		)
		(fill yes
			(thermal_gap 0.5)
			(thermal_bridge_width 0.5)
			(island_removal_mode 0)
		)
		(polygon
			(pts
				(arc
					(start 49.607978 -358.108504)
					(mid 47.829978 -358.108504)
					(end 49.607978 -358.108504)
				)
			)
		)
	)
	(zone
		(layers "In1.Cu" "In3.Cu" "In5.Cu" "In7.Cu" "In8.Cu" "In9.Cu" "In10.Cu"
			"In12.Cu" "In14.Cu" "In16.Cu"
		)
		(hatch none 0.5)
		(connect_pads
			(clearance 0)
		)
		(min_thickness 0.25)
		(keepout
			(tracks not_allowed)
			(vias allowed)
			(pads allowed)
			(copperpour not_allowed)
			(footprints allowed)
		)
		(placement
			(enabled no)
			(sheetname "")
		)
		(fill yes
			(thermal_gap 0.5)
			(thermal_bridge_width 0.5)
			(island_removal_mode 0)
		)
		(polygon
			(pts
				(arc
					(start 347.299788 -159.151066)
					(mid 345.539568 -159.151066)
					(end 347.299788 -159.151066)
				)
			)
		)
	)
	(zone
		(layers "In1.Cu" "In3.Cu" "In5.Cu" "In7.Cu" "In8.Cu" "In9.Cu" "In10.Cu"
			"In12.Cu" "In14.Cu" "In16.Cu"
		)
		(hatch none 0.5)
		(connect_pads
			(clearance 0)
		)
		(min_thickness 0.25)
		(keepout
			(tracks not_allowed)
			(vias allowed)
			(pads allowed)
			(copperpour not_allowed)
			(footprints allowed)
		)
		(placement
			(enabled no)
			(sheetname "")
		)
		(fill yes
			(thermal_gap 0.5)
			(thermal_bridge_width 0.5)
			(island_removal_mode 0)
		)
		(polygon
			(pts
				(arc
					(start 66.298064 -13.09751)
					(mid 64.520064 -13.09751)
					(end 66.298064 -13.09751)
				)
			)
		)
	)
	(zone
		(layers "In1.Cu" "In3.Cu" "In5.Cu" "In7.Cu" "In8.Cu" "In9.Cu" "In10.Cu"
			"In12.Cu" "In14.Cu" "In16.Cu"
		)
		(hatch none 0.5)
		(connect_pads
			(clearance 0)
		)
		(min_thickness 0.25)
		(keepout
			(tracks not_allowed)
			(vias allowed)
			(pads allowed)
			(copperpour not_allowed)
			(footprints allowed)
		)
		(placement
			(enabled no)
			(sheetname "")
		)
		(fill yes
			(thermal_gap 0.5)
			(thermal_bridge_width 0.5)
			(island_removal_mode 0)
		)
		(polygon
			(pts
				(arc
					(start 193.434716 -353.309174)
					(mid 191.674496 -353.309174)
					(end 193.434716 -353.309174)
				)
			)
		)
	)
	(zone
		(layers "In1.Cu" "In3.Cu" "In5.Cu" "In7.Cu" "In8.Cu" "In9.Cu" "In10.Cu"
			"In12.Cu" "In14.Cu" "In16.Cu"
		)
		(hatch none 0.5)
		(connect_pads
			(clearance 0)
		)
		(min_thickness 0.25)
		(keepout
			(tracks not_allowed)
			(vias allowed)
			(pads allowed)
			(copperpour not_allowed)
			(footprints allowed)
		)
		(placement
			(enabled no)
			(sheetname "")
		)
		(fill yes
			(thermal_gap 0.5)
			(thermal_bridge_width 0.5)
			(island_removal_mode 0)
		)
		(polygon
			(pts
				(arc
					(start 344.354404 -352.248216)
					(mid 342.576404 -352.248216)
					(end 344.354404 -352.248216)
				)
			)
		)
	)
	(zone
		(layers "In1.Cu" "In3.Cu" "In5.Cu" "In7.Cu" "In8.Cu" "In9.Cu" "In10.Cu"
			"In12.Cu" "In14.Cu" "In16.Cu"
		)
		(hatch none 0.5)
		(connect_pads
			(clearance 0)
		)
		(min_thickness 0.25)
		(keepout
			(tracks not_allowed)
			(vias allowed)
			(pads allowed)
			(copperpour not_allowed)
			(footprints allowed)
		)
		(placement
			(enabled no)
			(sheetname "")
		)
		(fill yes
			(thermal_gap 0.5)
			(thermal_bridge_width 0.5)
			(island_removal_mode 0)
		)
		(polygon
			(pts
				(arc
					(start 92.144088 -345.96959)
					(mid 90.366088 -345.96959)
					(end 92.144088 -345.96959)
				)
			)
		)
	)
	(zone
		(layers "In1.Cu" "In3.Cu" "In5.Cu" "In7.Cu" "In8.Cu" "In9.Cu" "In10.Cu"
			"In12.Cu" "In14.Cu" "In16.Cu"
		)
		(hatch none 0.5)
		(connect_pads
			(clearance 0)
		)
		(min_thickness 0.25)
		(keepout
			(tracks not_allowed)
			(vias allowed)
			(pads allowed)
			(copperpour not_allowed)
			(footprints allowed)
		)
		(placement
			(enabled no)
			(sheetname "")
		)
		(fill yes
			(thermal_gap 0.5)
			(thermal_bridge_width 0.5)
			(island_removal_mode 0)
		)
		(polygon
			(pts
				(arc
					(start 90.87104 -180.687472)
					(mid 89.11082 -180.687472)
					(end 90.87104 -180.687472)
				)
			)
		)
	)
	(zone
		(layers "In1.Cu" "In3.Cu" "In5.Cu" "In7.Cu" "In8.Cu" "In9.Cu" "In10.Cu"
			"In12.Cu" "In14.Cu" "In16.Cu"
		)
		(hatch none 0.5)
		(connect_pads
			(clearance 0)
		)
		(min_thickness 0.25)
		(keepout
			(tracks not_allowed)
			(vias allowed)
			(pads allowed)
			(copperpour not_allowed)
			(footprints allowed)
		)
		(placement
			(enabled no)
			(sheetname "")
		)
		(fill yes
			(thermal_gap 0.5)
			(thermal_bridge_width 0.5)
			(island_removal_mode 0)
		)
		(polygon
			(pts
				(arc
					(start 73.496424 -335.519268)
					(mid 71.736204 -335.519268)
					(end 73.496424 -335.519268)
				)
			)
		)
	)
	(zone
		(layers "In1.Cu" "In3.Cu" "In5.Cu" "In7.Cu" "In8.Cu" "In9.Cu" "In10.Cu"
			"In12.Cu" "In14.Cu" "In16.Cu"
		)
		(hatch none 0.5)
		(connect_pads
			(clearance 0)
		)
		(min_thickness 0.25)
		(keepout
			(tracks not_allowed)
			(vias allowed)
			(pads allowed)
			(copperpour not_allowed)
			(footprints allowed)
		)
		(placement
			(enabled no)
			(sheetname "")
		)
		(fill yes
			(thermal_gap 0.5)
			(thermal_bridge_width 0.5)
			(island_removal_mode 0)
		)
		(polygon
			(pts
				(arc
					(start 78.410816 -350.891094)
					(mid 76.632816 -350.891094)
					(end 78.410816 -350.891094)
				)
			)
		)
	)
	(zone
		(layers "In1.Cu" "In3.Cu" "In5.Cu" "In7.Cu" "In8.Cu" "In9.Cu" "In10.Cu"
			"In12.Cu" "In14.Cu" "In16.Cu"
		)
		(hatch none 0.5)
		(connect_pads
			(clearance 0)
		)
		(min_thickness 0.25)
		(keepout
			(tracks not_allowed)
			(vias allowed)
			(pads allowed)
			(copperpour not_allowed)
			(footprints allowed)
		)
		(placement
			(enabled no)
			(sheetname "")
		)
		(fill yes
			(thermal_gap 0.5)
			(thermal_bridge_width 0.5)
			(island_removal_mode 0)
		)
		(polygon
			(pts
				(arc
					(start 337.86445 -336.961988)
					(mid 336.10423 -336.961988)
					(end 337.86445 -336.961988)
				)
			)
		)
	)
	(zone
		(layers "In1.Cu" "In3.Cu" "In5.Cu" "In7.Cu" "In8.Cu" "In9.Cu" "In10.Cu"
			"In12.Cu" "In14.Cu" "In16.Cu"
		)
		(hatch none 0.5)
		(connect_pads
			(clearance 0)
		)
		(min_thickness 0.25)
		(keepout
			(tracks not_allowed)
			(vias allowed)
			(pads allowed)
			(copperpour not_allowed)
			(footprints allowed)
		)
		(placement
			(enabled no)
			(sheetname "")
		)
		(fill yes
			(thermal_gap 0.5)
			(thermal_bridge_width 0.5)
			(island_removal_mode 0)
		)
		(polygon
			(pts
				(arc
					(start 434.902102 -352.38309)
					(mid 433.124102 -352.38309)
					(end 434.902102 -352.38309)
				)
			)
		)
	)
	(zone
		(layers "In1.Cu" "In3.Cu" "In5.Cu" "In7.Cu" "In8.Cu" "In9.Cu" "In10.Cu"
			"In12.Cu" "In14.Cu" "In16.Cu"
		)
		(hatch none 0.5)
		(connect_pads
			(clearance 0)
		)
		(min_thickness 0.25)
		(keepout
			(tracks not_allowed)
			(vias allowed)
			(pads allowed)
			(copperpour not_allowed)
			(footprints allowed)
		)
		(placement
			(enabled no)
			(sheetname "")
		)
		(fill yes
			(thermal_gap 0.5)
			(thermal_bridge_width 0.5)
			(island_removal_mode 0)
		)
		(polygon
			(pts
				(arc
					(start 341.390224 -351.453196)
					(mid 339.612224 -351.453196)
					(end 341.390224 -351.453196)
				)
			)
		)
	)
	(zone
		(layers "In1.Cu" "In3.Cu" "In5.Cu" "In7.Cu" "In8.Cu" "In9.Cu" "In10.Cu"
			"In12.Cu" "In14.Cu" "In16.Cu"
		)
		(hatch none 0.5)
		(connect_pads
			(clearance 0)
		)
		(min_thickness 0.25)
		(keepout
			(tracks not_allowed)
			(vias allowed)
			(pads allowed)
			(copperpour not_allowed)
			(footprints allowed)
		)
		(placement
			(enabled no)
			(sheetname "")
		)
		(fill yes
			(thermal_gap 0.5)
			(thermal_bridge_width 0.5)
			(island_removal_mode 0)
		)
		(polygon
			(pts
				(arc
					(start 90.46845 -162.812476)
					(mid 88.69045 -162.812476)
					(end 90.46845 -162.812476)
				)
			)
		)
	)
	(zone
		(layers "In1.Cu" "In3.Cu" "In5.Cu" "In7.Cu" "In8.Cu" "In9.Cu" "In10.Cu"
			"In12.Cu" "In14.Cu" "In16.Cu"
		)
		(hatch none 0.5)
		(connect_pads
			(clearance 0)
		)
		(min_thickness 0.25)
		(keepout
			(tracks not_allowed)
			(vias allowed)
			(pads allowed)
			(copperpour not_allowed)
			(footprints allowed)
		)
		(placement
			(enabled no)
			(sheetname "")
		)
		(fill yes
			(thermal_gap 0.5)
			(thermal_bridge_width 0.5)
			(island_removal_mode 0)
		)
		(polygon
			(pts
				(arc
					(start 289.15995 -355.279198)
					(mid 287.38195 -355.279198)
					(end 289.15995 -355.279198)
				)
			)
		)
	)
	(zone
		(layers "In1.Cu" "In3.Cu" "In5.Cu" "In7.Cu" "In8.Cu" "In9.Cu" "In10.Cu"
			"In12.Cu" "In14.Cu" "In16.Cu"
		)
		(hatch none 0.5)
		(connect_pads
			(clearance 0)
		)
		(min_thickness 0.25)
		(keepout
			(tracks not_allowed)
			(vias allowed)
			(pads allowed)
			(copperpour not_allowed)
			(footprints allowed)
		)
		(placement
			(enabled no)
			(sheetname "")
		)
		(fill yes
			(thermal_gap 0.5)
			(thermal_bridge_width 0.5)
			(island_removal_mode 0)
		)
		(polygon
			(pts
				(arc
					(start 81.570068 -336.981292)
					(mid 79.809848 -336.981292)
					(end 81.570068 -336.981292)
				)
			)
		)
	)
	(zone
		(layers "In1.Cu" "In3.Cu" "In5.Cu" "In7.Cu" "In8.Cu" "In9.Cu" "In10.Cu"
			"In12.Cu" "In14.Cu" "In16.Cu"
		)
		(hatch none 0.5)
		(connect_pads
			(clearance 0)
		)
		(min_thickness 0.25)
		(keepout
			(tracks not_allowed)
			(vias allowed)
			(pads allowed)
			(copperpour not_allowed)
			(footprints allowed)
		)
		(placement
			(enabled no)
			(sheetname "")
		)
		(fill yes
			(thermal_gap 0.5)
			(thermal_bridge_width 0.5)
			(island_removal_mode 0)
		)
		(polygon
			(pts
				(arc
					(start 412.791402 -160.906968)
					(mid 411.013402 -160.906968)
					(end 412.791402 -160.906968)
				)
			)
		)
	)
	(zone
		(layers "In1.Cu" "In3.Cu" "In5.Cu" "In7.Cu" "In8.Cu" "In9.Cu" "In10.Cu"
			"In12.Cu" "In14.Cu" "In16.Cu"
		)
		(hatch none 0.5)
		(connect_pads
			(clearance 0)
		)
		(min_thickness 0.25)
		(keepout
			(tracks not_allowed)
			(vias allowed)
			(pads allowed)
			(copperpour not_allowed)
			(footprints allowed)
		)
		(placement
			(enabled no)
			(sheetname "")
		)
		(fill yes
			(thermal_gap 0.5)
			(thermal_bridge_width 0.5)
			(island_removal_mode 0)
		)
		(polygon
			(pts
				(arc
					(start 354.295202 -165.898576)
					(mid 352.517202 -165.898576)
					(end 354.295202 -165.898576)
				)
			)
		)
	)
	(zone
		(layers "In1.Cu" "In3.Cu" "In5.Cu" "In7.Cu" "In8.Cu" "In9.Cu" "In10.Cu"
			"In12.Cu" "In14.Cu" "In16.Cu"
		)
		(hatch none 0.5)
		(connect_pads
			(clearance 0)
		)
		(min_thickness 0.25)
		(keepout
			(tracks not_allowed)
			(vias allowed)
			(pads allowed)
			(copperpour not_allowed)
			(footprints allowed)
		)
		(placement
			(enabled no)
			(sheetname "")
		)
		(fill yes
			(thermal_gap 0.5)
			(thermal_bridge_width 0.5)
			(island_removal_mode 0)
		)
		(polygon
			(pts
				(arc
					(start 93.490288 -345.96959)
					(mid 91.712288 -345.96959)
					(end 93.490288 -345.96959)
				)
			)
		)
	)
	(zone
		(layers "In1.Cu" "In3.Cu" "In5.Cu" "In7.Cu" "In8.Cu" "In9.Cu" "In10.Cu"
			"In12.Cu" "In14.Cu" "In16.Cu"
		)
		(hatch none 0.5)
		(connect_pads
			(clearance 0)
		)
		(min_thickness 0.25)
		(keepout
			(tracks not_allowed)
			(vias allowed)
			(pads allowed)
			(copperpour not_allowed)
			(footprints allowed)
		)
		(placement
			(enabled no)
			(sheetname "")
		)
		(fill yes
			(thermal_gap 0.5)
			(thermal_bridge_width 0.5)
			(island_removal_mode 0)
		)
		(polygon
			(pts
				(arc
					(start 320.53403 -336.983578)
					(mid 318.77381 -336.983578)
					(end 320.53403 -336.983578)
				)
			)
		)
	)
	(zone
		(layers "In1.Cu" "In3.Cu" "In5.Cu" "In7.Cu" "In8.Cu" "In9.Cu" "In10.Cu"
			"In12.Cu" "In14.Cu" "In16.Cu"
		)
		(hatch none 0.5)
		(connect_pads
			(clearance 0)
		)
		(min_thickness 0.25)
		(keepout
			(tracks not_allowed)
			(vias allowed)
			(pads allowed)
			(copperpour not_allowed)
			(footprints allowed)
		)
		(placement
			(enabled no)
			(sheetname "")
		)
		(fill yes
			(thermal_gap 0.5)
			(thermal_bridge_width 0.5)
			(island_removal_mode 0)
		)
		(polygon
			(pts
				(arc
					(start 68.177664 -25.56891)
					(mid 66.399664 -25.56891)
					(end 68.177664 -25.56891)
				)
			)
		)
	)
	(zone
		(layers "In1.Cu" "In3.Cu" "In5.Cu" "In7.Cu" "In8.Cu" "In9.Cu" "In10.Cu"
			"In12.Cu" "In14.Cu" "In16.Cu"
		)
		(hatch none 0.5)
		(connect_pads
			(clearance 0)
		)
		(min_thickness 0.25)
		(keepout
			(tracks not_allowed)
			(vias allowed)
			(pads allowed)
			(copperpour not_allowed)
			(footprints allowed)
		)
		(placement
			(enabled no)
			(sheetname "")
		)
		(fill yes
			(thermal_gap 0.5)
			(thermal_bridge_width 0.5)
			(island_removal_mode 0)
		)
		(polygon
			(pts
				(arc
					(start 372.85676 -180.803804)
					(mid 371.09654 -180.803804)
					(end 372.85676 -180.803804)
				)
			)
		)
	)
	(zone
		(layers "In1.Cu" "In3.Cu" "In5.Cu" "In7.Cu" "In8.Cu" "In9.Cu" "In10.Cu"
			"In12.Cu" "In14.Cu" "In16.Cu"
		)
		(hatch none 0.5)
		(connect_pads
			(clearance 0)
		)
		(min_thickness 0.25)
		(keepout
			(tracks not_allowed)
			(vias allowed)
			(pads allowed)
			(copperpour not_allowed)
			(footprints allowed)
		)
		(placement
			(enabled no)
			(sheetname "")
		)
		(fill yes
			(thermal_gap 0.5)
			(thermal_bridge_width 0.5)
			(island_removal_mode 0)
		)
		(polygon
			(pts
				(arc
					(start 106.41076 -176.183544)
					(mid 104.65054 -176.183544)
					(end 106.41076 -176.183544)
				)
			)
		)
	)
	(zone
		(layers "In1.Cu" "In3.Cu" "In5.Cu" "In7.Cu" "In8.Cu" "In9.Cu" "In10.Cu"
			"In12.Cu" "In14.Cu" "In16.Cu"
		)
		(hatch none 0.5)
		(connect_pads
			(clearance 0)
		)
		(min_thickness 0.25)
		(keepout
			(tracks not_allowed)
			(vias allowed)
			(pads allowed)
			(copperpour not_allowed)
			(footprints allowed)
		)
		(placement
			(enabled no)
			(sheetname "")
		)
		(fill yes
			(thermal_gap 0.5)
			(thermal_bridge_width 0.5)
			(island_removal_mode 0)
		)
		(polygon
			(pts
				(arc
					(start 289.17011 -355.949758)
					(mid 287.39211 -355.949758)
					(end 289.17011 -355.949758)
				)
			)
		)
	)
	(zone
		(layers "In1.Cu" "In3.Cu" "In5.Cu" "In7.Cu" "In8.Cu" "In9.Cu" "In10.Cu"
			"In12.Cu" "In14.Cu" "In16.Cu"
		)
		(hatch none 0.5)
		(connect_pads
			(clearance 0)
		)
		(min_thickness 0.25)
		(keepout
			(tracks not_allowed)
			(vias allowed)
			(pads allowed)
			(copperpour not_allowed)
			(footprints allowed)
		)
		(placement
			(enabled no)
			(sheetname "")
		)
		(fill yes
			(thermal_gap 0.5)
			(thermal_bridge_width 0.5)
			(island_removal_mode 0)
		)
		(polygon
			(pts
				(arc
					(start 92.893642 -346.639896)
					(mid 91.115642 -346.639896)
					(end 92.893642 -346.639896)
				)
			)
		)
	)
	(zone
		(layers "In1.Cu" "In3.Cu" "In5.Cu" "In7.Cu" "In8.Cu" "In9.Cu" "In10.Cu"
			"In12.Cu" "In14.Cu" "In16.Cu"
		)
		(hatch none 0.5)
		(connect_pads
			(clearance 0)
		)
		(min_thickness 0.25)
		(keepout
			(tracks not_allowed)
			(vias allowed)
			(pads allowed)
			(copperpour not_allowed)
			(footprints allowed)
		)
		(placement
			(enabled no)
			(sheetname "")
		)
		(fill yes
			(thermal_gap 0.5)
			(thermal_bridge_width 0.5)
			(island_removal_mode 0)
		)
		(polygon
			(pts
				(arc
					(start 44.872656 -357.859838)
					(mid 43.094656 -357.859838)
					(end 44.872656 -357.859838)
				)
			)
		)
	)
	(zone
		(layers "In1.Cu" "In3.Cu" "In5.Cu" "In7.Cu" "In8.Cu" "In9.Cu" "In10.Cu"
			"In12.Cu" "In14.Cu" "In16.Cu"
		)
		(hatch none 0.5)
		(connect_pads
			(clearance 0)
		)
		(min_thickness 0.25)
		(keepout
			(tracks not_allowed)
			(vias allowed)
			(pads allowed)
			(copperpour not_allowed)
			(footprints allowed)
		)
		(placement
			(enabled no)
			(sheetname "")
		)
		(fill yes
			(thermal_gap 0.5)
			(thermal_bridge_width 0.5)
			(island_removal_mode 0)
		)
		(polygon
			(pts
				(arc
					(start 57.609994 -349.904558)
					(mid 55.831994 -349.904558)
					(end 57.609994 -349.904558)
				)
			)
		)
	)
	(zone
		(layers "In1.Cu" "In3.Cu" "In5.Cu" "In7.Cu" "In8.Cu" "In9.Cu" "In10.Cu"
			"In12.Cu" "In14.Cu" "In16.Cu"
		)
		(hatch none 0.5)
		(connect_pads
			(clearance 0)
		)
		(min_thickness 0.25)
		(keepout
			(tracks not_allowed)
			(vias allowed)
			(pads allowed)
			(copperpour not_allowed)
			(footprints allowed)
		)
		(placement
			(enabled no)
			(sheetname "")
		)
		(fill yes
			(thermal_gap 0.5)
			(thermal_bridge_width 0.5)
			(island_removal_mode 0)
		)
		(polygon
			(pts
				(arc
					(start 249.103134 -52.171346)
					(mid 247.325134 -52.171346)
					(end 249.103134 -52.171346)
				)
			)
		)
	)
	(zone
		(layers "In1.Cu" "In3.Cu" "In5.Cu" "In7.Cu" "In8.Cu" "In9.Cu" "In10.Cu"
			"In12.Cu" "In14.Cu" "In16.Cu"
		)
		(hatch none 0.5)
		(connect_pads
			(clearance 0)
		)
		(min_thickness 0.25)
		(keepout
			(tracks not_allowed)
			(vias allowed)
			(pads allowed)
			(copperpour not_allowed)
			(footprints allowed)
		)
		(placement
			(enabled no)
			(sheetname "")
		)
		(fill yes
			(thermal_gap 0.5)
			(thermal_bridge_width 0.5)
			(island_removal_mode 0)
		)
		(polygon
			(pts
				(arc
					(start 83.364578 -337.058762)
					(mid 81.586578 -337.058762)
					(end 83.364578 -337.058762)
				)
			)
		)
	)
	(zone
		(layers "In1.Cu" "In3.Cu" "In5.Cu" "In7.Cu" "In8.Cu" "In9.Cu" "In10.Cu"
			"In12.Cu" "In14.Cu" "In16.Cu"
		)
		(hatch none 0.5)
		(connect_pads
			(clearance 0)
		)
		(min_thickness 0.25)
		(keepout
			(tracks not_allowed)
			(vias allowed)
			(pads allowed)
			(copperpour not_allowed)
			(footprints allowed)
		)
		(placement
			(enabled no)
			(sheetname "")
		)
		(fill yes
			(thermal_gap 0.5)
			(thermal_bridge_width 0.5)
			(island_removal_mode 0)
		)
		(polygon
			(pts
				(arc
					(start 68.558664 -24.88311)
					(mid 66.780664 -24.88311)
					(end 68.558664 -24.88311)
				)
			)
		)
	)
	(zone
		(layers "In1.Cu" "In3.Cu" "In5.Cu" "In7.Cu" "In8.Cu" "In9.Cu" "In10.Cu"
			"In12.Cu" "In14.Cu" "In16.Cu"
		)
		(hatch none 0.5)
		(connect_pads
			(clearance 0)
		)
		(min_thickness 0.25)
		(keepout
			(tracks not_allowed)
			(vias allowed)
			(pads allowed)
			(copperpour not_allowed)
			(footprints allowed)
		)
		(placement
			(enabled no)
			(sheetname "")
		)
		(fill yes
			(thermal_gap 0.5)
			(thermal_bridge_width 0.5)
			(island_removal_mode 0)
		)
		(polygon
			(pts
				(arc
					(start 31.684214 -347.966538)
					(mid 29.906214 -347.966538)
					(end 31.684214 -347.966538)
				)
			)
		)
	)
	(zone
		(layers "In1.Cu" "In3.Cu" "In5.Cu" "In7.Cu" "In8.Cu" "In9.Cu" "In10.Cu"
			"In12.Cu" "In14.Cu" "In16.Cu"
		)
		(hatch none 0.5)
		(connect_pads
			(clearance 0)
		)
		(min_thickness 0.25)
		(keepout
			(tracks not_allowed)
			(vias allowed)
			(pads allowed)
			(copperpour not_allowed)
			(footprints allowed)
		)
		(placement
			(enabled no)
			(sheetname "")
		)
		(fill yes
			(thermal_gap 0.5)
			(thermal_bridge_width 0.5)
			(island_removal_mode 0)
		)
		(polygon
			(pts
				(arc
					(start 345.464638 -158.717996)
					(mid 343.686638 -158.717996)
					(end 345.464638 -158.717996)
				)
			)
		)
	)
	(zone
		(layers "In1.Cu" "In3.Cu" "In5.Cu" "In7.Cu" "In8.Cu" "In9.Cu" "In10.Cu"
			"In12.Cu" "In14.Cu" "In16.Cu"
		)
		(hatch none 0.5)
		(connect_pads
			(clearance 0)
		)
		(min_thickness 0.25)
		(keepout
			(tracks not_allowed)
			(vias allowed)
			(pads allowed)
			(copperpour not_allowed)
			(footprints allowed)
		)
		(placement
			(enabled no)
			(sheetname "")
		)
		(fill yes
			(thermal_gap 0.5)
			(thermal_bridge_width 0.5)
			(island_removal_mode 0)
		)
		(polygon
			(pts
				(arc
					(start 80.546194 -179.883054)
					(mid 78.768194 -179.883054)
					(end 80.546194 -179.883054)
				)
			)
		)
	)
	(zone
		(layers "In1.Cu" "In3.Cu" "In5.Cu" "In7.Cu" "In8.Cu" "In9.Cu" "In10.Cu"
			"In12.Cu" "In14.Cu" "In16.Cu"
		)
		(hatch none 0.5)
		(connect_pads
			(clearance 0)
		)
		(min_thickness 0.25)
		(keepout
			(tracks not_allowed)
			(vias allowed)
			(pads allowed)
			(copperpour not_allowed)
			(footprints allowed)
		)
		(placement
			(enabled no)
			(sheetname "")
		)
		(fill yes
			(thermal_gap 0.5)
			(thermal_bridge_width 0.5)
			(island_removal_mode 0)
		)
		(polygon
			(pts
				(arc
					(start 49.786794 -350.260158)
					(mid 48.008794 -350.260158)
					(end 49.786794 -350.260158)
				)
			)
		)
	)
	(zone
		(layers "In1.Cu" "In3.Cu" "In5.Cu" "In7.Cu" "In8.Cu" "In9.Cu" "In10.Cu"
			"In12.Cu" "In14.Cu" "In16.Cu"
		)
		(hatch none 0.5)
		(connect_pads
			(clearance 0)
		)
		(min_thickness 0.25)
		(keepout
			(tracks not_allowed)
			(vias allowed)
			(pads allowed)
			(copperpour not_allowed)
			(footprints allowed)
		)
		(placement
			(enabled no)
			(sheetname "")
		)
		(fill yes
			(thermal_gap 0.5)
			(thermal_bridge_width 0.5)
			(island_removal_mode 0)
		)
		(polygon
			(pts
				(arc
					(start 441.834524 -10.626852)
					(mid 440.056524 -10.626852)
					(end 441.834524 -10.626852)
				)
			)
		)
	)
	(zone
		(layers "In1.Cu" "In3.Cu" "In5.Cu" "In7.Cu" "In8.Cu" "In9.Cu" "In10.Cu"
			"In12.Cu" "In14.Cu" "In16.Cu"
		)
		(hatch none 0.5)
		(connect_pads
			(clearance 0)
		)
		(min_thickness 0.25)
		(keepout
			(tracks not_allowed)
			(vias allowed)
			(pads allowed)
			(copperpour not_allowed)
			(footprints allowed)
		)
		(placement
			(enabled no)
			(sheetname "")
		)
		(fill yes
			(thermal_gap 0.5)
			(thermal_bridge_width 0.5)
			(island_removal_mode 0)
		)
		(polygon
			(pts
				(arc
					(start 239.832134 -44.802806)
					(mid 238.054134 -44.802806)
					(end 239.832134 -44.802806)
				)
			)
		)
	)
	(zone
		(layers "In1.Cu" "In3.Cu" "In5.Cu" "In7.Cu" "In8.Cu" "In9.Cu" "In10.Cu"
			"In12.Cu" "In14.Cu" "In16.Cu"
		)
		(hatch none 0.5)
		(connect_pads
			(clearance 0)
		)
		(min_thickness 0.25)
		(keepout
			(tracks not_allowed)
			(vias allowed)
			(pads allowed)
			(copperpour not_allowed)
			(footprints allowed)
		)
		(placement
			(enabled no)
			(sheetname "")
		)
		(fill yes
			(thermal_gap 0.5)
			(thermal_bridge_width 0.5)
			(island_removal_mode 0)
		)
		(polygon
			(pts
				(arc
					(start 90.25382 -180.687472)
					(mid 88.4936 -180.687472)
					(end 90.25382 -180.687472)
				)
			)
		)
	)
	(zone
		(layers "In1.Cu" "In3.Cu" "In5.Cu" "In7.Cu" "In8.Cu" "In9.Cu" "In10.Cu"
			"In12.Cu" "In14.Cu" "In16.Cu"
		)
		(hatch none 0.5)
		(connect_pads
			(clearance 0)
		)
		(min_thickness 0.25)
		(keepout
			(tracks not_allowed)
			(vias allowed)
			(pads allowed)
			(copperpour not_allowed)
			(footprints allowed)
		)
		(placement
			(enabled no)
			(sheetname "")
		)
		(fill yes
			(thermal_gap 0.5)
			(thermal_bridge_width 0.5)
			(island_removal_mode 0)
		)
		(polygon
			(pts
				(arc
					(start 105.717594 -175.311054)
					(mid 103.939594 -175.311054)
					(end 105.717594 -175.311054)
				)
			)
		)
	)
	(zone
		(layers "In1.Cu" "In3.Cu" "In5.Cu" "In7.Cu" "In8.Cu" "In9.Cu" "In10.Cu"
			"In12.Cu" "In14.Cu" "In16.Cu"
		)
		(hatch none 0.5)
		(connect_pads
			(clearance 0)
		)
		(min_thickness 0.25)
		(keepout
			(tracks not_allowed)
			(vias allowed)
			(pads allowed)
			(copperpour not_allowed)
			(footprints allowed)
		)
		(placement
			(enabled no)
			(sheetname "")
		)
		(fill yes
			(thermal_gap 0.5)
			(thermal_bridge_width 0.5)
			(island_removal_mode 0)
		)
		(polygon
			(pts
				(arc
					(start 119.718074 -152.657556)
					(mid 117.940074 -152.657556)
					(end 119.718074 -152.657556)
				)
			)
		)
	)
	(zone
		(layers "In1.Cu" "In3.Cu" "In5.Cu" "In7.Cu" "In8.Cu" "In9.Cu" "In10.Cu"
			"In12.Cu" "In14.Cu" "In16.Cu"
		)
		(hatch none 0.5)
		(connect_pads
			(clearance 0)
		)
		(min_thickness 0.25)
		(keepout
			(tracks not_allowed)
			(vias allowed)
			(pads allowed)
			(copperpour not_allowed)
			(footprints allowed)
		)
		(placement
			(enabled no)
			(sheetname "")
		)
		(fill yes
			(thermal_gap 0.5)
			(thermal_bridge_width 0.5)
			(island_removal_mode 0)
		)
		(polygon
			(pts
				(arc
					(start 97.641664 -337.017614)
					(mid 95.881444 -337.017614)
					(end 97.641664 -337.017614)
				)
			)
		)
	)
	(zone
		(layers "In1.Cu" "In3.Cu" "In5.Cu" "In7.Cu" "In8.Cu" "In9.Cu" "In10.Cu"
			"In12.Cu" "In14.Cu" "In16.Cu"
		)
		(hatch none 0.5)
		(connect_pads
			(clearance 0)
		)
		(min_thickness 0.25)
		(keepout
			(tracks not_allowed)
			(vias allowed)
			(pads allowed)
			(copperpour not_allowed)
			(footprints allowed)
		)
		(placement
			(enabled no)
			(sheetname "")
		)
		(fill yes
			(thermal_gap 0.5)
			(thermal_bridge_width 0.5)
			(island_removal_mode 0)
		)
		(polygon
			(pts
				(arc
					(start 83.11134 -349.569786)
					(mid 81.33334 -349.569786)
					(end 83.11134 -349.569786)
				)
			)
		)
	)
	(zone
		(layers "In1.Cu" "In3.Cu" "In5.Cu" "In7.Cu" "In8.Cu" "In9.Cu" "In10.Cu"
			"In12.Cu" "In14.Cu" "In16.Cu"
		)
		(hatch none 0.5)
		(connect_pads
			(clearance 0)
		)
		(min_thickness 0.25)
		(keepout
			(tracks not_allowed)
			(vias allowed)
			(pads allowed)
			(copperpour not_allowed)
			(footprints allowed)
		)
		(placement
			(enabled no)
			(sheetname "")
		)
		(fill yes
			(thermal_gap 0.5)
			(thermal_bridge_width 0.5)
			(island_removal_mode 0)
		)
		(polygon
			(pts
				(arc
					(start 344.905838 -158.336996)
					(mid 343.127838 -158.336996)
					(end 344.905838 -158.336996)
				)
			)
		)
	)
	(zone
		(layers "In1.Cu" "In3.Cu" "In5.Cu" "In7.Cu" "In8.Cu" "In9.Cu" "In10.Cu"
			"In12.Cu" "In14.Cu" "In16.Cu"
		)
		(hatch none 0.5)
		(connect_pads
			(clearance 0)
		)
		(min_thickness 0.25)
		(keepout
			(tracks not_allowed)
			(vias allowed)
			(pads allowed)
			(copperpour not_allowed)
			(footprints allowed)
		)
		(placement
			(enabled no)
			(sheetname "")
		)
		(fill yes
			(thermal_gap 0.5)
			(thermal_bridge_width 0.5)
			(island_removal_mode 0)
		)
		(polygon
			(pts
				(arc
					(start 342.191848 -353.010216)
					(mid 340.413848 -353.010216)
					(end 342.191848 -353.010216)
				)
			)
		)
	)
	(zone
		(layers "In1.Cu" "In3.Cu" "In5.Cu" "In7.Cu" "In8.Cu" "In9.Cu" "In10.Cu"
			"In12.Cu" "In14.Cu" "In16.Cu"
		)
		(hatch none 0.5)
		(connect_pads
			(clearance 0)
		)
		(min_thickness 0.25)
		(keepout
			(tracks not_allowed)
			(vias allowed)
			(pads allowed)
			(copperpour not_allowed)
			(footprints allowed)
		)
		(placement
			(enabled no)
			(sheetname "")
		)
		(fill yes
			(thermal_gap 0.5)
			(thermal_bridge_width 0.5)
			(island_removal_mode 0)
		)
		(polygon
			(pts
				(arc
					(start 130.16103 -154.109674)
					(mid 128.38303 -154.109674)
					(end 130.16103 -154.109674)
				)
			)
		)
	)
	(zone
		(layers "In1.Cu" "In3.Cu" "In5.Cu" "In7.Cu" "In8.Cu" "In9.Cu" "In10.Cu"
			"In12.Cu" "In14.Cu" "In16.Cu"
		)
		(hatch none 0.5)
		(connect_pads
			(clearance 0)
		)
		(min_thickness 0.25)
		(keepout
			(tracks not_allowed)
			(vias allowed)
			(pads allowed)
			(copperpour not_allowed)
			(footprints allowed)
		)
		(placement
			(enabled no)
			(sheetname "")
		)
		(fill yes
			(thermal_gap 0.5)
			(thermal_bridge_width 0.5)
			(island_removal_mode 0)
		)
		(polygon
			(pts
				(arc
					(start 404.409402 -164.996368)
					(mid 402.631402 -164.996368)
					(end 404.409402 -164.996368)
				)
			)
		)
	)
	(zone
		(layers "In1.Cu" "In3.Cu" "In5.Cu" "In7.Cu" "In8.Cu" "In9.Cu" "In10.Cu"
			"In12.Cu" "In14.Cu" "In16.Cu"
		)
		(hatch none 0.5)
		(connect_pads
			(clearance 0)
		)
		(min_thickness 0.25)
		(keepout
			(tracks not_allowed)
			(vias allowed)
			(pads allowed)
			(copperpour not_allowed)
			(footprints allowed)
		)
		(placement
			(enabled no)
			(sheetname "")
		)
		(fill yes
			(thermal_gap 0.5)
			(thermal_bridge_width 0.5)
			(island_removal_mode 0)
		)
		(polygon
			(pts
				(arc
					(start 252.405134 -51.612546)
					(mid 250.627134 -51.612546)
					(end 252.405134 -51.612546)
				)
			)
		)
	)
	(zone
		(layers "In1.Cu" "In3.Cu" "In5.Cu" "In7.Cu" "In8.Cu" "In9.Cu" "In10.Cu"
			"In12.Cu" "In14.Cu" "In16.Cu"
		)
		(hatch none 0.5)
		(connect_pads
			(clearance 0)
		)
		(min_thickness 0.25)
		(keepout
			(tracks not_allowed)
			(vias allowed)
			(pads allowed)
			(copperpour not_allowed)
			(footprints allowed)
		)
		(placement
			(enabled no)
			(sheetname "")
		)
		(fill yes
			(thermal_gap 0.5)
			(thermal_bridge_width 0.5)
			(island_removal_mode 0)
		)
		(polygon
			(pts
				(arc
					(start 286.758126 -347.982032)
					(mid 284.980126 -347.982032)
					(end 286.758126 -347.982032)
				)
			)
		)
	)
	(zone
		(layers "In1.Cu" "In3.Cu" "In5.Cu" "In7.Cu" "In8.Cu" "In9.Cu" "In10.Cu"
			"In12.Cu" "In14.Cu" "In16.Cu"
		)
		(hatch none 0.5)
		(connect_pads
			(clearance 0)
		)
		(min_thickness 0.25)
		(keepout
			(tracks not_allowed)
			(vias allowed)
			(pads allowed)
			(copperpour not_allowed)
			(footprints allowed)
		)
		(placement
			(enabled no)
			(sheetname "")
		)
		(fill yes
			(thermal_gap 0.5)
			(thermal_bridge_width 0.5)
			(island_removal_mode 0)
		)
		(polygon
			(pts
				(arc
					(start 346.906596 -338.621878)
					(mid 345.128596 -338.621878)
					(end 346.906596 -338.621878)
				)
			)
		)
	)
	(zone
		(layers "In1.Cu" "In3.Cu" "In5.Cu" "In7.Cu" "In8.Cu" "In9.Cu" "In10.Cu"
			"In12.Cu" "In14.Cu" "In16.Cu"
		)
		(hatch none 0.5)
		(connect_pads
			(clearance 0)
		)
		(min_thickness 0.25)
		(keepout
			(tracks not_allowed)
			(vias allowed)
			(pads allowed)
			(copperpour not_allowed)
			(footprints allowed)
		)
		(placement
			(enabled no)
			(sheetname "")
		)
		(fill yes
			(thermal_gap 0.5)
			(thermal_bridge_width 0.5)
			(island_removal_mode 0)
		)
		(polygon
			(pts
				(arc
					(start 96.25203 -180.627274)
					(mid 94.47403 -180.627274)
					(end 96.25203 -180.627274)
				)
			)
		)
	)
	(zone
		(layers "In1.Cu" "In3.Cu" "In5.Cu" "In7.Cu" "In8.Cu" "In9.Cu" "In10.Cu"
			"In12.Cu" "In14.Cu" "In16.Cu"
		)
		(hatch none 0.5)
		(connect_pads
			(clearance 0)
		)
		(min_thickness 0.25)
		(keepout
			(tracks not_allowed)
			(vias allowed)
			(pads allowed)
			(copperpour not_allowed)
			(footprints allowed)
		)
		(placement
			(enabled no)
			(sheetname "")
		)
		(fill yes
			(thermal_gap 0.5)
			(thermal_bridge_width 0.5)
			(island_removal_mode 0)
		)
		(polygon
			(pts
				(arc
					(start 75.738482 -353.131374)
					(mid 73.960482 -353.131374)
					(end 75.738482 -353.131374)
				)
			)
		)
	)
	(zone
		(layers "In1.Cu" "In3.Cu" "In5.Cu" "In7.Cu" "In8.Cu" "In9.Cu" "In10.Cu"
			"In12.Cu" "In14.Cu" "In16.Cu"
		)
		(hatch none 0.5)
		(connect_pads
			(clearance 0)
		)
		(min_thickness 0.25)
		(keepout
			(tracks not_allowed)
			(vias allowed)
			(pads allowed)
			(copperpour not_allowed)
			(footprints allowed)
		)
		(placement
			(enabled no)
			(sheetname "")
		)
		(fill yes
			(thermal_gap 0.5)
			(thermal_bridge_width 0.5)
			(island_removal_mode 0)
		)
		(polygon
			(pts
				(arc
					(start 304.964846 -350.255332)
					(mid 303.186846 -350.255332)
					(end 304.964846 -350.255332)
				)
			)
		)
	)
	(zone
		(layers "In1.Cu" "In3.Cu" "In5.Cu" "In7.Cu" "In8.Cu" "In9.Cu" "In10.Cu"
			"In12.Cu" "In14.Cu" "In16.Cu"
		)
		(hatch none 0.5)
		(connect_pads
			(clearance 0)
		)
		(min_thickness 0.25)
		(keepout
			(tracks not_allowed)
			(vias allowed)
			(pads allowed)
			(copperpour not_allowed)
			(footprints allowed)
		)
		(placement
			(enabled no)
			(sheetname "")
		)
		(fill yes
			(thermal_gap 0.5)
			(thermal_bridge_width 0.5)
			(island_removal_mode 0)
		)
		(polygon
			(pts
				(arc
					(start 295.035986 -347.959172)
					(mid 293.257986 -347.959172)
					(end 295.035986 -347.959172)
				)
			)
		)
	)
	(zone
		(layers "In1.Cu" "In3.Cu" "In5.Cu" "In7.Cu" "In8.Cu" "In9.Cu" "In10.Cu"
			"In12.Cu" "In14.Cu" "In16.Cu"
		)
		(hatch none 0.5)
		(connect_pads
			(clearance 0)
		)
		(min_thickness 0.25)
		(keepout
			(tracks not_allowed)
			(vias allowed)
			(pads allowed)
			(copperpour not_allowed)
			(footprints allowed)
		)
		(placement
			(enabled no)
			(sheetname "")
		)
		(fill yes
			(thermal_gap 0.5)
			(thermal_bridge_width 0.5)
			(island_removal_mode 0)
		)
		(polygon
			(pts
				(arc
					(start 117.782594 -152.022556)
					(mid 116.004594 -152.022556)
					(end 117.782594 -152.022556)
				)
			)
		)
	)
	(zone
		(layers "In1.Cu" "In3.Cu" "In5.Cu" "In7.Cu" "In8.Cu" "In9.Cu" "In10.Cu"
			"In12.Cu" "In14.Cu" "In16.Cu"
		)
		(hatch none 0.5)
		(connect_pads
			(clearance 0)
		)
		(min_thickness 0.25)
		(keepout
			(tracks not_allowed)
			(vias allowed)
			(pads allowed)
			(copperpour not_allowed)
			(footprints allowed)
		)
		(placement
			(enabled no)
			(sheetname "")
		)
		(fill yes
			(thermal_gap 0.5)
			(thermal_bridge_width 0.5)
			(island_removal_mode 0)
		)
		(polygon
			(pts
				(arc
					(start 85.773006 -350.239838)
					(mid 83.995006 -350.239838)
					(end 85.773006 -350.239838)
				)
			)
		)
	)
	(zone
		(layers "In1.Cu" "In3.Cu" "In5.Cu" "In7.Cu" "In8.Cu" "In9.Cu" "In10.Cu"
			"In12.Cu" "In14.Cu" "In16.Cu"
		)
		(hatch none 0.5)
		(connect_pads
			(clearance 0)
		)
		(min_thickness 0.25)
		(keepout
			(tracks not_allowed)
			(vias allowed)
			(pads allowed)
			(copperpour not_allowed)
			(footprints allowed)
		)
		(placement
			(enabled no)
			(sheetname "")
		)
		(fill yes
			(thermal_gap 0.5)
			(thermal_bridge_width 0.5)
			(island_removal_mode 0)
		)
		(polygon
			(pts
				(arc
					(start 111.537496 -150.941786)
					(mid 108.743496 -150.941786)
					(end 111.537496 -150.941786)
				)
			)
		)
	)
	(zone
		(layers "In1.Cu" "In3.Cu" "In5.Cu" "In7.Cu" "In8.Cu" "In9.Cu" "In10.Cu"
			"In12.Cu" "In14.Cu" "In16.Cu"
		)
		(hatch none 0.5)
		(connect_pads
			(clearance 0)
		)
		(min_thickness 0.25)
		(keepout
			(tracks not_allowed)
			(vias allowed)
			(pads allowed)
			(copperpour not_allowed)
			(footprints allowed)
		)
		(placement
			(enabled no)
			(sheetname "")
		)
		(fill yes
			(thermal_gap 0.5)
			(thermal_bridge_width 0.5)
			(island_removal_mode 0)
		)
		(polygon
			(pts
				(arc
					(start 252.405134 -50.723546)
					(mid 250.627134 -50.723546)
					(end 252.405134 -50.723546)
				)
			)
		)
	)
	(zone
		(layers "In1.Cu" "In3.Cu" "In5.Cu" "In7.Cu" "In8.Cu" "In9.Cu" "In10.Cu"
			"In12.Cu" "In14.Cu" "In16.Cu"
		)
		(hatch none 0.5)
		(connect_pads
			(clearance 0)
		)
		(min_thickness 0.25)
		(keepout
			(tracks not_allowed)
			(vias allowed)
			(pads allowed)
			(copperpour not_allowed)
			(footprints allowed)
		)
		(placement
			(enabled no)
			(sheetname "")
		)
		(fill yes
			(thermal_gap 0.5)
			(thermal_bridge_width 0.5)
			(island_removal_mode 0)
		)
		(polygon
			(pts
				(arc
					(start 70.387464 -24.55291)
					(mid 68.609464 -24.55291)
					(end 70.387464 -24.55291)
				)
			)
		)
	)
	(zone
		(layers "In1.Cu" "In3.Cu" "In5.Cu" "In7.Cu" "In8.Cu" "In9.Cu" "In10.Cu"
			"In12.Cu" "In14.Cu" "In16.Cu"
		)
		(hatch none 0.5)
		(connect_pads
			(clearance 0)
		)
		(min_thickness 0.25)
		(keepout
			(tracks not_allowed)
			(vias allowed)
			(pads allowed)
			(copperpour not_allowed)
			(footprints allowed)
		)
		(placement
			(enabled no)
			(sheetname "")
		)
		(fill yes
			(thermal_gap 0.5)
			(thermal_bridge_width 0.5)
			(island_removal_mode 0)
		)
		(polygon
			(pts
				(arc
					(start 442.364622 -14.123162)
					(mid 440.586622 -14.123162)
					(end 442.364622 -14.123162)
				)
			)
		)
	)
	(zone
		(layers "In1.Cu" "In3.Cu" "In5.Cu" "In7.Cu" "In8.Cu" "In9.Cu" "In10.Cu"
			"In12.Cu" "In14.Cu" "In16.Cu"
		)
		(hatch none 0.5)
		(connect_pads
			(clearance 0)
		)
		(min_thickness 0.25)
		(keepout
			(tracks not_allowed)
			(vias allowed)
			(pads allowed)
			(copperpour not_allowed)
			(footprints allowed)
		)
		(placement
			(enabled no)
			(sheetname "")
		)
		(fill yes
			(thermal_gap 0.5)
			(thermal_bridge_width 0.5)
			(island_removal_mode 0)
		)
		(polygon
			(pts
				(arc
					(start 296.049446 -349.137732)
					(mid 294.271446 -349.137732)
					(end 296.049446 -349.137732)
				)
			)
		)
	)
	(zone
		(layers "In1.Cu" "In3.Cu" "In5.Cu" "In7.Cu" "In8.Cu" "In9.Cu" "In10.Cu"
			"In12.Cu" "In14.Cu" "In16.Cu"
		)
		(hatch none 0.5)
		(connect_pads
			(clearance 0)
		)
		(min_thickness 0.25)
		(keepout
			(tracks not_allowed)
			(vias allowed)
			(pads allowed)
			(copperpour not_allowed)
			(footprints allowed)
		)
		(placement
			(enabled no)
			(sheetname "")
		)
		(fill yes
			(thermal_gap 0.5)
			(thermal_bridge_width 0.5)
			(island_removal_mode 0)
		)
		(polygon
			(pts
				(arc
					(start 53.511704 -393.292838)
					(mid 53.816504 -393.597638)
					(end 54.121304 -393.292838)
				)
				(arc
					(start 54.121304 -392.429238)
					(mid 53.816504 -392.124438)
					(end 53.511704 -392.429238)
				)
			)
		)
	)
	(zone
		(layers "In1.Cu" "In3.Cu" "In5.Cu" "In7.Cu" "In8.Cu" "In9.Cu" "In10.Cu"
			"In12.Cu" "In14.Cu" "In16.Cu"
		)
		(hatch none 0.5)
		(connect_pads
			(clearance 0)
		)
		(min_thickness 0.25)
		(keepout
			(tracks not_allowed)
			(vias allowed)
			(pads allowed)
			(copperpour not_allowed)
			(footprints allowed)
		)
		(placement
			(enabled no)
			(sheetname "")
		)
		(fill yes
			(thermal_gap 0.5)
			(thermal_bridge_width 0.5)
			(island_removal_mode 0)
		)
		(polygon
			(pts
				(arc
					(start 370.203984 -164.53358)
					(mid 368.425984 -164.53358)
					(end 370.203984 -164.53358)
				)
			)
		)
	)
	(zone
		(layers "In1.Cu" "In3.Cu" "In5.Cu" "In7.Cu" "In8.Cu" "In9.Cu" "In10.Cu"
			"In12.Cu" "In14.Cu" "In16.Cu"
		)
		(hatch none 0.5)
		(connect_pads
			(clearance 0)
		)
		(min_thickness 0.25)
		(keepout
			(tracks not_allowed)
			(vias allowed)
			(pads allowed)
			(copperpour not_allowed)
			(footprints allowed)
		)
		(placement
			(enabled no)
			(sheetname "")
		)
		(fill yes
			(thermal_gap 0.5)
			(thermal_bridge_width 0.5)
			(island_removal_mode 0)
		)
		(polygon
			(pts
				(arc
					(start 289.80511 -356.584758)
					(mid 288.02711 -356.584758)
					(end 289.80511 -356.584758)
				)
			)
		)
	)
	(zone
		(layers "In1.Cu" "In3.Cu" "In5.Cu" "In7.Cu" "In8.Cu" "In9.Cu" "In10.Cu"
			"In12.Cu" "In14.Cu" "In16.Cu"
		)
		(hatch none 0.5)
		(connect_pads
			(clearance 0)
		)
		(min_thickness 0.25)
		(keepout
			(tracks not_allowed)
			(vias allowed)
			(pads allowed)
			(copperpour not_allowed)
			(footprints allowed)
		)
		(placement
			(enabled no)
			(sheetname "")
		)
		(fill yes
			(thermal_gap 0.5)
			(thermal_bridge_width 0.5)
			(island_removal_mode 0)
		)
		(polygon
			(pts
				(arc
					(start 404.993856 -167.320214)
					(mid 403.215856 -167.320214)
					(end 404.993856 -167.320214)
				)
			)
		)
	)
	(zone
		(layers "In1.Cu" "In3.Cu" "In5.Cu" "In7.Cu" "In8.Cu" "In9.Cu" "In10.Cu"
			"In12.Cu" "In14.Cu" "In16.Cu"
		)
		(hatch none 0.5)
		(connect_pads
			(clearance 0)
		)
		(min_thickness 0.25)
		(keepout
			(tracks not_allowed)
			(vias allowed)
			(pads allowed)
			(copperpour not_allowed)
			(footprints allowed)
		)
		(placement
			(enabled no)
			(sheetname "")
		)
		(fill yes
			(thermal_gap 0.5)
			(thermal_bridge_width 0.5)
			(island_removal_mode 0)
		)
		(polygon
			(pts
				(arc
					(start 107.90301 -343.249504)
					(mid 106.12501 -343.249504)
					(end 107.90301 -343.249504)
				)
			)
		)
	)
	(zone
		(layers "In1.Cu" "In3.Cu" "In5.Cu" "In7.Cu" "In8.Cu" "In9.Cu" "In10.Cu"
			"In12.Cu" "In14.Cu" "In16.Cu"
		)
		(hatch none 0.5)
		(connect_pads
			(clearance 0)
		)
		(min_thickness 0.25)
		(keepout
			(tracks not_allowed)
			(vias allowed)
			(pads allowed)
			(copperpour not_allowed)
			(footprints allowed)
		)
		(placement
			(enabled no)
			(sheetname "")
		)
		(fill yes
			(thermal_gap 0.5)
			(thermal_bridge_width 0.5)
			(island_removal_mode 0)
		)
		(polygon
			(pts
				(arc
					(start 345.989402 -157.541976)
					(mid 344.211402 -157.541976)
					(end 345.989402 -157.541976)
				)
			)
		)
	)
	(zone
		(layers "In1.Cu" "In3.Cu" "In5.Cu" "In7.Cu" "In8.Cu" "In9.Cu" "In10.Cu"
			"In12.Cu" "In14.Cu" "In16.Cu"
		)
		(hatch none 0.5)
		(connect_pads
			(clearance 0)
		)
		(min_thickness 0.25)
		(keepout
			(tracks not_allowed)
			(vias allowed)
			(pads allowed)
			(copperpour not_allowed)
			(footprints allowed)
		)
		(placement
			(enabled no)
			(sheetname "")
		)
		(fill yes
			(thermal_gap 0.5)
			(thermal_bridge_width 0.5)
			(island_removal_mode 0)
		)
		(polygon
			(pts
				(arc
					(start 105.16743 -174.988474)
					(mid 103.38943 -174.988474)
					(end 105.16743 -174.988474)
				)
			)
		)
	)
	(zone
		(layers "In1.Cu" "In3.Cu" "In5.Cu" "In7.Cu" "In8.Cu" "In9.Cu" "In10.Cu"
			"In12.Cu" "In14.Cu" "In16.Cu"
		)
		(hatch none 0.5)
		(connect_pads
			(clearance 0)
		)
		(min_thickness 0.25)
		(keepout
			(tracks not_allowed)
			(vias allowed)
			(pads allowed)
			(copperpour not_allowed)
			(footprints allowed)
		)
		(placement
			(enabled no)
			(sheetname "")
		)
		(fill yes
			(thermal_gap 0.5)
			(thermal_bridge_width 0.5)
			(island_removal_mode 0)
		)
		(polygon
			(pts
				(arc
					(start 436.011828 -353.56165)
					(mid 434.233828 -353.56165)
					(end 436.011828 -353.56165)
				)
			)
		)
	)
	(zone
		(layers "In1.Cu" "In3.Cu" "In5.Cu" "In7.Cu" "In8.Cu" "In9.Cu" "In10.Cu"
			"In12.Cu" "In14.Cu" "In16.Cu"
		)
		(hatch none 0.5)
		(connect_pads
			(clearance 0)
		)
		(min_thickness 0.25)
		(keepout
			(tracks not_allowed)
			(vias allowed)
			(pads allowed)
			(copperpour not_allowed)
			(footprints allowed)
		)
		(placement
			(enabled no)
			(sheetname "")
		)
		(fill yes
			(thermal_gap 0.5)
			(thermal_bridge_width 0.5)
			(island_removal_mode 0)
		)
		(polygon
			(pts
				(arc
					(start 412.241238 -160.584388)
					(mid 410.463238 -160.584388)
					(end 412.241238 -160.584388)
				)
			)
		)
	)
	(zone
		(layers "In1.Cu" "In3.Cu" "In5.Cu" "In7.Cu" "In8.Cu" "In9.Cu" "In10.Cu"
			"In12.Cu" "In14.Cu" "In16.Cu"
		)
		(hatch none 0.5)
		(connect_pads
			(clearance 0)
		)
		(min_thickness 0.25)
		(keepout
			(tracks not_allowed)
			(vias allowed)
			(pads allowed)
			(copperpour not_allowed)
			(footprints allowed)
		)
		(placement
			(enabled no)
			(sheetname "")
		)
		(fill yes
			(thermal_gap 0.5)
			(thermal_bridge_width 0.5)
			(island_removal_mode 0)
		)
		(polygon
			(pts
				(arc
					(start 330.767944 -338.171536)
					(mid 328.989944 -338.171536)
					(end 330.767944 -338.171536)
				)
			)
		)
	)
	(zone
		(layers "In1.Cu" "In3.Cu" "In5.Cu" "In7.Cu" "In8.Cu" "In9.Cu" "In10.Cu"
			"In12.Cu" "In14.Cu" "In16.Cu"
		)
		(hatch none 0.5)
		(connect_pads
			(clearance 0)
		)
		(min_thickness 0.25)
		(keepout
			(tracks not_allowed)
			(vias allowed)
			(pads allowed)
			(copperpour not_allowed)
			(footprints allowed)
		)
		(placement
			(enabled no)
			(sheetname "")
		)
		(fill yes
			(thermal_gap 0.5)
			(thermal_bridge_width 0.5)
			(island_removal_mode 0)
		)
		(polygon
			(pts
				(arc
					(start 91.163394 -337.399884)
					(mid 89.385394 -337.399884)
					(end 91.163394 -337.399884)
				)
			)
		)
	)
	(zone
		(layers "In1.Cu" "In3.Cu" "In5.Cu" "In7.Cu" "In8.Cu" "In9.Cu" "In10.Cu"
			"In12.Cu" "In14.Cu" "In16.Cu"
		)
		(hatch none 0.5)
		(connect_pads
			(clearance 0)
		)
		(min_thickness 0.25)
		(keepout
			(tracks not_allowed)
			(vias allowed)
			(pads allowed)
			(copperpour not_allowed)
			(footprints allowed)
		)
		(placement
			(enabled no)
			(sheetname "")
		)
		(fill yes
			(thermal_gap 0.5)
			(thermal_bridge_width 0.5)
			(island_removal_mode 0)
		)
		(polygon
			(pts
				(arc
					(start 48.711612 -393.292838)
					(mid 49.016412 -393.597638)
					(end 49.321212 -393.292838)
				)
				(arc
					(start 49.321212 -392.429238)
					(mid 49.016412 -392.124438)
					(end 48.711612 -392.429238)
				)
			)
		)
	)
	(zone
		(layers "In1.Cu" "In3.Cu" "In5.Cu" "In7.Cu" "In8.Cu" "In9.Cu" "In10.Cu"
			"In12.Cu" "In14.Cu" "In16.Cu"
		)
		(hatch none 0.5)
		(connect_pads
			(clearance 0)
		)
		(min_thickness 0.25)
		(keepout
			(tracks not_allowed)
			(vias allowed)
			(pads allowed)
			(copperpour not_allowed)
			(footprints allowed)
		)
		(placement
			(enabled no)
			(sheetname "")
		)
		(fill yes
			(thermal_gap 0.5)
			(thermal_bridge_width 0.5)
			(island_removal_mode 0)
		)
		(polygon
			(pts
				(arc
					(start 114.480848 -170.59656)
					(mid 112.702848 -170.59656)
					(end 114.480848 -170.59656)
				)
			)
		)
	)
	(zone
		(layers "In1.Cu" "In3.Cu" "In5.Cu" "In7.Cu" "In8.Cu" "In9.Cu" "In10.Cu"
			"In12.Cu" "In14.Cu" "In16.Cu"
		)
		(hatch none 0.5)
		(connect_pads
			(clearance 0)
		)
		(min_thickness 0.25)
		(keepout
			(tracks not_allowed)
			(vias allowed)
			(pads allowed)
			(copperpour not_allowed)
			(footprints allowed)
		)
		(placement
			(enabled no)
			(sheetname "")
		)
		(fill yes
			(thermal_gap 0.5)
			(thermal_bridge_width 0.5)
			(island_removal_mode 0)
		)
		(polygon
			(pts
				(arc
					(start 89.38133 -181.39664)
					(mid 87.60333 -181.39664)
					(end 89.38133 -181.39664)
				)
			)
		)
	)
	(zone
		(layers "In1.Cu" "In3.Cu" "In5.Cu" "In7.Cu" "In8.Cu" "In9.Cu" "In10.Cu"
			"In12.Cu" "In14.Cu" "In16.Cu"
		)
		(hatch none 0.5)
		(connect_pads
			(clearance 0)
		)
		(min_thickness 0.25)
		(keepout
			(tracks not_allowed)
			(vias allowed)
			(pads allowed)
			(copperpour not_allowed)
			(footprints allowed)
		)
		(placement
			(enabled no)
			(sheetname "")
		)
		(fill yes
			(thermal_gap 0.5)
			(thermal_bridge_width 0.5)
			(island_removal_mode 0)
		)
		(polygon
			(pts
				(arc
					(start 97.869248 -181.39664)
					(mid 96.091248 -181.39664)
					(end 97.869248 -181.39664)
				)
			)
		)
	)
	(zone
		(layers "In1.Cu" "In3.Cu" "In5.Cu" "In7.Cu" "In8.Cu" "In9.Cu" "In10.Cu"
			"In12.Cu" "In14.Cu" "In16.Cu"
		)
		(hatch none 0.5)
		(connect_pads
			(clearance 0)
		)
		(min_thickness 0.25)
		(keepout
			(tracks not_allowed)
			(vias allowed)
			(pads allowed)
			(copperpour not_allowed)
			(footprints allowed)
		)
		(placement
			(enabled no)
			(sheetname "")
		)
		(fill yes
			(thermal_gap 0.5)
			(thermal_bridge_width 0.5)
			(island_removal_mode 0)
		)
		(polygon
			(pts
				(arc
					(start 121.14403 -161.653474)
					(mid 119.36603 -161.653474)
					(end 121.14403 -161.653474)
				)
			)
		)
	)
	(zone
		(layers "In1.Cu" "In3.Cu" "In5.Cu" "In7.Cu" "In8.Cu" "In9.Cu" "In10.Cu"
			"In12.Cu" "In14.Cu" "In16.Cu"
		)
		(hatch none 0.5)
		(connect_pads
			(clearance 0)
		)
		(min_thickness 0.25)
		(keepout
			(tracks not_allowed)
			(vias allowed)
			(pads allowed)
			(copperpour not_allowed)
			(footprints allowed)
		)
		(placement
			(enabled no)
			(sheetname "")
		)
		(fill yes
			(thermal_gap 0.5)
			(thermal_bridge_width 0.5)
			(island_removal_mode 0)
		)
		(polygon
			(pts
				(arc
					(start 78.067408 -16.520668)
					(mid 76.289408 -16.520668)
					(end 78.067408 -16.520668)
				)
			)
		)
	)
	(zone
		(layers "In1.Cu" "In3.Cu" "In5.Cu" "In7.Cu" "In8.Cu" "In9.Cu" "In10.Cu"
			"In12.Cu" "In14.Cu" "In16.Cu"
		)
		(hatch none 0.5)
		(connect_pads
			(clearance 0)
		)
		(min_thickness 0.25)
		(keepout
			(tracks not_allowed)
			(vias allowed)
			(pads allowed)
			(copperpour not_allowed)
			(footprints allowed)
		)
		(placement
			(enabled no)
			(sheetname "")
		)
		(fill yes
			(thermal_gap 0.5)
			(thermal_bridge_width 0.5)
			(island_removal_mode 0)
		)
		(polygon
			(pts
				(arc
					(start 287.90011 -356.584758)
					(mid 286.12211 -356.584758)
					(end 287.90011 -356.584758)
				)
			)
		)
	)
	(zone
		(layers "In1.Cu" "In3.Cu" "In5.Cu" "In7.Cu" "In8.Cu" "In9.Cu" "In10.Cu"
			"In12.Cu" "In14.Cu" "In16.Cu"
		)
		(hatch none 0.5)
		(connect_pads
			(clearance 0)
		)
		(min_thickness 0.25)
		(keepout
			(tracks not_allowed)
			(vias allowed)
			(pads allowed)
			(copperpour not_allowed)
			(footprints allowed)
		)
		(placement
			(enabled no)
			(sheetname "")
		)
		(fill yes
			(thermal_gap 0.5)
			(thermal_bridge_width 0.5)
			(island_removal_mode 0)
		)
		(polygon
			(pts
				(arc
					(start 51.56073 -357.457502)
					(mid 49.78273 -357.457502)
					(end 51.56073 -357.457502)
				)
			)
		)
	)
	(zone
		(layers "In1.Cu" "In3.Cu" "In5.Cu" "In7.Cu" "In8.Cu" "In9.Cu" "In10.Cu"
			"In12.Cu" "In14.Cu" "In16.Cu"
		)
		(hatch none 0.5)
		(connect_pads
			(clearance 0)
		)
		(min_thickness 0.25)
		(keepout
			(tracks not_allowed)
			(vias allowed)
			(pads allowed)
			(copperpour not_allowed)
			(footprints allowed)
		)
		(placement
			(enabled no)
			(sheetname "")
		)
		(fill yes
			(thermal_gap 0.5)
			(thermal_bridge_width 0.5)
			(island_removal_mode 0)
		)
		(polygon
			(pts
				(arc
					(start 362.025438 -174.587916)
					(mid 360.247438 -174.587916)
					(end 362.025438 -174.587916)
				)
			)
		)
	)
	(zone
		(layers "In1.Cu" "In3.Cu" "In5.Cu" "In7.Cu" "In8.Cu" "In9.Cu" "In10.Cu"
			"In12.Cu" "In14.Cu" "In16.Cu"
		)
		(hatch none 0.5)
		(connect_pads
			(clearance 0)
		)
		(min_thickness 0.25)
		(keepout
			(tracks not_allowed)
			(vias allowed)
			(pads allowed)
			(copperpour not_allowed)
			(footprints allowed)
		)
		(placement
			(enabled no)
			(sheetname "")
		)
		(fill yes
			(thermal_gap 0.5)
			(thermal_bridge_width 0.5)
			(island_removal_mode 0)
		)
		(polygon
			(pts
				(arc
					(start 193.985134 -15.781528)
					(mid 192.207134 -15.781528)
					(end 193.985134 -15.781528)
				)
			)
		)
	)
	(zone
		(layers "In1.Cu" "In3.Cu" "In5.Cu" "In7.Cu" "In8.Cu" "In9.Cu" "In10.Cu"
			"In12.Cu" "In14.Cu" "In16.Cu"
		)
		(hatch none 0.5)
		(connect_pads
			(clearance 0)
		)
		(min_thickness 0.25)
		(keepout
			(tracks not_allowed)
			(vias allowed)
			(pads allowed)
			(copperpour not_allowed)
			(footprints allowed)
		)
		(placement
			(enabled no)
			(sheetname "")
		)
		(fill yes
			(thermal_gap 0.5)
			(thermal_bridge_width 0.5)
			(island_removal_mode 0)
		)
		(polygon
			(pts
				(arc
					(start 303.170336 -348.704662)
					(mid 301.410116 -348.704662)
					(end 303.170336 -348.704662)
				)
			)
		)
	)
	(zone
		(layers "In1.Cu" "In3.Cu" "In5.Cu" "In7.Cu" "In8.Cu" "In9.Cu" "In10.Cu"
			"In12.Cu" "In14.Cu" "In16.Cu"
		)
		(hatch none 0.5)
		(connect_pads
			(clearance 0)
		)
		(min_thickness 0.25)
		(keepout
			(tracks not_allowed)
			(vias allowed)
			(pads allowed)
			(copperpour not_allowed)
			(footprints allowed)
		)
		(placement
			(enabled no)
			(sheetname "")
		)
		(fill yes
			(thermal_gap 0.5)
			(thermal_bridge_width 0.5)
			(island_removal_mode 0)
		)
		(polygon
			(pts
				(arc
					(start 74.15022 -175.639222)
					(mid 72.39 -175.639222)
					(end 74.15022 -175.639222)
				)
			)
		)
	)
	(zone
		(layers "In1.Cu" "In3.Cu" "In5.Cu" "In7.Cu" "In8.Cu" "In9.Cu" "In10.Cu"
			"In12.Cu" "In14.Cu" "In16.Cu"
		)
		(hatch none 0.5)
		(connect_pads
			(clearance 0)
		)
		(min_thickness 0.25)
		(keepout
			(tracks not_allowed)
			(vias allowed)
			(pads allowed)
			(copperpour not_allowed)
			(footprints allowed)
		)
		(placement
			(enabled no)
			(sheetname "")
		)
		(fill yes
			(thermal_gap 0.5)
			(thermal_bridge_width 0.5)
			(island_removal_mode 0)
		)
		(polygon
			(pts
				(arc
					(start 49.253394 -349.904558)
					(mid 47.475394 -349.904558)
					(end 49.253394 -349.904558)
				)
			)
		)
	)
	(zone
		(layers "In1.Cu" "In3.Cu" "In5.Cu" "In7.Cu" "In8.Cu" "In9.Cu" "In10.Cu"
			"In12.Cu" "In14.Cu" "In16.Cu"
		)
		(hatch none 0.5)
		(connect_pads
			(clearance 0)
		)
		(min_thickness 0.25)
		(keepout
			(tracks not_allowed)
			(vias allowed)
			(pads allowed)
			(copperpour not_allowed)
			(footprints allowed)
		)
		(placement
			(enabled no)
			(sheetname "")
		)
		(fill yes
			(thermal_gap 0.5)
			(thermal_bridge_width 0.5)
			(island_removal_mode 0)
		)
		(polygon
			(pts
				(arc
					(start 41.480994 -348.786958)
					(mid 39.702994 -348.786958)
					(end 41.480994 -348.786958)
				)
			)
		)
	)
	(zone
		(layers "In1.Cu" "In3.Cu" "In5.Cu" "In7.Cu" "In8.Cu" "In9.Cu" "In10.Cu"
			"In12.Cu" "In14.Cu" "In16.Cu"
		)
		(hatch none 0.5)
		(connect_pads
			(clearance 0)
		)
		(min_thickness 0.25)
		(keepout
			(tracks not_allowed)
			(vias allowed)
			(pads allowed)
			(copperpour not_allowed)
			(footprints allowed)
		)
		(placement
			(enabled no)
			(sheetname "")
		)
		(fill yes
			(thermal_gap 0.5)
			(thermal_bridge_width 0.5)
			(island_removal_mode 0)
		)
		(polygon
			(pts
				(arc
					(start 356.222808 -167.507666)
					(mid 354.462588 -167.507666)
					(end 356.222808 -167.507666)
				)
			)
		)
	)
	(zone
		(layers "In1.Cu" "In3.Cu" "In5.Cu" "In7.Cu" "In8.Cu" "In9.Cu" "In10.Cu"
			"In12.Cu" "In14.Cu" "In16.Cu"
		)
		(hatch none 0.5)
		(connect_pads
			(clearance 0)
		)
		(min_thickness 0.25)
		(keepout
			(tracks not_allowed)
			(vias allowed)
			(pads allowed)
			(copperpour not_allowed)
			(footprints allowed)
		)
		(placement
			(enabled no)
			(sheetname "")
		)
		(fill yes
			(thermal_gap 0.5)
			(thermal_bridge_width 0.5)
			(island_removal_mode 0)
		)
		(polygon
			(pts
				(arc
					(start 129.60223 -153.728674)
					(mid 127.82423 -153.728674)
					(end 129.60223 -153.728674)
				)
			)
		)
	)
	(zone
		(layers "In1.Cu" "In3.Cu" "In5.Cu" "In7.Cu" "In8.Cu" "In9.Cu" "In10.Cu"
			"In12.Cu" "In14.Cu" "In16.Cu"
		)
		(hatch none 0.5)
		(connect_pads
			(clearance 0)
		)
		(min_thickness 0.25)
		(keepout
			(tracks not_allowed)
			(vias allowed)
			(pads allowed)
			(copperpour not_allowed)
			(footprints allowed)
		)
		(placement
			(enabled no)
			(sheetname "")
		)
		(fill yes
			(thermal_gap 0.5)
			(thermal_bridge_width 0.5)
			(island_removal_mode 0)
		)
		(polygon
			(pts
				(arc
					(start 191.397636 -22.856952)
					(mid 189.619636 -22.856952)
					(end 191.397636 -22.856952)
				)
			)
		)
	)
	(zone
		(layers "In1.Cu" "In3.Cu" "In5.Cu" "In7.Cu" "In8.Cu" "In9.Cu" "In10.Cu"
			"In12.Cu" "In14.Cu" "In16.Cu"
		)
		(hatch none 0.5)
		(connect_pads
			(clearance 0)
		)
		(min_thickness 0.25)
		(keepout
			(tracks not_allowed)
			(vias allowed)
			(pads allowed)
			(copperpour not_allowed)
			(footprints allowed)
		)
		(placement
			(enabled no)
			(sheetname "")
		)
		(fill yes
			(thermal_gap 0.5)
			(thermal_bridge_width 0.5)
			(island_removal_mode 0)
		)
		(polygon
			(pts
				(arc
					(start 83.072986 -348.89948)
					(mid 81.294986 -348.89948)
					(end 83.072986 -348.89948)
				)
			)
		)
	)
	(zone
		(layers "In1.Cu" "In3.Cu" "In5.Cu" "In7.Cu" "In8.Cu" "In9.Cu" "In10.Cu"
			"In12.Cu" "In14.Cu" "In16.Cu"
		)
		(hatch none 0.5)
		(connect_pads
			(clearance 0)
		)
		(min_thickness 0.25)
		(keepout
			(tracks not_allowed)
			(vias allowed)
			(pads allowed)
			(copperpour not_allowed)
			(footprints allowed)
		)
		(placement
			(enabled no)
			(sheetname "")
		)
		(fill yes
			(thermal_gap 0.5)
			(thermal_bridge_width 0.5)
			(island_removal_mode 0)
		)
		(polygon
			(pts
				(arc
					(start 80.810862 -17.502124)
					(mid 79.032862 -17.502124)
					(end 80.810862 -17.502124)
				)
			)
		)
	)
	(zone
		(layers "In1.Cu" "In3.Cu" "In5.Cu" "In7.Cu" "In8.Cu" "In9.Cu" "In10.Cu"
			"In12.Cu" "In14.Cu" "In16.Cu"
		)
		(hatch none 0.5)
		(connect_pads
			(clearance 0)
		)
		(min_thickness 0.25)
		(keepout
			(tracks not_allowed)
			(vias allowed)
			(pads allowed)
			(copperpour not_allowed)
			(footprints allowed)
		)
		(placement
			(enabled no)
			(sheetname "")
		)
		(fill yes
			(thermal_gap 0.5)
			(thermal_bridge_width 0.5)
			(island_removal_mode 0)
		)
		(polygon
			(pts
				(arc
					(start 88.56345 -163.447476)
					(mid 86.78545 -163.447476)
					(end 88.56345 -163.447476)
				)
			)
		)
	)
	(zone
		(layers "In1.Cu" "In3.Cu" "In5.Cu" "In7.Cu" "In8.Cu" "In9.Cu" "In10.Cu"
			"In12.Cu" "In14.Cu" "In16.Cu"
		)
		(hatch none 0.5)
		(connect_pads
			(clearance 0)
		)
		(min_thickness 0.25)
		(keepout
			(tracks not_allowed)
			(vias allowed)
			(pads allowed)
			(copperpour not_allowed)
			(footprints allowed)
		)
		(placement
			(enabled no)
			(sheetname "")
		)
		(fill yes
			(thermal_gap 0.5)
			(thermal_bridge_width 0.5)
			(island_removal_mode 0)
		)
		(polygon
			(pts
				(arc
					(start 96.25203 -179.154074)
					(mid 94.47403 -179.154074)
					(end 96.25203 -179.154074)
				)
			)
		)
	)
	(zone
		(layers "In1.Cu" "In3.Cu" "In5.Cu" "In7.Cu" "In8.Cu" "In9.Cu" "In10.Cu"
			"In12.Cu" "In14.Cu" "In16.Cu"
		)
		(hatch none 0.5)
		(connect_pads
			(clearance 0)
		)
		(min_thickness 0.25)
		(keepout
			(tracks not_allowed)
			(vias allowed)
			(pads allowed)
			(copperpour not_allowed)
			(footprints allowed)
		)
		(placement
			(enabled no)
			(sheetname "")
		)
		(fill yes
			(thermal_gap 0.5)
			(thermal_bridge_width 0.5)
			(island_removal_mode 0)
		)
		(polygon
			(pts
				(arc
					(start 285.890716 -348.704662)
					(mid 284.130496 -348.704662)
					(end 285.890716 -348.704662)
				)
			)
		)
	)
	(zone
		(layers "In1.Cu" "In3.Cu" "In5.Cu" "In7.Cu" "In8.Cu" "In9.Cu" "In10.Cu"
			"In12.Cu" "In14.Cu" "In16.Cu"
		)
		(hatch none 0.5)
		(connect_pads
			(clearance 0)
		)
		(min_thickness 0.25)
		(keepout
			(tracks not_allowed)
			(vias allowed)
			(pads allowed)
			(copperpour not_allowed)
			(footprints allowed)
		)
		(placement
			(enabled no)
			(sheetname "")
		)
		(fill yes
			(thermal_gap 0.5)
			(thermal_bridge_width 0.5)
			(island_removal_mode 0)
		)
		(polygon
			(pts
				(arc
					(start 69.066664 -25.56891)
					(mid 67.288664 -25.56891)
					(end 69.066664 -25.56891)
				)
			)
		)
	)
	(zone
		(layers "In1.Cu" "In3.Cu" "In5.Cu" "In7.Cu" "In8.Cu" "In9.Cu" "In10.Cu"
			"In12.Cu" "In14.Cu" "In16.Cu"
		)
		(hatch none 0.5)
		(connect_pads
			(clearance 0)
		)
		(min_thickness 0.25)
		(keepout
			(tracks not_allowed)
			(vias allowed)
			(pads allowed)
			(copperpour not_allowed)
			(footprints allowed)
		)
		(placement
			(enabled no)
			(sheetname "")
		)
		(fill yes
			(thermal_gap 0.5)
			(thermal_bridge_width 0.5)
			(island_removal_mode 0)
		)
		(polygon
			(pts
				(arc
					(start 75.008994 -338.539074)
					(mid 73.230994 -338.539074)
					(end 75.008994 -338.539074)
				)
			)
		)
	)
	(zone
		(layers "In1.Cu" "In3.Cu" "In5.Cu" "In7.Cu" "In8.Cu" "In9.Cu" "In10.Cu"
			"In12.Cu" "In14.Cu" "In16.Cu"
		)
		(hatch none 0.5)
		(connect_pads
			(clearance 0)
		)
		(min_thickness 0.25)
		(keepout
			(tracks not_allowed)
			(vias allowed)
			(pads allowed)
			(copperpour not_allowed)
			(footprints allowed)
		)
		(placement
			(enabled no)
			(sheetname "")
		)
		(fill yes
			(thermal_gap 0.5)
			(thermal_bridge_width 0.5)
			(island_removal_mode 0)
		)
		(polygon
			(pts
				(arc
					(start 356.265988 -342.000332)
					(mid 354.487988 -342.000332)
					(end 356.265988 -342.000332)
				)
			)
		)
	)
	(zone
		(layers "In1.Cu" "In3.Cu" "In5.Cu" "In7.Cu" "In8.Cu" "In9.Cu" "In10.Cu"
			"In12.Cu" "In14.Cu" "In16.Cu"
		)
		(hatch none 0.5)
		(connect_pads
			(clearance 0)
		)
		(min_thickness 0.25)
		(keepout
			(tracks not_allowed)
			(vias allowed)
			(pads allowed)
			(copperpour not_allowed)
			(footprints allowed)
		)
		(placement
			(enabled no)
			(sheetname "")
		)
		(fill yes
			(thermal_gap 0.5)
			(thermal_bridge_width 0.5)
			(island_removal_mode 0)
		)
		(polygon
			(pts
				(arc
					(start 107.87507 -342.540844)
					(mid 106.09707 -342.540844)
					(end 107.87507 -342.540844)
				)
			)
		)
	)
	(zone
		(layers "In1.Cu" "In3.Cu" "In5.Cu" "In7.Cu" "In8.Cu" "In9.Cu" "In10.Cu"
			"In12.Cu" "In14.Cu" "In16.Cu"
		)
		(hatch none 0.5)
		(connect_pads
			(clearance 0)
		)
		(min_thickness 0.25)
		(keepout
			(tracks not_allowed)
			(vias allowed)
			(pads allowed)
			(copperpour not_allowed)
			(footprints allowed)
		)
		(placement
			(enabled no)
			(sheetname "")
		)
		(fill yes
			(thermal_gap 0.5)
			(thermal_bridge_width 0.5)
			(island_removal_mode 0)
		)
		(polygon
			(pts
				(arc
					(start 202.634342 -346.583)
					(mid 200.856342 -346.583)
					(end 202.634342 -346.583)
				)
			)
		)
	)
	(zone
		(layers "In1.Cu" "In3.Cu" "In5.Cu" "In7.Cu" "In8.Cu" "In9.Cu" "In10.Cu"
			"In12.Cu" "In14.Cu" "In16.Cu"
		)
		(hatch none 0.5)
		(connect_pads
			(clearance 0)
		)
		(min_thickness 0.25)
		(keepout
			(tracks not_allowed)
			(vias allowed)
			(pads allowed)
			(copperpour not_allowed)
			(footprints allowed)
		)
		(placement
			(enabled no)
			(sheetname "")
		)
		(fill yes
			(thermal_gap 0.5)
			(thermal_bridge_width 0.5)
			(island_removal_mode 0)
		)
		(polygon
			(pts
				(arc
					(start 191.397636 -23.593552)
					(mid 189.619636 -23.593552)
					(end 191.397636 -23.593552)
				)
			)
		)
	)
	(zone
		(layers "In1.Cu" "In3.Cu" "In5.Cu" "In7.Cu" "In8.Cu" "In9.Cu" "In10.Cu"
			"In12.Cu" "In14.Cu" "In16.Cu"
		)
		(hatch none 0.5)
		(connect_pads
			(clearance 0)
		)
		(min_thickness 0.25)
		(keepout
			(tracks not_allowed)
			(vias allowed)
			(pads allowed)
			(copperpour not_allowed)
			(footprints allowed)
		)
		(placement
			(enabled no)
			(sheetname "")
		)
		(fill yes
			(thermal_gap 0.5)
			(thermal_bridge_width 0.5)
			(island_removal_mode 0)
		)
		(polygon
			(pts
				(arc
					(start 75.008994 -337.065874)
					(mid 73.230994 -337.065874)
					(end 75.008994 -337.065874)
				)
			)
		)
	)
	(zone
		(layers "In1.Cu" "In3.Cu" "In5.Cu" "In7.Cu" "In8.Cu" "In9.Cu" "In10.Cu"
			"In12.Cu" "In14.Cu" "In16.Cu"
		)
		(hatch none 0.5)
		(connect_pads
			(clearance 0)
		)
		(min_thickness 0.25)
		(keepout
			(tracks not_allowed)
			(vias allowed)
			(pads allowed)
			(copperpour not_allowed)
			(footprints allowed)
		)
		(placement
			(enabled no)
			(sheetname "")
		)
		(fill yes
			(thermal_gap 0.5)
			(thermal_bridge_width 0.5)
			(island_removal_mode 0)
		)
		(polygon
			(pts
				(arc
					(start 186.436254 -354.892864)
					(mid 184.658254 -354.892864)
					(end 186.436254 -354.892864)
				)
			)
		)
	)
	(zone
		(layers "In1.Cu" "In3.Cu" "In5.Cu" "In7.Cu" "In8.Cu" "In9.Cu" "In10.Cu"
			"In12.Cu" "In14.Cu" "In16.Cu"
		)
		(hatch none 0.5)
		(connect_pads
			(clearance 0)
		)
		(min_thickness 0.25)
		(keepout
			(tracks not_allowed)
			(vias allowed)
			(pads allowed)
			(copperpour not_allowed)
			(footprints allowed)
		)
		(placement
			(enabled no)
			(sheetname "")
		)
		(fill yes
			(thermal_gap 0.5)
			(thermal_bridge_width 0.5)
			(island_removal_mode 0)
		)
		(polygon
			(pts
				(arc
					(start 437.120538 -359.972102)
					(mid 435.342538 -359.972102)
					(end 437.120538 -359.972102)
				)
			)
		)
	)
	(zone
		(layers "In1.Cu" "In3.Cu" "In5.Cu" "In7.Cu" "In8.Cu" "In9.Cu" "In10.Cu"
			"In12.Cu" "In14.Cu" "In16.Cu"
		)
		(hatch none 0.5)
		(connect_pads
			(clearance 0)
		)
		(min_thickness 0.25)
		(keepout
			(tracks not_allowed)
			(vias allowed)
			(pads allowed)
			(copperpour not_allowed)
			(footprints allowed)
		)
		(placement
			(enabled no)
			(sheetname "")
		)
		(fill yes
			(thermal_gap 0.5)
			(thermal_bridge_width 0.5)
			(island_removal_mode 0)
		)
		(polygon
			(pts
				(arc
					(start 443.34049 -25.461976)
					(mid 441.56249 -25.461976)
					(end 443.34049 -25.461976)
				)
			)
		)
	)
	(zone
		(layers "In1.Cu" "In3.Cu" "In5.Cu" "In7.Cu" "In8.Cu" "In9.Cu" "In10.Cu"
			"In12.Cu" "In14.Cu" "In16.Cu"
		)
		(hatch none 0.5)
		(connect_pads
			(clearance 0)
		)
		(min_thickness 0.25)
		(keepout
			(tracks not_allowed)
			(vias allowed)
			(pads allowed)
			(copperpour not_allowed)
			(footprints allowed)
		)
		(placement
			(enabled no)
			(sheetname "")
		)
		(fill yes
			(thermal_gap 0.5)
			(thermal_bridge_width 0.5)
			(island_removal_mode 0)
		)
		(polygon
			(pts
				(arc
					(start 346.682568 -159.151066)
					(mid 344.922348 -159.151066)
					(end 346.682568 -159.151066)
				)
			)
		)
	)
	(zone
		(layers "In1.Cu" "In3.Cu" "In5.Cu" "In7.Cu" "In8.Cu" "In9.Cu" "In10.Cu"
			"In12.Cu" "In14.Cu" "In16.Cu"
		)
		(hatch none 0.5)
		(connect_pads
			(clearance 0)
		)
		(min_thickness 0.25)
		(keepout
			(tracks not_allowed)
			(vias allowed)
			(pads allowed)
			(copperpour not_allowed)
			(footprints allowed)
		)
		(placement
			(enabled no)
			(sheetname "")
		)
		(fill yes
			(thermal_gap 0.5)
			(thermal_bridge_width 0.5)
			(island_removal_mode 0)
		)
		(polygon
			(pts
				(arc
					(start 62.82563 -166.12616)
					(mid 61.04763 -166.12616)
					(end 62.82563 -166.12616)
				)
			)
		)
	)
	(zone
		(layers "In1.Cu" "In3.Cu" "In5.Cu" "In7.Cu" "In8.Cu" "In9.Cu" "In10.Cu"
			"In12.Cu" "In14.Cu" "In16.Cu"
		)
		(hatch none 0.5)
		(connect_pads
			(clearance 0)
		)
		(min_thickness 0.25)
		(keepout
			(tracks not_allowed)
			(vias allowed)
			(pads allowed)
			(copperpour not_allowed)
			(footprints allowed)
		)
		(placement
			(enabled no)
			(sheetname "")
		)
		(fill yes
			(thermal_gap 0.5)
			(thermal_bridge_width 0.5)
			(island_removal_mode 0)
		)
		(polygon
			(pts
				(arc
					(start 403.884638 -166.172388)
					(mid 402.106638 -166.172388)
					(end 403.884638 -166.172388)
				)
			)
		)
	)
	(zone
		(layers "In1.Cu" "In3.Cu" "In5.Cu" "In7.Cu" "In8.Cu" "In9.Cu" "In10.Cu"
			"In12.Cu" "In14.Cu" "In16.Cu"
		)
		(hatch none 0.5)
		(connect_pads
			(clearance 0)
		)
		(min_thickness 0.25)
		(keepout
			(tracks not_allowed)
			(vias allowed)
			(pads allowed)
			(copperpour not_allowed)
			(footprints allowed)
		)
		(placement
			(enabled no)
			(sheetname "")
		)
		(fill yes
			(thermal_gap 0.5)
			(thermal_bridge_width 0.5)
			(island_removal_mode 0)
		)
		(polygon
			(pts
				(arc
					(start 438.592214 -12.400788)
					(mid 436.814214 -12.400788)
					(end 438.592214 -12.400788)
				)
			)
		)
	)
	(zone
		(layers "In1.Cu" "In3.Cu" "In5.Cu" "In7.Cu" "In8.Cu" "In9.Cu" "In10.Cu"
			"In12.Cu" "In14.Cu" "In16.Cu"
		)
		(hatch none 0.5)
		(connect_pads
			(clearance 0)
		)
		(min_thickness 0.25)
		(keepout
			(tracks not_allowed)
			(vias allowed)
			(pads allowed)
			(copperpour not_allowed)
			(footprints allowed)
		)
		(placement
			(enabled no)
			(sheetname "")
		)
		(fill yes
			(thermal_gap 0.5)
			(thermal_bridge_width 0.5)
			(island_removal_mode 0)
		)
		(polygon
			(pts
				(arc
					(start 72.91578 -175.639222)
					(mid 71.15556 -175.639222)
					(end 72.91578 -175.639222)
				)
			)
		)
	)
	(zone
		(layers "In1.Cu" "In3.Cu" "In5.Cu" "In7.Cu" "In8.Cu" "In9.Cu" "In10.Cu"
			"In12.Cu" "In14.Cu" "In16.Cu"
		)
		(hatch none 0.5)
		(connect_pads
			(clearance 0)
		)
		(min_thickness 0.25)
		(keepout
			(tracks not_allowed)
			(vias allowed)
			(pads allowed)
			(copperpour not_allowed)
			(footprints allowed)
		)
		(placement
			(enabled no)
			(sheetname "")
		)
		(fill yes
			(thermal_gap 0.5)
			(thermal_bridge_width 0.5)
			(island_removal_mode 0)
		)
		(polygon
			(pts
				(arc
					(start 368.946684 -165.19398)
					(mid 367.168684 -165.19398)
					(end 368.946684 -165.19398)
				)
			)
		)
	)
	(zone
		(layers "In1.Cu" "In3.Cu" "In5.Cu" "In7.Cu" "In8.Cu" "In9.Cu" "In10.Cu"
			"In12.Cu" "In14.Cu" "In16.Cu"
		)
		(hatch none 0.5)
		(connect_pads
			(clearance 0)
		)
		(min_thickness 0.25)
		(keepout
			(tracks not_allowed)
			(vias allowed)
			(pads allowed)
			(copperpour not_allowed)
			(footprints allowed)
		)
		(placement
			(enabled no)
			(sheetname "")
		)
		(fill yes
			(thermal_gap 0.5)
			(thermal_bridge_width 0.5)
			(island_removal_mode 0)
		)
		(polygon
			(pts
				(arc
					(start 51.56073 -356.822502)
					(mid 49.78273 -356.822502)
					(end 51.56073 -356.822502)
				)
			)
		)
	)
	(zone
		(layers "In1.Cu" "In3.Cu" "In5.Cu" "In7.Cu" "In8.Cu" "In9.Cu" "In10.Cu"
			"In12.Cu" "In14.Cu" "In16.Cu"
		)
		(hatch none 0.5)
		(connect_pads
			(clearance 0)
		)
		(min_thickness 0.25)
		(keepout
			(tracks not_allowed)
			(vias allowed)
			(pads allowed)
			(copperpour not_allowed)
			(footprints allowed)
		)
		(placement
			(enabled no)
			(sheetname "")
		)
		(fill yes
			(thermal_gap 0.5)
			(thermal_bridge_width 0.5)
			(island_removal_mode 0)
		)
		(polygon
			(pts
				(arc
					(start 48.255174 -347.280738)
					(mid 46.477174 -347.280738)
					(end 48.255174 -347.280738)
				)
			)
		)
	)
	(zone
		(layers "In1.Cu" "In3.Cu" "In5.Cu" "In7.Cu" "In8.Cu" "In9.Cu" "In10.Cu"
			"In12.Cu" "In14.Cu" "In16.Cu"
		)
		(hatch none 0.5)
		(connect_pads
			(clearance 0)
		)
		(min_thickness 0.25)
		(keepout
			(tracks not_allowed)
			(vias allowed)
			(pads allowed)
			(copperpour not_allowed)
			(footprints allowed)
		)
		(placement
			(enabled no)
			(sheetname "")
		)
		(fill yes
			(thermal_gap 0.5)
			(thermal_bridge_width 0.5)
			(island_removal_mode 0)
		)
		(polygon
			(pts
				(arc
					(start 120.353074 -152.657556)
					(mid 118.575074 -152.657556)
					(end 120.353074 -152.657556)
				)
			)
		)
	)
	(zone
		(layers "In1.Cu" "In3.Cu" "In5.Cu" "In7.Cu" "In8.Cu" "In9.Cu" "In10.Cu"
			"In12.Cu" "In14.Cu" "In16.Cu"
		)
		(hatch none 0.5)
		(connect_pads
			(clearance 0)
		)
		(min_thickness 0.25)
		(keepout
			(tracks not_allowed)
			(vias allowed)
			(pads allowed)
			(copperpour not_allowed)
			(footprints allowed)
		)
		(placement
			(enabled no)
			(sheetname "")
		)
		(fill yes
			(thermal_gap 0.5)
			(thermal_bridge_width 0.5)
			(island_removal_mode 0)
		)
		(polygon
			(pts
				(arc
					(start 434.902102 -351.64649)
					(mid 433.124102 -351.64649)
					(end 434.902102 -351.64649)
				)
			)
		)
	)
	(zone
		(layers "In1.Cu" "In3.Cu" "In5.Cu" "In7.Cu" "In8.Cu" "In9.Cu" "In10.Cu"
			"In12.Cu" "In14.Cu" "In16.Cu"
		)
		(hatch none 0.5)
		(connect_pads
			(clearance 0)
		)
		(min_thickness 0.25)
		(keepout
			(tracks not_allowed)
			(vias allowed)
			(pads allowed)
			(copperpour not_allowed)
			(footprints allowed)
		)
		(placement
			(enabled no)
			(sheetname "")
		)
		(fill yes
			(thermal_gap 0.5)
			(thermal_bridge_width 0.5)
			(island_removal_mode 0)
		)
		(polygon
			(pts
				(arc
					(start 354.471478 -341.922862)
					(mid 352.711258 -341.922862)
					(end 354.471478 -341.922862)
				)
			)
		)
	)
	(zone
		(layers "In1.Cu" "In3.Cu" "In5.Cu" "In7.Cu" "In8.Cu" "In9.Cu" "In10.Cu"
			"In12.Cu" "In14.Cu" "In16.Cu"
		)
		(hatch none 0.5)
		(connect_pads
			(clearance 0)
		)
		(min_thickness 0.25)
		(keepout
			(tracks not_allowed)
			(vias allowed)
			(pads allowed)
			(copperpour not_allowed)
			(footprints allowed)
		)
		(placement
			(enabled no)
			(sheetname "")
		)
		(fill yes
			(thermal_gap 0.5)
			(thermal_bridge_width 0.5)
			(island_removal_mode 0)
		)
		(polygon
			(pts
				(arc
					(start 41.480994 -350.260158)
					(mid 39.702994 -350.260158)
					(end 41.480994 -350.260158)
				)
			)
		)
	)
	(zone
		(layers "In1.Cu" "In3.Cu" "In5.Cu" "In7.Cu" "In8.Cu" "In9.Cu" "In10.Cu"
			"In12.Cu" "In14.Cu" "In16.Cu"
		)
		(hatch none 0.5)
		(connect_pads
			(clearance 0)
		)
		(min_thickness 0.25)
		(keepout
			(tracks not_allowed)
			(vias allowed)
			(pads allowed)
			(copperpour not_allowed)
			(footprints allowed)
		)
		(placement
			(enabled no)
			(sheetname "")
		)
		(fill yes
			(thermal_gap 0.5)
			(thermal_bridge_width 0.5)
			(island_removal_mode 0)
		)
		(polygon
			(pts
				(arc
					(start 426.575474 -352.35769)
					(mid 424.797474 -352.35769)
					(end 426.575474 -352.35769)
				)
			)
		)
	)
	(zone
		(layers "In1.Cu" "In3.Cu" "In5.Cu" "In7.Cu" "In8.Cu" "In9.Cu" "In10.Cu"
			"In12.Cu" "In14.Cu" "In16.Cu"
		)
		(hatch none 0.5)
		(connect_pads
			(clearance 0)
		)
		(min_thickness 0.25)
		(keepout
			(tracks not_allowed)
			(vias allowed)
			(pads allowed)
			(copperpour not_allowed)
			(footprints allowed)
		)
		(placement
			(enabled no)
			(sheetname "")
		)
		(fill yes
			(thermal_gap 0.5)
			(thermal_bridge_width 0.5)
			(island_removal_mode 0)
		)
		(polygon
			(pts
				(arc
					(start 72.781668 -176.37252)
					(mid 71.003668 -176.37252)
					(end 72.781668 -176.37252)
				)
			)
		)
	)
	(zone
		(layers "In1.Cu" "In3.Cu" "In5.Cu" "In7.Cu" "In8.Cu" "In9.Cu" "In10.Cu"
			"In12.Cu" "In14.Cu" "In16.Cu"
		)
		(hatch none 0.5)
		(connect_pads
			(clearance 0)
		)
		(min_thickness 0.25)
		(keepout
			(tracks not_allowed)
			(vias allowed)
			(pads allowed)
			(copperpour not_allowed)
			(footprints allowed)
		)
		(placement
			(enabled no)
			(sheetname "")
		)
		(fill yes
			(thermal_gap 0.5)
			(thermal_bridge_width 0.5)
			(island_removal_mode 0)
		)
		(polygon
			(pts
				(arc
					(start 67.390264 -12.43711)
					(mid 65.612264 -12.43711)
					(end 67.390264 -12.43711)
				)
			)
		)
	)
	(zone
		(layers "In1.Cu" "In3.Cu" "In5.Cu" "In7.Cu" "In8.Cu" "In9.Cu" "In10.Cu"
			"In12.Cu" "In14.Cu" "In16.Cu"
		)
		(hatch none 0.5)
		(connect_pads
			(clearance 0)
		)
		(min_thickness 0.25)
		(keepout
			(tracks not_allowed)
			(vias allowed)
			(pads allowed)
			(copperpour not_allowed)
			(footprints allowed)
		)
		(placement
			(enabled no)
			(sheetname "")
		)
		(fill yes
			(thermal_gap 0.5)
			(thermal_bridge_width 0.5)
			(island_removal_mode 0)
		)
		(polygon
			(pts
				(arc
					(start 42.258742 -358.549194)
					(mid 40.480742 -358.549194)
					(end 42.258742 -358.549194)
				)
			)
		)
	)
	(zone
		(layers "In1.Cu" "In3.Cu" "In5.Cu" "In7.Cu" "In8.Cu" "In9.Cu" "In10.Cu"
			"In12.Cu" "In14.Cu" "In16.Cu"
		)
		(hatch none 0.5)
		(connect_pads
			(clearance 0)
		)
		(min_thickness 0.25)
		(keepout
			(tracks not_allowed)
			(vias allowed)
			(pads allowed)
			(copperpour not_allowed)
			(footprints allowed)
		)
		(placement
			(enabled no)
			(sheetname "")
		)
		(fill yes
			(thermal_gap 0.5)
			(thermal_bridge_width 0.5)
			(island_removal_mode 0)
		)
		(polygon
			(pts
				(arc
					(start 64.311784 -393.292838)
					(mid 64.616584 -393.597638)
					(end 64.921384 -393.292838)
				)
				(arc
					(start 64.921384 -392.429238)
					(mid 64.616584 -392.124438)
					(end 64.311784 -392.429238)
				)
			)
		)
	)
	(zone
		(layers "In1.Cu" "In3.Cu" "In5.Cu" "In7.Cu" "In8.Cu" "In9.Cu" "In10.Cu"
			"In12.Cu" "In14.Cu" "In16.Cu"
		)
		(hatch none 0.5)
		(connect_pads
			(clearance 0)
		)
		(min_thickness 0.25)
		(keepout
			(tracks not_allowed)
			(vias allowed)
			(pads allowed)
			(copperpour not_allowed)
			(footprints allowed)
		)
		(placement
			(enabled no)
			(sheetname "")
		)
		(fill yes
			(thermal_gap 0.5)
			(thermal_bridge_width 0.5)
			(island_removal_mode 0)
		)
		(polygon
			(pts
				(arc
					(start 81.130648 -181.483)
					(mid 79.352648 -181.483)
					(end 81.130648 -181.483)
				)
			)
		)
	)
	(zone
		(layers "In1.Cu" "In3.Cu" "In5.Cu" "In7.Cu" "In8.Cu" "In9.Cu" "In10.Cu"
			"In12.Cu" "In14.Cu" "In16.Cu"
		)
		(hatch none 0.5)
		(connect_pads
			(clearance 0)
		)
		(min_thickness 0.25)
		(keepout
			(tracks not_allowed)
			(vias allowed)
			(pads allowed)
			(copperpour not_allowed)
			(footprints allowed)
		)
		(placement
			(enabled no)
			(sheetname "")
		)
		(fill yes
			(thermal_gap 0.5)
			(thermal_bridge_width 0.5)
			(island_removal_mode 0)
		)
		(polygon
			(pts
				(arc
					(start 178.110134 -26.634948)
					(mid 176.332134 -26.634948)
					(end 178.110134 -26.634948)
				)
			)
		)
	)
	(zone
		(layers "In1.Cu" "In3.Cu" "In5.Cu" "In7.Cu" "In8.Cu" "In9.Cu" "In10.Cu"
			"In12.Cu" "In14.Cu" "In16.Cu"
		)
		(hatch none 0.5)
		(connect_pads
			(clearance 0)
		)
		(min_thickness 0.25)
		(keepout
			(tracks not_allowed)
			(vias allowed)
			(pads allowed)
			(copperpour not_allowed)
			(footprints allowed)
		)
		(placement
			(enabled no)
			(sheetname "")
		)
		(fill yes
			(thermal_gap 0.5)
			(thermal_bridge_width 0.5)
			(island_removal_mode 0)
		)
		(polygon
			(pts
				(arc
					(start 98.258884 -337.017614)
					(mid 96.498664 -337.017614)
					(end 98.258884 -337.017614)
				)
			)
		)
	)
	(zone
		(layers "In1.Cu" "In3.Cu" "In5.Cu" "In7.Cu" "In8.Cu" "In9.Cu" "In10.Cu"
			"In12.Cu" "In14.Cu" "In16.Cu"
		)
		(hatch none 0.5)
		(connect_pads
			(clearance 0)
		)
		(min_thickness 0.25)
		(keepout
			(tracks not_allowed)
			(vias allowed)
			(pads allowed)
			(copperpour not_allowed)
			(footprints allowed)
		)
		(placement
			(enabled no)
			(sheetname "")
		)
		(fill yes
			(thermal_gap 0.5)
			(thermal_bridge_width 0.5)
			(island_removal_mode 0)
		)
		(polygon
			(pts
				(arc
					(start 82.4738 -180.755544)
					(mid 80.71358 -180.755544)
					(end 82.4738 -180.755544)
				)
			)
		)
	)
	(zone
		(layers "In1.Cu" "In3.Cu" "In5.Cu" "In7.Cu" "In8.Cu" "In9.Cu" "In10.Cu"
			"In12.Cu" "In14.Cu" "In16.Cu"
		)
		(hatch none 0.5)
		(connect_pads
			(clearance 0)
		)
		(min_thickness 0.25)
		(keepout
			(tracks not_allowed)
			(vias allowed)
			(pads allowed)
			(copperpour not_allowed)
			(footprints allowed)
		)
		(placement
			(enabled no)
			(sheetname "")
		)
		(fill yes
			(thermal_gap 0.5)
			(thermal_bridge_width 0.5)
			(island_removal_mode 0)
		)
		(polygon
			(pts
				(arc
					(start 251.668534 -52.222146)
					(mid 249.890534 -52.222146)
					(end 251.668534 -52.222146)
				)
			)
		)
	)
	(zone
		(layers "In1.Cu" "In3.Cu" "In5.Cu" "In7.Cu" "In8.Cu" "In9.Cu" "In10.Cu"
			"In12.Cu" "In14.Cu" "In16.Cu"
		)
		(hatch none 0.5)
		(connect_pads
			(clearance 0)
		)
		(min_thickness 0.25)
		(keepout
			(tracks not_allowed)
			(vias allowed)
			(pads allowed)
			(copperpour not_allowed)
			(footprints allowed)
		)
		(placement
			(enabled no)
			(sheetname "")
		)
		(fill yes
			(thermal_gap 0.5)
			(thermal_bridge_width 0.5)
			(island_removal_mode 0)
		)
		(polygon
			(pts
				(arc
					(start 131.99618 -154.542744)
					(mid 130.23596 -154.542744)
					(end 131.99618 -154.542744)
				)
			)
		)
	)
	(zone
		(layers "In1.Cu" "In3.Cu" "In5.Cu" "In7.Cu" "In8.Cu" "In9.Cu" "In10.Cu"
			"In12.Cu" "In14.Cu" "In16.Cu"
		)
		(hatch none 0.5)
		(connect_pads
			(clearance 0)
		)
		(min_thickness 0.25)
		(keepout
			(tracks not_allowed)
			(vias allowed)
			(pads allowed)
			(copperpour not_allowed)
			(footprints allowed)
		)
		(placement
			(enabled no)
			(sheetname "")
		)
		(fill yes
			(thermal_gap 0.5)
			(thermal_bridge_width 0.5)
			(island_removal_mode 0)
		)
		(polygon
			(pts
				(arc
					(start 98.02876 -180.704744)
					(mid 96.26854 -180.704744)
					(end 98.02876 -180.704744)
				)
			)
		)
	)
	(zone
		(layers "In1.Cu" "In3.Cu" "In5.Cu" "In7.Cu" "In8.Cu" "In9.Cu" "In10.Cu"
			"In12.Cu" "In14.Cu" "In16.Cu"
		)
		(hatch none 0.5)
		(connect_pads
			(clearance 0)
		)
		(min_thickness 0.25)
		(keepout
			(tracks not_allowed)
			(vias allowed)
			(pads allowed)
			(copperpour not_allowed)
			(footprints allowed)
		)
		(placement
			(enabled no)
			(sheetname "")
		)
		(fill yes
			(thermal_gap 0.5)
			(thermal_bridge_width 0.5)
			(island_removal_mode 0)
		)
		(polygon
			(pts
				(arc
					(start 186.923172 -360.710988)
					(mid 185.145172 -360.710988)
					(end 186.923172 -360.710988)
				)
			)
		)
	)
	(zone
		(layers "In1.Cu" "In3.Cu" "In5.Cu" "In7.Cu" "In8.Cu" "In9.Cu" "In10.Cu"
			"In12.Cu" "In14.Cu" "In16.Cu"
		)
		(hatch none 0.5)
		(connect_pads
			(clearance 0)
		)
		(min_thickness 0.25)
		(keepout
			(tracks not_allowed)
			(vias allowed)
			(pads allowed)
			(copperpour not_allowed)
			(footprints allowed)
		)
		(placement
			(enabled no)
			(sheetname "")
		)
		(fill yes
			(thermal_gap 0.5)
			(thermal_bridge_width 0.5)
			(island_removal_mode 0)
		)
		(polygon
			(pts
				(arc
					(start 64.088264 -12.43711)
					(mid 62.310264 -12.43711)
					(end 64.088264 -12.43711)
				)
			)
		)
	)
	(zone
		(layers "In1.Cu" "In3.Cu" "In5.Cu" "In7.Cu" "In8.Cu" "In9.Cu" "In10.Cu"
			"In12.Cu" "In14.Cu" "In16.Cu"
		)
		(hatch none 0.5)
		(connect_pads
			(clearance 0)
		)
		(min_thickness 0.25)
		(keepout
			(tracks not_allowed)
			(vias allowed)
			(pads allowed)
			(copperpour not_allowed)
			(footprints allowed)
		)
		(placement
			(enabled no)
			(sheetname "")
		)
		(fill yes
			(thermal_gap 0.5)
			(thermal_bridge_width 0.5)
			(island_removal_mode 0)
		)
		(polygon
			(pts
				(arc
					(start 91.507056 -345.261184)
					(mid 89.729056 -345.261184)
					(end 91.507056 -345.261184)
				)
			)
		)
	)
	(zone
		(layers "In1.Cu" "In3.Cu" "In5.Cu" "In7.Cu" "In8.Cu" "In9.Cu" "In10.Cu"
			"In12.Cu" "In14.Cu" "In16.Cu"
		)
		(hatch none 0.5)
		(connect_pads
			(clearance 0)
		)
		(min_thickness 0.25)
		(keepout
			(tracks not_allowed)
			(vias allowed)
			(pads allowed)
			(copperpour not_allowed)
			(footprints allowed)
		)
		(placement
			(enabled no)
			(sheetname "")
		)
		(fill yes
			(thermal_gap 0.5)
			(thermal_bridge_width 0.5)
			(island_removal_mode 0)
		)
		(polygon
			(pts
				(arc
					(start 388.182358 -155.724352)
					(mid 386.404358 -155.724352)
					(end 388.182358 -155.724352)
				)
			)
		)
	)
	(zone
		(layers "In1.Cu" "In3.Cu" "In5.Cu" "In7.Cu" "In8.Cu" "In9.Cu" "In10.Cu"
			"In12.Cu" "In14.Cu" "In16.Cu"
		)
		(hatch none 0.5)
		(connect_pads
			(clearance 0)
		)
		(min_thickness 0.25)
		(keepout
			(tracks not_allowed)
			(vias allowed)
			(pads allowed)
			(copperpour not_allowed)
			(footprints allowed)
		)
		(placement
			(enabled no)
			(sheetname "")
		)
		(fill yes
			(thermal_gap 0.5)
			(thermal_bridge_width 0.5)
			(island_removal_mode 0)
		)
		(polygon
			(pts
				(arc
					(start 75.738736 -352.30816)
					(mid 73.960736 -352.30816)
					(end 75.738736 -352.30816)
				)
			)
		)
	)
	(zone
		(layers "In1.Cu" "In3.Cu" "In5.Cu" "In7.Cu" "In8.Cu" "In9.Cu" "In10.Cu"
			"In12.Cu" "In14.Cu" "In16.Cu"
		)
		(hatch none 0.5)
		(connect_pads
			(clearance 0)
		)
		(min_thickness 0.25)
		(keepout
			(tracks not_allowed)
			(vias allowed)
			(pads allowed)
			(copperpour not_allowed)
			(footprints allowed)
		)
		(placement
			(enabled no)
			(sheetname "")
		)
		(fill yes
			(thermal_gap 0.5)
			(thermal_bridge_width 0.5)
			(island_removal_mode 0)
		)
		(polygon
			(pts
				(arc
					(start 83.364578 -338.531962)
					(mid 81.586578 -338.531962)
					(end 83.364578 -338.531962)
				)
			)
		)
	)
	(zone
		(layers "In1.Cu" "In3.Cu" "In5.Cu" "In7.Cu" "In8.Cu" "In9.Cu" "In10.Cu"
			"In12.Cu" "In14.Cu" "In16.Cu"
		)
		(hatch none 0.5)
		(connect_pads
			(clearance 0)
		)
		(min_thickness 0.25)
		(keepout
			(tracks not_allowed)
			(vias allowed)
			(pads allowed)
			(copperpour not_allowed)
			(footprints allowed)
		)
		(placement
			(enabled no)
			(sheetname "")
		)
		(fill yes
			(thermal_gap 0.5)
			(thermal_bridge_width 0.5)
			(island_removal_mode 0)
		)
		(polygon
			(pts
				(arc
					(start 387.120638 -179.560474)
					(mid 385.342638 -179.560474)
					(end 387.120638 -179.560474)
				)
			)
		)
	)
	(zone
		(layers "In1.Cu" "In3.Cu" "In5.Cu" "In7.Cu" "In8.Cu" "In9.Cu" "In10.Cu"
			"In12.Cu" "In14.Cu" "In16.Cu"
		)
		(hatch none 0.5)
		(connect_pads
			(clearance 0)
		)
		(min_thickness 0.25)
		(keepout
			(tracks not_allowed)
			(vias allowed)
			(pads allowed)
			(copperpour not_allowed)
			(footprints allowed)
		)
		(placement
			(enabled no)
			(sheetname "")
		)
		(fill yes
			(thermal_gap 0.5)
			(thermal_bridge_width 0.5)
			(island_removal_mode 0)
		)
		(polygon
			(pts
				(arc
					(start 355.182424 -342.795352)
					(mid 353.404424 -342.795352)
					(end 355.182424 -342.795352)
				)
			)
		)
	)
	(zone
		(layers "In1.Cu" "In3.Cu" "In5.Cu" "In7.Cu" "In8.Cu" "In9.Cu" "In10.Cu"
			"In12.Cu" "In14.Cu" "In16.Cu"
		)
		(hatch none 0.5)
		(connect_pads
			(clearance 0)
		)
		(min_thickness 0.25)
		(keepout
			(tracks not_allowed)
			(vias allowed)
			(pads allowed)
			(copperpour not_allowed)
			(footprints allowed)
		)
		(placement
			(enabled no)
			(sheetname "")
		)
		(fill yes
			(thermal_gap 0.5)
			(thermal_bridge_width 0.5)
			(island_removal_mode 0)
		)
		(polygon
			(pts
				(arc
					(start 180.396134 -25.517348)
					(mid 178.618134 -25.517348)
					(end 180.396134 -25.517348)
				)
			)
		)
	)
	(zone
		(layers "In1.Cu" "In3.Cu" "In5.Cu" "In7.Cu" "In8.Cu" "In9.Cu" "In10.Cu"
			"In12.Cu" "In14.Cu" "In16.Cu"
		)
		(hatch none 0.5)
		(connect_pads
			(clearance 0)
		)
		(min_thickness 0.25)
		(keepout
			(tracks not_allowed)
			(vias allowed)
			(pads allowed)
			(copperpour not_allowed)
			(footprints allowed)
		)
		(placement
			(enabled no)
			(sheetname "")
		)
		(fill yes
			(thermal_gap 0.5)
			(thermal_bridge_width 0.5)
			(island_removal_mode 0)
		)
		(polygon
			(pts
				(arc
					(start 319.91681 -336.983578)
					(mid 318.15659 -336.983578)
					(end 319.91681 -336.983578)
				)
			)
		)
	)
	(zone
		(layers "In1.Cu" "In3.Cu" "In5.Cu" "In7.Cu" "In8.Cu" "In9.Cu" "In10.Cu"
			"In12.Cu" "In14.Cu" "In16.Cu"
		)
		(hatch none 0.5)
		(connect_pads
			(clearance 0)
		)
		(min_thickness 0.25)
		(keepout
			(tracks not_allowed)
			(vias allowed)
			(pads allowed)
			(copperpour not_allowed)
			(footprints allowed)
		)
		(placement
			(enabled no)
			(sheetname "")
		)
		(fill yes
			(thermal_gap 0.5)
			(thermal_bridge_width 0.5)
			(island_removal_mode 0)
		)
		(polygon
			(pts
				(arc
					(start 48.81753 -357.457502)
					(mid 47.03953 -357.457502)
					(end 48.81753 -357.457502)
				)
			)
		)
	)
	(zone
		(layers "In1.Cu" "In3.Cu" "In5.Cu" "In7.Cu" "In8.Cu" "In9.Cu" "In10.Cu"
			"In12.Cu" "In14.Cu" "In16.Cu"
		)
		(hatch none 0.5)
		(connect_pads
			(clearance 0)
		)
		(min_thickness 0.25)
		(keepout
			(tracks not_allowed)
			(vias allowed)
			(pads allowed)
			(copperpour not_allowed)
			(footprints allowed)
		)
		(placement
			(enabled no)
			(sheetname "")
		)
		(fill yes
			(thermal_gap 0.5)
			(thermal_bridge_width 0.5)
			(island_removal_mode 0)
		)
		(polygon
			(pts
				(arc
					(start 336.63001 -336.961988)
					(mid 334.86979 -336.961988)
					(end 336.63001 -336.961988)
				)
			)
		)
	)
	(zone
		(layers "In1.Cu" "In3.Cu" "In5.Cu" "In7.Cu" "In8.Cu" "In9.Cu" "In10.Cu"
			"In12.Cu" "In14.Cu" "In16.Cu"
		)
		(hatch none 0.5)
		(connect_pads
			(clearance 0)
		)
		(min_thickness 0.25)
		(keepout
			(tracks not_allowed)
			(vias allowed)
			(pads allowed)
			(copperpour not_allowed)
			(footprints allowed)
		)
		(placement
			(enabled no)
			(sheetname "")
		)
		(fill yes
			(thermal_gap 0.5)
			(thermal_bridge_width 0.5)
			(island_removal_mode 0)
		)
		(polygon
			(pts
				(arc
					(start 347.45676 -338.207858)
					(mid 345.67876 -338.207858)
					(end 347.45676 -338.207858)
				)
			)
		)
	)
	(zone
		(layers "In1.Cu" "In3.Cu" "In5.Cu" "In7.Cu" "In8.Cu" "In9.Cu" "In10.Cu"
			"In12.Cu" "In14.Cu" "In16.Cu"
		)
		(hatch none 0.5)
		(connect_pads
			(clearance 0)
		)
		(min_thickness 0.25)
		(keepout
			(tracks not_allowed)
			(vias allowed)
			(pads allowed)
			(copperpour not_allowed)
			(footprints allowed)
		)
		(placement
			(enabled no)
			(sheetname "")
		)
		(fill yes
			(thermal_gap 0.5)
			(thermal_bridge_width 0.5)
			(island_removal_mode 0)
		)
		(polygon
			(pts
				(arc
					(start 288.53511 -355.949758)
					(mid 286.75711 -355.949758)
					(end 288.53511 -355.949758)
				)
			)
		)
	)
	(zone
		(layers "In1.Cu" "In3.Cu" "In5.Cu" "In7.Cu" "In8.Cu" "In9.Cu" "In10.Cu"
			"In12.Cu" "In14.Cu" "In16.Cu"
		)
		(hatch none 0.5)
		(connect_pads
			(clearance 0)
		)
		(min_thickness 0.25)
		(keepout
			(tracks not_allowed)
			(vias allowed)
			(pads allowed)
			(copperpour not_allowed)
			(footprints allowed)
		)
		(placement
			(enabled no)
			(sheetname "")
		)
		(fill yes
			(thermal_gap 0.5)
			(thermal_bridge_width 0.5)
			(island_removal_mode 0)
		)
		(polygon
			(pts
				(arc
					(start 90.912442 -346.639896)
					(mid 89.134442 -346.639896)
					(end 90.912442 -346.639896)
				)
			)
		)
	)
	(zone
		(layers "In1.Cu" "In3.Cu" "In5.Cu" "In7.Cu" "In8.Cu" "In9.Cu" "In10.Cu"
			"In12.Cu" "In14.Cu" "In16.Cu"
		)
		(hatch none 0.5)
		(connect_pads
			(clearance 0)
		)
		(min_thickness 0.25)
		(keepout
			(tracks not_allowed)
			(vias allowed)
			(pads allowed)
			(copperpour not_allowed)
			(footprints allowed)
		)
		(placement
			(enabled no)
			(sheetname "")
		)
		(fill yes
			(thermal_gap 0.5)
			(thermal_bridge_width 0.5)
			(island_removal_mode 0)
		)
		(polygon
			(pts
				(arc
					(start 343.461848 -353.010216)
					(mid 341.683848 -353.010216)
					(end 343.461848 -353.010216)
				)
			)
		)
	)
	(zone
		(layers "In1.Cu" "In3.Cu" "In5.Cu" "In7.Cu" "In8.Cu" "In9.Cu" "In10.Cu"
			"In12.Cu" "In14.Cu" "In16.Cu"
		)
		(hatch none 0.5)
		(connect_pads
			(clearance 0)
		)
		(min_thickness 0.25)
		(keepout
			(tracks not_allowed)
			(vias allowed)
			(pads allowed)
			(copperpour not_allowed)
			(footprints allowed)
		)
		(placement
			(enabled no)
			(sheetname "")
		)
		(fill yes
			(thermal_gap 0.5)
			(thermal_bridge_width 0.5)
			(island_removal_mode 0)
		)
		(polygon
			(pts
				(arc
					(start 93.528642 -346.639896)
					(mid 91.750642 -346.639896)
					(end 93.528642 -346.639896)
				)
			)
		)
	)
	(zone
		(layers "In1.Cu" "In3.Cu" "In5.Cu" "In7.Cu" "In8.Cu" "In9.Cu" "In10.Cu"
			"In12.Cu" "In14.Cu" "In16.Cu"
		)
		(hatch none 0.5)
		(connect_pads
			(clearance 0)
		)
		(min_thickness 0.25)
		(keepout
			(tracks not_allowed)
			(vias allowed)
			(pads allowed)
			(copperpour not_allowed)
			(footprints allowed)
		)
		(placement
			(enabled no)
			(sheetname "")
		)
		(fill yes
			(thermal_gap 0.5)
			(thermal_bridge_width 0.5)
			(island_removal_mode 0)
		)
		(polygon
			(pts
				(arc
					(start 51.512978 -358.108504)
					(mid 49.734978 -358.108504)
					(end 51.512978 -358.108504)
				)
			)
		)
	)
	(zone
		(layers "In1.Cu" "In3.Cu" "In5.Cu" "In7.Cu" "In8.Cu" "In9.Cu" "In10.Cu"
			"In12.Cu" "In14.Cu" "In16.Cu"
		)
		(hatch none 0.5)
		(connect_pads
			(clearance 0)
		)
		(min_thickness 0.25)
		(keepout
			(tracks not_allowed)
			(vias allowed)
			(pads allowed)
			(copperpour not_allowed)
			(footprints allowed)
		)
		(placement
			(enabled no)
			(sheetname "")
		)
		(fill yes
			(thermal_gap 0.5)
			(thermal_bridge_width 0.5)
			(island_removal_mode 0)
		)
		(polygon
			(pts
				(arc
					(start 368.281204 -165.19398)
					(mid 366.503204 -165.19398)
					(end 368.281204 -165.19398)
				)
			)
		)
	)
	(zone
		(layers "In1.Cu" "In3.Cu" "In5.Cu" "In7.Cu" "In8.Cu" "In9.Cu" "In10.Cu"
			"In12.Cu" "In14.Cu" "In16.Cu"
		)
		(hatch none 0.5)
		(connect_pads
			(clearance 0)
		)
		(min_thickness 0.25)
		(keepout
			(tracks not_allowed)
			(vias allowed)
			(pads allowed)
			(copperpour not_allowed)
			(footprints allowed)
		)
		(placement
			(enabled no)
			(sheetname "")
		)
		(fill yes
			(thermal_gap 0.5)
			(thermal_bridge_width 0.5)
			(island_removal_mode 0)
		)
		(polygon
			(pts
				(arc
					(start 177.602134 -25.949148)
					(mid 175.824134 -25.949148)
					(end 177.602134 -25.949148)
				)
			)
		)
	)
	(zone
		(layers "In1.Cu" "In3.Cu" "In5.Cu" "In7.Cu" "In8.Cu" "In9.Cu" "In10.Cu"
			"In12.Cu" "In14.Cu" "In16.Cu"
		)
		(hatch none 0.5)
		(connect_pads
			(clearance 0)
		)
		(min_thickness 0.25)
		(keepout
			(tracks not_allowed)
			(vias allowed)
			(pads allowed)
			(copperpour not_allowed)
			(footprints allowed)
		)
		(placement
			(enabled no)
			(sheetname "")
		)
		(fill yes
			(thermal_gap 0.5)
			(thermal_bridge_width 0.5)
			(island_removal_mode 0)
		)
		(polygon
			(pts
				(arc
					(start 286.507936 -348.704662)
					(mid 284.747716 -348.704662)
					(end 286.507936 -348.704662)
				)
			)
		)
	)
	(zone
		(layers "In1.Cu" "In3.Cu" "In5.Cu" "In7.Cu" "In8.Cu" "In9.Cu" "In10.Cu"
			"In12.Cu" "In14.Cu" "In16.Cu"
		)
		(hatch none 0.5)
		(connect_pads
			(clearance 0)
		)
		(min_thickness 0.25)
		(keepout
			(tracks not_allowed)
			(vias allowed)
			(pads allowed)
			(copperpour not_allowed)
			(footprints allowed)
		)
		(placement
			(enabled no)
			(sheetname "")
		)
		(fill yes
			(thermal_gap 0.5)
			(thermal_bridge_width 0.5)
			(island_removal_mode 0)
		)
		(polygon
			(pts
				(arc
					(start 344.354404 -351.486216)
					(mid 342.576404 -351.486216)
					(end 344.354404 -351.486216)
				)
			)
		)
	)
	(zone
		(layers "In1.Cu" "In3.Cu" "In5.Cu" "In7.Cu" "In8.Cu" "In9.Cu" "In10.Cu"
			"In12.Cu" "In14.Cu" "In16.Cu"
		)
		(hatch none 0.5)
		(connect_pads
			(clearance 0)
		)
		(min_thickness 0.25)
		(keepout
			(tracks not_allowed)
			(vias allowed)
			(pads allowed)
			(copperpour not_allowed)
			(footprints allowed)
		)
		(placement
			(enabled no)
			(sheetname "")
		)
		(fill yes
			(thermal_gap 0.5)
			(thermal_bridge_width 0.5)
			(island_removal_mode 0)
		)
		(polygon
			(pts
				(arc
					(start 403.325838 -166.527988)
					(mid 401.547838 -166.527988)
					(end 403.325838 -166.527988)
				)
			)
		)
	)
	(zone
		(layers "In1.Cu" "In3.Cu" "In5.Cu" "In7.Cu" "In8.Cu" "In9.Cu" "In10.Cu"
			"In12.Cu" "In14.Cu" "In16.Cu"
		)
		(hatch none 0.5)
		(connect_pads
			(clearance 0)
		)
		(min_thickness 0.25)
		(keepout
			(tracks not_allowed)
			(vias allowed)
			(pads allowed)
			(copperpour not_allowed)
			(footprints allowed)
		)
		(placement
			(enabled no)
			(sheetname "")
		)
		(fill yes
			(thermal_gap 0.5)
			(thermal_bridge_width 0.5)
			(island_removal_mode 0)
		)
		(polygon
			(pts
				(arc
					(start 403.325838 -165.054788)
					(mid 401.547838 -165.054788)
					(end 403.325838 -165.054788)
				)
			)
		)
	)
	(zone
		(layers "In1.Cu" "In3.Cu" "In5.Cu" "In7.Cu" "In8.Cu" "In9.Cu" "In10.Cu"
			"In12.Cu" "In14.Cu" "In16.Cu"
		)
		(hatch none 0.5)
		(connect_pads
			(clearance 0)
		)
		(min_thickness 0.25)
		(keepout
			(tracks not_allowed)
			(vias allowed)
			(pads allowed)
			(copperpour not_allowed)
			(footprints allowed)
		)
		(placement
			(enabled no)
			(sheetname "")
		)
		(fill yes
			(thermal_gap 0.5)
			(thermal_bridge_width 0.5)
			(island_removal_mode 0)
		)
		(polygon
			(pts
				(arc
					(start 368.268504 -164.53358)
					(mid 366.490504 -164.53358)
					(end 368.268504 -164.53358)
				)
			)
		)
	)
	(zone
		(layers "In1.Cu" "In3.Cu" "In5.Cu" "In7.Cu" "In8.Cu" "In9.Cu" "In10.Cu"
			"In12.Cu" "In14.Cu" "In16.Cu"
		)
		(hatch none 0.5)
		(connect_pads
			(clearance 0)
		)
		(min_thickness 0.25)
		(keepout
			(tracks not_allowed)
			(vias allowed)
			(pads allowed)
			(copperpour not_allowed)
			(footprints allowed)
		)
		(placement
			(enabled no)
			(sheetname "")
		)
		(fill yes
			(thermal_gap 0.5)
			(thermal_bridge_width 0.5)
			(island_removal_mode 0)
		)
		(polygon
			(pts
				(arc
					(start 451.559676 -15.273782)
					(mid 449.781676 -15.273782)
					(end 451.559676 -15.273782)
				)
			)
		)
	)
	(zone
		(layers "In1.Cu" "In3.Cu" "In5.Cu" "In7.Cu" "In8.Cu" "In9.Cu" "In10.Cu"
			"In12.Cu" "In14.Cu" "In16.Cu"
		)
		(hatch none 0.5)
		(connect_pads
			(clearance 0)
		)
		(min_thickness 0.25)
		(keepout
			(tracks not_allowed)
			(vias allowed)
			(pads allowed)
			(copperpour not_allowed)
			(footprints allowed)
		)
		(placement
			(enabled no)
			(sheetname "")
		)
		(fill yes
			(thermal_gap 0.5)
			(thermal_bridge_width 0.5)
			(island_removal_mode 0)
		)
		(polygon
			(pts
				(arc
					(start 91.722194 -337.780884)
					(mid 89.944194 -337.780884)
					(end 91.722194 -337.780884)
				)
			)
		)
	)
	(zone
		(layers "In1.Cu" "In3.Cu" "In5.Cu" "In7.Cu" "In8.Cu" "In9.Cu" "In10.Cu"
			"In12.Cu" "In14.Cu" "In16.Cu"
		)
		(hatch none 0.5)
		(connect_pads
			(clearance 0)
		)
		(min_thickness 0.25)
		(keepout
			(tracks not_allowed)
			(vias allowed)
			(pads allowed)
			(copperpour not_allowed)
			(footprints allowed)
		)
		(placement
			(enabled no)
			(sheetname "")
		)
		(fill yes
			(thermal_gap 0.5)
			(thermal_bridge_width 0.5)
			(island_removal_mode 0)
		)
		(polygon
			(pts
				(arc
					(start 303.415446 -348.002352)
					(mid 301.637446 -348.002352)
					(end 303.415446 -348.002352)
				)
			)
		)
	)
	(zone
		(layers "In1.Cu" "In3.Cu" "In5.Cu" "In7.Cu" "In8.Cu" "In9.Cu" "In10.Cu"
			"In12.Cu" "In14.Cu" "In16.Cu"
		)
		(hatch none 0.5)
		(connect_pads
			(clearance 0)
		)
		(min_thickness 0.25)
		(keepout
			(tracks not_allowed)
			(vias allowed)
			(pads allowed)
			(copperpour not_allowed)
			(footprints allowed)
		)
		(placement
			(enabled no)
			(sheetname "")
		)
		(fill yes
			(thermal_gap 0.5)
			(thermal_bridge_width 0.5)
			(island_removal_mode 0)
		)
		(polygon
			(pts
				(arc
					(start 287.26511 -356.584758)
					(mid 285.48711 -356.584758)
					(end 287.26511 -356.584758)
				)
			)
		)
	)
	(zone
		(layers "In1.Cu" "In3.Cu" "In5.Cu" "In7.Cu" "In8.Cu" "In9.Cu" "In10.Cu"
			"In12.Cu" "In14.Cu" "In16.Cu"
		)
		(hatch none 0.5)
		(connect_pads
			(clearance 0)
		)
		(min_thickness 0.25)
		(keepout
			(tracks not_allowed)
			(vias allowed)
			(pads allowed)
			(copperpour not_allowed)
			(footprints allowed)
		)
		(placement
			(enabled no)
			(sheetname "")
		)
		(fill yes
			(thermal_gap 0.5)
			(thermal_bridge_width 0.5)
			(island_removal_mode 0)
		)
		(polygon
			(pts
				(arc
					(start 82.805778 -337.414362)
					(mid 81.027778 -337.414362)
					(end 82.805778 -337.414362)
				)
			)
		)
	)
	(zone
		(layers "In1.Cu" "In3.Cu" "In5.Cu" "In7.Cu" "In8.Cu" "In9.Cu" "In10.Cu"
			"In12.Cu" "In14.Cu" "In16.Cu"
		)
		(hatch none 0.5)
		(connect_pads
			(clearance 0)
		)
		(min_thickness 0.25)
		(keepout
			(tracks not_allowed)
			(vias allowed)
			(pads allowed)
			(copperpour not_allowed)
			(footprints allowed)
		)
		(placement
			(enabled no)
			(sheetname "")
		)
		(fill yes
			(thermal_gap 0.5)
			(thermal_bridge_width 0.5)
			(island_removal_mode 0)
		)
		(polygon
			(pts
				(arc
					(start 88.54313 -164.097716)
					(mid 86.76513 -164.097716)
					(end 88.54313 -164.097716)
				)
			)
		)
	)
	(zone
		(layers "In1.Cu" "In3.Cu" "In5.Cu" "In7.Cu" "In8.Cu" "In9.Cu" "In10.Cu"
			"In12.Cu" "In14.Cu" "In16.Cu"
		)
		(hatch none 0.5)
		(connect_pads
			(clearance 0)
		)
		(min_thickness 0.25)
		(keepout
			(tracks not_allowed)
			(vias allowed)
			(pads allowed)
			(copperpour not_allowed)
			(footprints allowed)
		)
		(placement
			(enabled no)
			(sheetname "")
		)
		(fill yes
			(thermal_gap 0.5)
			(thermal_bridge_width 0.5)
			(island_removal_mode 0)
		)
		(polygon
			(pts
				(arc
					(start 369.568984 -164.53358)
					(mid 367.790984 -164.53358)
					(end 369.568984 -164.53358)
				)
			)
		)
	)
	(zone
		(layers "In1.Cu" "In3.Cu" "In5.Cu" "In7.Cu" "In8.Cu" "In9.Cu" "In10.Cu"
			"In12.Cu" "In14.Cu" "In16.Cu"
		)
		(hatch none 0.5)
		(connect_pads
			(clearance 0)
		)
		(min_thickness 0.25)
		(keepout
			(tracks not_allowed)
			(vias allowed)
			(pads allowed)
			(copperpour not_allowed)
			(footprints allowed)
		)
		(placement
			(enabled no)
			(sheetname "")
		)
		(fill yes
			(thermal_gap 0.5)
			(thermal_bridge_width 0.5)
			(island_removal_mode 0)
		)
		(polygon
			(pts
				(arc
					(start 395.517878 -173.21911)
					(mid 393.739878 -173.21911)
					(end 395.517878 -173.21911)
				)
			)
		)
	)
	(zone
		(layers "In1.Cu" "In3.Cu" "In5.Cu" "In7.Cu" "In8.Cu" "In9.Cu" "In10.Cu"
			"In12.Cu" "In14.Cu" "In16.Cu"
		)
		(hatch none 0.5)
		(connect_pads
			(clearance 0)
		)
		(min_thickness 0.25)
		(keepout
			(tracks not_allowed)
			(vias allowed)
			(pads allowed)
			(copperpour not_allowed)
			(footprints allowed)
		)
		(placement
			(enabled no)
			(sheetname "")
		)
		(fill yes
			(thermal_gap 0.5)
			(thermal_bridge_width 0.5)
			(island_removal_mode 0)
		)
		(polygon
			(pts
				(arc
					(start 64.062864 -348.709488)
					(mid 62.302644 -348.709488)
					(end 64.062864 -348.709488)
				)
			)
		)
	)
	(zone
		(layers "In1.Cu" "In3.Cu" "In5.Cu" "In7.Cu" "In8.Cu" "In9.Cu" "In10.Cu"
			"In12.Cu" "In14.Cu" "In16.Cu"
		)
		(hatch none 0.5)
		(connect_pads
			(clearance 0)
		)
		(min_thickness 0.25)
		(keepout
			(tracks not_allowed)
			(vias allowed)
			(pads allowed)
			(copperpour not_allowed)
			(footprints allowed)
		)
		(placement
			(enabled no)
			(sheetname "")
		)
		(fill yes
			(thermal_gap 0.5)
			(thermal_bridge_width 0.5)
			(island_removal_mode 0)
		)
		(polygon
			(pts
				(arc
					(start 247.762522 -52.022502)
					(mid 245.984522 -52.022502)
					(end 247.762522 -52.022502)
				)
			)
		)
	)
	(zone
		(layers "In1.Cu" "In3.Cu" "In5.Cu" "In7.Cu" "In8.Cu" "In9.Cu" "In10.Cu"
			"In12.Cu" "In14.Cu" "In16.Cu"
		)
		(hatch none 0.5)
		(connect_pads
			(clearance 0)
		)
		(min_thickness 0.25)
		(keepout
			(tracks not_allowed)
			(vias allowed)
			(pads allowed)
			(copperpour not_allowed)
			(footprints allowed)
		)
		(placement
			(enabled no)
			(sheetname "")
		)
		(fill yes
			(thermal_gap 0.5)
			(thermal_bridge_width 0.5)
			(island_removal_mode 0)
		)
		(polygon
			(pts
				(arc
					(start 278.227536 -348.704662)
					(mid 276.467316 -348.704662)
					(end 278.227536 -348.704662)
				)
			)
		)
	)
	(zone
		(layers "In1.Cu" "In3.Cu" "In5.Cu" "In7.Cu" "In8.Cu" "In9.Cu" "In10.Cu"
			"In12.Cu" "In14.Cu" "In16.Cu"
		)
		(hatch none 0.5)
		(connect_pads
			(clearance 0)
		)
		(min_thickness 0.25)
		(keepout
			(tracks not_allowed)
			(vias allowed)
			(pads allowed)
			(copperpour not_allowed)
			(footprints allowed)
		)
		(placement
			(enabled no)
			(sheetname "")
		)
		(fill yes
			(thermal_gap 0.5)
			(thermal_bridge_width 0.5)
			(island_removal_mode 0)
		)
		(polygon
			(pts
				(arc
					(start 240.467134 -44.040806)
					(mid 238.689134 -44.040806)
					(end 240.467134 -44.040806)
				)
			)
		)
	)
	(zone
		(layers "In1.Cu" "In3.Cu" "In5.Cu" "In7.Cu" "In8.Cu" "In9.Cu" "In10.Cu"
			"In12.Cu" "In14.Cu" "In16.Cu"
		)
		(hatch none 0.5)
		(connect_pads
			(clearance 0)
		)
		(min_thickness 0.25)
		(keepout
			(tracks not_allowed)
			(vias allowed)
			(pads allowed)
			(copperpour not_allowed)
			(footprints allowed)
		)
		(placement
			(enabled no)
			(sheetname "")
		)
		(fill yes
			(thermal_gap 0.5)
			(thermal_bridge_width 0.5)
			(island_removal_mode 0)
		)
		(polygon
			(pts
				(arc
					(start 414.101788 -161.779458)
					(mid 412.341568 -161.779458)
					(end 414.101788 -161.779458)
				)
			)
		)
	)
	(zone
		(layers "In1.Cu" "In3.Cu" "In5.Cu" "In7.Cu" "In8.Cu" "In9.Cu" "In10.Cu"
			"In12.Cu" "In14.Cu" "In16.Cu"
		)
		(hatch none 0.5)
		(connect_pads
			(clearance 0)
		)
		(min_thickness 0.25)
		(keepout
			(tracks not_allowed)
			(vias allowed)
			(pads allowed)
			(copperpour not_allowed)
			(footprints allowed)
		)
		(placement
			(enabled no)
			(sheetname "")
		)
		(fill yes
			(thermal_gap 0.5)
			(thermal_bridge_width 0.5)
			(island_removal_mode 0)
		)
		(polygon
			(pts
				(arc
					(start 396.670276 -175.895254)
					(mid 394.892276 -175.895254)
					(end 396.670276 -175.895254)
				)
			)
		)
	)
	(zone
		(layers "In1.Cu" "In3.Cu" "In5.Cu" "In7.Cu" "In8.Cu" "In9.Cu" "In10.Cu"
			"In12.Cu" "In14.Cu" "In16.Cu"
		)
		(hatch none 0.5)
		(connect_pads
			(clearance 0)
		)
		(min_thickness 0.25)
		(keepout
			(tracks not_allowed)
			(vias allowed)
			(pads allowed)
			(copperpour not_allowed)
			(footprints allowed)
		)
		(placement
			(enabled no)
			(sheetname "")
		)
		(fill yes
			(thermal_gap 0.5)
			(thermal_bridge_width 0.5)
			(island_removal_mode 0)
		)
		(polygon
			(pts
				(arc
					(start 87.85987 -179.136802)
					(mid 86.08187 -179.136802)
					(end 87.85987 -179.136802)
				)
			)
		)
	)
	(zone
		(layers "In1.Cu" "In3.Cu" "In5.Cu" "In7.Cu" "In8.Cu" "In9.Cu" "In10.Cu"
			"In12.Cu" "In14.Cu" "In16.Cu"
		)
		(hatch none 0.5)
		(connect_pads
			(clearance 0)
		)
		(min_thickness 0.25)
		(keepout
			(tracks not_allowed)
			(vias allowed)
			(pads allowed)
			(copperpour not_allowed)
			(footprints allowed)
		)
		(placement
			(enabled no)
			(sheetname "")
		)
		(fill yes
			(thermal_gap 0.5)
			(thermal_bridge_width 0.5)
			(island_removal_mode 0)
		)
		(polygon
			(pts
				(arc
					(start 440.370214 -12.400788)
					(mid 438.592214 -12.400788)
					(end 440.370214 -12.400788)
				)
			)
		)
	)
	(zone
		(layers "In1.Cu" "In3.Cu" "In5.Cu" "In7.Cu" "In8.Cu" "In9.Cu" "In10.Cu"
			"In12.Cu" "In14.Cu" "In16.Cu"
		)
		(hatch none 0.5)
		(connect_pads
			(clearance 0)
		)
		(min_thickness 0.25)
		(keepout
			(tracks not_allowed)
			(vias allowed)
			(pads allowed)
			(copperpour not_allowed)
			(footprints allowed)
		)
		(placement
			(enabled no)
			(sheetname "")
		)
		(fill yes
			(thermal_gap 0.5)
			(thermal_bridge_width 0.5)
			(island_removal_mode 0)
		)
		(polygon
			(pts
				(arc
					(start 177.767234 -19.942048)
					(mid 175.989234 -19.942048)
					(end 177.767234 -19.942048)
				)
			)
		)
	)
	(zone
		(layers "In1.Cu" "In3.Cu" "In5.Cu" "In7.Cu" "In8.Cu" "In9.Cu" "In10.Cu"
			"In12.Cu" "In14.Cu" "In16.Cu"
		)
		(hatch none 0.5)
		(connect_pads
			(clearance 0)
		)
		(min_thickness 0.25)
		(keepout
			(tracks not_allowed)
			(vias allowed)
			(pads allowed)
			(copperpour not_allowed)
			(footprints allowed)
		)
		(placement
			(enabled no)
			(sheetname "")
		)
		(fill yes
			(thermal_gap 0.5)
			(thermal_bridge_width 0.5)
			(island_removal_mode 0)
		)
		(polygon
			(pts
				(arc
					(start 119.083074 -152.022556)
					(mid 117.305074 -152.022556)
					(end 119.083074 -152.022556)
				)
			)
		)
	)
	(zone
		(layers "In1.Cu" "In3.Cu" "In5.Cu" "In7.Cu" "In8.Cu" "In9.Cu" "In10.Cu"
			"In12.Cu" "In14.Cu" "In16.Cu"
		)
		(hatch none 0.5)
		(connect_pads
			(clearance 0)
		)
		(min_thickness 0.25)
		(keepout
			(tracks not_allowed)
			(vias allowed)
			(pads allowed)
			(copperpour not_allowed)
			(footprints allowed)
		)
		(placement
			(enabled no)
			(sheetname "")
		)
		(fill yes
			(thermal_gap 0.5)
			(thermal_bridge_width 0.5)
			(island_removal_mode 0)
		)
		(polygon
			(pts
				(arc
					(start 433.41036 -361.827826)
					(mid 430.61636 -361.827826)
					(end 433.41036 -361.827826)
				)
			)
		)
	)
	(zone
		(layers "In1.Cu" "In3.Cu" "In5.Cu" "In7.Cu" "In8.Cu" "In9.Cu" "In10.Cu"
			"In12.Cu" "In14.Cu" "In16.Cu"
		)
		(hatch none 0.5)
		(connect_pads
			(clearance 0)
		)
		(min_thickness 0.25)
		(keepout
			(tracks not_allowed)
			(vias allowed)
			(pads allowed)
			(copperpour not_allowed)
			(footprints allowed)
		)
		(placement
			(enabled no)
			(sheetname "")
		)
		(fill yes
			(thermal_gap 0.5)
			(thermal_bridge_width 0.5)
			(island_removal_mode 0)
		)
		(polygon
			(pts
				(arc
					(start 411.707838 -160.228788)
					(mid 409.929838 -160.228788)
					(end 411.707838 -160.228788)
				)
			)
		)
	)
	(zone
		(layers "In1.Cu" "In3.Cu" "In5.Cu" "In7.Cu" "In8.Cu" "In9.Cu" "In10.Cu"
			"In12.Cu" "In14.Cu" "In16.Cu"
		)
		(hatch none 0.5)
		(connect_pads
			(clearance 0)
		)
		(min_thickness 0.25)
		(keepout
			(tracks not_allowed)
			(vias allowed)
			(pads allowed)
			(copperpour not_allowed)
			(footprints allowed)
		)
		(placement
			(enabled no)
			(sheetname "")
		)
		(fill yes
			(thermal_gap 0.5)
			(thermal_bridge_width 0.5)
			(island_removal_mode 0)
		)
		(polygon
			(pts
				(arc
					(start 321.15125 -336.983578)
					(mid 319.39103 -336.983578)
					(end 321.15125 -336.983578)
				)
			)
		)
	)
	(zone
		(layers "In1.Cu" "In3.Cu" "In5.Cu" "In7.Cu" "In8.Cu" "In9.Cu" "In10.Cu"
			"In12.Cu" "In14.Cu" "In16.Cu"
		)
		(hatch none 0.5)
		(connect_pads
			(clearance 0)
		)
		(min_thickness 0.25)
		(keepout
			(tracks not_allowed)
			(vias allowed)
			(pads allowed)
			(copperpour not_allowed)
			(footprints allowed)
		)
		(placement
			(enabled no)
			(sheetname "")
		)
		(fill yes
			(thermal_gap 0.5)
			(thermal_bridge_width 0.5)
			(island_removal_mode 0)
		)
		(polygon
			(pts
				(arc
					(start 381.267208 -180.755544)
					(mid 379.506988 -180.755544)
					(end 381.267208 -180.755544)
				)
			)
		)
	)
	(zone
		(layers "In1.Cu" "In3.Cu" "In5.Cu" "In7.Cu" "In8.Cu" "In9.Cu" "In10.Cu"
			"In12.Cu" "In14.Cu" "In16.Cu"
		)
		(hatch none 0.5)
		(connect_pads
			(clearance 0)
		)
		(min_thickness 0.25)
		(keepout
			(tracks not_allowed)
			(vias allowed)
			(pads allowed)
			(copperpour not_allowed)
			(footprints allowed)
		)
		(placement
			(enabled no)
			(sheetname "")
		)
		(fill yes
			(thermal_gap 0.5)
			(thermal_bridge_width 0.5)
			(island_removal_mode 0)
		)
		(polygon
			(pts
				(arc
					(start 72.781668 -177.10912)
					(mid 71.003668 -177.10912)
					(end 72.781668 -177.10912)
				)
			)
		)
	)
	(zone
		(layers "In1.Cu" "In3.Cu" "In5.Cu" "In7.Cu" "In8.Cu" "In9.Cu" "In10.Cu"
			"In12.Cu" "In14.Cu" "In16.Cu"
		)
		(hatch none 0.5)
		(connect_pads
			(clearance 0)
		)
		(min_thickness 0.25)
		(keepout
			(tracks not_allowed)
			(vias allowed)
			(pads allowed)
			(copperpour not_allowed)
			(footprints allowed)
		)
		(placement
			(enabled no)
			(sheetname "")
		)
		(fill yes
			(thermal_gap 0.5)
			(thermal_bridge_width 0.5)
			(island_removal_mode 0)
		)
		(polygon
			(pts
				(arc
					(start 88.41867 -180.254402)
					(mid 86.64067 -180.254402)
					(end 88.41867 -180.254402)
				)
			)
		)
	)
	(zone
		(layers "In1.Cu" "In3.Cu" "In5.Cu" "In7.Cu" "In8.Cu" "In9.Cu" "In10.Cu"
			"In12.Cu" "In14.Cu" "In16.Cu"
		)
		(hatch none 0.5)
		(connect_pads
			(clearance 0)
		)
		(min_thickness 0.25)
		(keepout
			(tracks not_allowed)
			(vias allowed)
			(pads allowed)
			(copperpour not_allowed)
			(footprints allowed)
		)
		(placement
			(enabled no)
			(sheetname "")
		)
		(fill yes
			(thermal_gap 0.5)
			(thermal_bridge_width 0.5)
			(island_removal_mode 0)
		)
		(polygon
			(pts
				(arc
					(start 378.256038 -179.204874)
					(mid 376.478038 -179.204874)
					(end 378.256038 -179.204874)
				)
			)
		)
	)
	(zone
		(layers "In1.Cu" "In3.Cu" "In5.Cu" "In7.Cu" "In8.Cu" "In9.Cu" "In10.Cu"
			"In12.Cu" "In14.Cu" "In16.Cu"
		)
		(hatch none 0.5)
		(connect_pads
			(clearance 0)
		)
		(min_thickness 0.25)
		(keepout
			(tracks not_allowed)
			(vias allowed)
			(pads allowed)
			(copperpour not_allowed)
			(footprints allowed)
		)
		(placement
			(enabled no)
			(sheetname "")
		)
		(fill yes
			(thermal_gap 0.5)
			(thermal_bridge_width 0.5)
			(island_removal_mode 0)
		)
		(polygon
			(pts
				(arc
					(start 87.85987 -179.873402)
					(mid 86.08187 -179.873402)
					(end 87.85987 -179.873402)
				)
			)
		)
	)
	(zone
		(layers "In1.Cu" "In3.Cu" "In5.Cu" "In7.Cu" "In8.Cu" "In9.Cu" "In10.Cu"
			"In12.Cu" "In14.Cu" "In16.Cu"
		)
		(hatch none 0.5)
		(connect_pads
			(clearance 0)
		)
		(min_thickness 0.25)
		(keepout
			(tracks not_allowed)
			(vias allowed)
			(pads allowed)
			(copperpour not_allowed)
			(footprints allowed)
		)
		(placement
			(enabled no)
			(sheetname "")
		)
		(fill yes
			(thermal_gap 0.5)
			(thermal_bridge_width 0.5)
			(island_removal_mode 0)
		)
		(polygon
			(pts
				(arc
					(start 115.8748 -169.935144)
					(mid 114.11458 -169.935144)
					(end 115.8748 -169.935144)
				)
			)
		)
	)
	(zone
		(layers "In1.Cu" "In3.Cu" "In5.Cu" "In7.Cu" "In8.Cu" "In9.Cu" "In10.Cu"
			"In12.Cu" "In14.Cu" "In16.Cu"
		)
		(hatch none 0.5)
		(connect_pads
			(clearance 0)
		)
		(min_thickness 0.25)
		(keepout
			(tracks not_allowed)
			(vias allowed)
			(pads allowed)
			(copperpour not_allowed)
			(footprints allowed)
		)
		(placement
			(enabled no)
			(sheetname "")
		)
		(fill yes
			(thermal_gap 0.5)
			(thermal_bridge_width 0.5)
			(island_removal_mode 0)
		)
		(polygon
			(pts
				(arc
					(start 344.35415 -353.006152)
					(mid 342.57615 -353.006152)
					(end 344.35415 -353.006152)
				)
			)
		)
	)
	(zone
		(layers "In1.Cu" "In3.Cu" "In5.Cu" "In7.Cu" "In8.Cu" "In9.Cu" "In10.Cu"
			"In12.Cu" "In14.Cu" "In16.Cu"
		)
		(hatch none 0.5)
		(connect_pads
			(clearance 0)
		)
		(min_thickness 0.25)
		(keepout
			(tracks not_allowed)
			(vias allowed)
			(pads allowed)
			(copperpour not_allowed)
			(footprints allowed)
		)
		(placement
			(enabled no)
			(sheetname "")
		)
		(fill yes
			(thermal_gap 0.5)
			(thermal_bridge_width 0.5)
			(island_removal_mode 0)
		)
		(polygon
			(pts
				(arc
					(start 405.719788 -166.605458)
					(mid 403.959568 -166.605458)
					(end 405.719788 -166.605458)
				)
			)
		)
	)
	(zone
		(layers "In1.Cu" "In3.Cu" "In5.Cu" "In7.Cu" "In8.Cu" "In9.Cu" "In10.Cu"
			"In12.Cu" "In14.Cu" "In16.Cu"
		)
		(hatch none 0.5)
		(connect_pads
			(clearance 0)
		)
		(min_thickness 0.25)
		(keepout
			(tracks not_allowed)
			(vias allowed)
			(pads allowed)
			(copperpour not_allowed)
			(footprints allowed)
		)
		(placement
			(enabled no)
			(sheetname "")
		)
		(fill yes
			(thermal_gap 0.5)
			(thermal_bridge_width 0.5)
			(island_removal_mode 0)
		)
		(polygon
			(pts
				(arc
					(start 388.182358 -154.428952)
					(mid 386.404358 -154.428952)
					(end 388.182358 -154.428952)
				)
			)
		)
	)
	(zone
		(layers "In1.Cu" "In3.Cu" "In5.Cu" "In7.Cu" "In8.Cu" "In9.Cu" "In10.Cu"
			"In12.Cu" "In14.Cu" "In16.Cu"
		)
		(hatch none 0.5)
		(connect_pads
			(clearance 0)
		)
		(min_thickness 0.25)
		(keepout
			(tracks not_allowed)
			(vias allowed)
			(pads allowed)
			(copperpour not_allowed)
			(footprints allowed)
		)
		(placement
			(enabled no)
			(sheetname "")
		)
		(fill yes
			(thermal_gap 0.5)
			(thermal_bridge_width 0.5)
			(island_removal_mode 0)
		)
		(polygon
			(pts
				(arc
					(start 245.407942 -42.611802)
					(mid 243.629942 -42.611802)
					(end 245.407942 -42.611802)
				)
			)
		)
	)
	(zone
		(layers "In1.Cu" "In3.Cu" "In5.Cu" "In7.Cu" "In8.Cu" "In9.Cu" "In10.Cu"
			"In12.Cu" "In14.Cu" "In16.Cu"
		)
		(hatch none 0.5)
		(connect_pads
			(clearance 0)
		)
		(min_thickness 0.25)
		(keepout
			(tracks not_allowed)
			(vias allowed)
			(pads allowed)
			(copperpour not_allowed)
			(footprints allowed)
		)
		(placement
			(enabled no)
			(sheetname "")
		)
		(fill yes
			(thermal_gap 0.5)
			(thermal_bridge_width 0.5)
			(island_removal_mode 0)
		)
		(polygon
			(pts
				(arc
					(start 287.769046 -349.899732)
					(mid 285.991046 -349.899732)
					(end 287.769046 -349.899732)
				)
			)
		)
	)
	(zone
		(layers "In1.Cu" "In3.Cu" "In5.Cu" "In7.Cu" "In8.Cu" "In9.Cu" "In10.Cu"
			"In12.Cu" "In14.Cu" "In16.Cu"
		)
		(hatch none 0.5)
		(connect_pads
			(clearance 0)
		)
		(min_thickness 0.25)
		(keepout
			(tracks not_allowed)
			(vias allowed)
			(pads allowed)
			(copperpour not_allowed)
			(footprints allowed)
		)
		(placement
			(enabled no)
			(sheetname "")
		)
		(fill yes
			(thermal_gap 0.5)
			(thermal_bridge_width 0.5)
			(island_removal_mode 0)
		)
		(polygon
			(pts
				(arc
					(start 249.770646 -51.320446)
					(mid 247.992646 -51.320446)
					(end 249.770646 -51.320446)
				)
			)
		)
	)
	(zone
		(layers "In1.Cu" "In3.Cu" "In5.Cu" "In7.Cu" "In8.Cu" "In9.Cu" "In10.Cu"
			"In12.Cu" "In14.Cu" "In16.Cu"
		)
		(hatch none 0.5)
		(connect_pads
			(clearance 0)
		)
		(min_thickness 0.25)
		(keepout
			(tracks not_allowed)
			(vias allowed)
			(pads allowed)
			(copperpour not_allowed)
			(footprints allowed)
		)
		(placement
			(enabled no)
			(sheetname "")
		)
		(fill yes
			(thermal_gap 0.5)
			(thermal_bridge_width 0.5)
			(island_removal_mode 0)
		)
		(polygon
			(pts
				(arc
					(start 294.813736 -348.704662)
					(mid 293.053516 -348.704662)
					(end 294.813736 -348.704662)
				)
			)
		)
	)
	(zone
		(layers "In1.Cu" "In3.Cu" "In5.Cu" "In7.Cu" "In8.Cu" "In9.Cu" "In10.Cu"
			"In12.Cu" "In14.Cu" "In16.Cu"
		)
		(hatch none 0.5)
		(connect_pads
			(clearance 0)
		)
		(min_thickness 0.25)
		(keepout
			(tracks not_allowed)
			(vias allowed)
			(pads allowed)
			(copperpour not_allowed)
			(footprints allowed)
		)
		(placement
			(enabled no)
			(sheetname "")
		)
		(fill yes
			(thermal_gap 0.5)
			(thermal_bridge_width 0.5)
			(island_removal_mode 0)
		)
		(polygon
			(pts
				(arc
					(start 106.225848 -177.65776)
					(mid 104.447848 -177.65776)
					(end 106.225848 -177.65776)
				)
			)
		)
	)
	(zone
		(layers "In1.Cu" "In3.Cu" "In5.Cu" "In7.Cu" "In8.Cu" "In9.Cu" "In10.Cu"
			"In12.Cu" "In14.Cu" "In16.Cu"
		)
		(hatch none 0.5)
		(connect_pads
			(clearance 0)
		)
		(min_thickness 0.25)
		(keepout
			(tracks not_allowed)
			(vias allowed)
			(pads allowed)
			(copperpour not_allowed)
			(footprints allowed)
		)
		(placement
			(enabled no)
			(sheetname "")
		)
		(fill yes
			(thermal_gap 0.5)
			(thermal_bridge_width 0.5)
			(island_removal_mode 0)
		)
		(polygon
			(pts
				(arc
					(start 362.575602 -174.910496)
					(mid 360.797602 -174.910496)
					(end 362.575602 -174.910496)
				)
			)
		)
	)
	(zone
		(layers "In1.Cu" "In3.Cu" "In5.Cu" "In7.Cu" "In8.Cu" "In9.Cu" "In10.Cu"
			"In12.Cu" "In14.Cu" "In16.Cu"
		)
		(hatch none 0.5)
		(connect_pads
			(clearance 0)
		)
		(min_thickness 0.25)
		(keepout
			(tracks not_allowed)
			(vias allowed)
			(pads allowed)
			(copperpour not_allowed)
			(footprints allowed)
		)
		(placement
			(enabled no)
			(sheetname "")
		)
		(fill yes
			(thermal_gap 0.5)
			(thermal_bridge_width 0.5)
			(island_removal_mode 0)
		)
		(polygon
			(pts
				(arc
					(start 397.396208 -175.182784)
					(mid 395.635988 -175.182784)
					(end 397.396208 -175.182784)
				)
			)
		)
	)
	(zone
		(layers "In1.Cu" "In3.Cu" "In5.Cu" "In7.Cu" "In8.Cu" "In9.Cu" "In10.Cu"
			"In12.Cu" "In14.Cu" "In16.Cu"
		)
		(hatch none 0.5)
		(connect_pads
			(clearance 0)
		)
		(min_thickness 0.25)
		(keepout
			(tracks not_allowed)
			(vias allowed)
			(pads allowed)
			(copperpour not_allowed)
			(footprints allowed)
		)
		(placement
			(enabled no)
			(sheetname "")
		)
		(fill yes
			(thermal_gap 0.5)
			(thermal_bridge_width 0.5)
			(island_removal_mode 0)
		)
		(polygon
			(pts
				(arc
					(start 96.78543 -179.509674)
					(mid 95.00743 -179.509674)
					(end 96.78543 -179.509674)
				)
			)
		)
	)
	(zone
		(layers "In1.Cu" "In3.Cu" "In5.Cu" "In7.Cu" "In8.Cu" "In9.Cu" "In10.Cu"
			"In12.Cu" "In14.Cu" "In16.Cu"
		)
		(hatch none 0.5)
		(connect_pads
			(clearance 0)
		)
		(min_thickness 0.25)
		(keepout
			(tracks not_allowed)
			(vias allowed)
			(pads allowed)
			(copperpour not_allowed)
			(footprints allowed)
		)
		(placement
			(enabled no)
			(sheetname "")
		)
		(fill yes
			(thermal_gap 0.5)
			(thermal_bridge_width 0.5)
			(island_removal_mode 0)
		)
		(polygon
			(pts
				(arc
					(start 80.335628 -336.981292)
					(mid 78.575408 -336.981292)
					(end 80.335628 -336.981292)
				)
			)
		)
	)
	(zone
		(layers "In1.Cu" "In3.Cu" "In5.Cu" "In7.Cu" "In8.Cu" "In9.Cu" "In10.Cu"
			"In12.Cu" "In14.Cu" "In16.Cu"
		)
		(hatch none 0.5)
		(connect_pads
			(clearance 0)
		)
		(min_thickness 0.25)
		(keepout
			(tracks not_allowed)
			(vias allowed)
			(pads allowed)
			(copperpour not_allowed)
			(footprints allowed)
		)
		(placement
			(enabled no)
			(sheetname "")
		)
		(fill yes
			(thermal_gap 0.5)
			(thermal_bridge_width 0.5)
			(island_removal_mode 0)
		)
		(polygon
			(pts
				(arc
					(start 96.25203 -179.890674)
					(mid 94.47403 -179.890674)
					(end 96.25203 -179.890674)
				)
			)
		)
	)
	(zone
		(layers "In1.Cu" "In3.Cu" "In5.Cu" "In7.Cu" "In8.Cu" "In9.Cu" "In10.Cu"
			"In12.Cu" "In14.Cu" "In16.Cu"
		)
		(hatch none 0.5)
		(connect_pads
			(clearance 0)
		)
		(min_thickness 0.25)
		(keepout
			(tracks not_allowed)
			(vias allowed)
			(pads allowed)
			(copperpour not_allowed)
			(footprints allowed)
		)
		(placement
			(enabled no)
			(sheetname "")
		)
		(fill yes
			(thermal_gap 0.5)
			(thermal_bridge_width 0.5)
			(island_removal_mode 0)
		)
		(polygon
			(pts
				(arc
					(start 363.160056 -176.518316)
					(mid 361.382056 -176.518316)
					(end 363.160056 -176.518316)
				)
			)
		)
	)
	(zone
		(layers "In1.Cu" "In3.Cu" "In5.Cu" "In7.Cu" "In8.Cu" "In9.Cu" "In10.Cu"
			"In12.Cu" "In14.Cu" "In16.Cu"
		)
		(hatch none 0.5)
		(connect_pads
			(clearance 0)
		)
		(min_thickness 0.25)
		(keepout
			(tracks not_allowed)
			(vias allowed)
			(pads allowed)
			(copperpour not_allowed)
			(footprints allowed)
		)
		(placement
			(enabled no)
			(sheetname "")
		)
		(fill yes
			(thermal_gap 0.5)
			(thermal_bridge_width 0.5)
			(island_removal_mode 0)
		)
		(polygon
			(pts
				(arc
					(start 443.260734 -20.348702)
					(mid 441.482734 -20.348702)
					(end 443.260734 -20.348702)
				)
			)
		)
	)
	(zone
		(layers "In1.Cu" "In3.Cu" "In5.Cu" "In7.Cu" "In8.Cu" "In9.Cu" "In10.Cu"
			"In12.Cu" "In14.Cu" "In16.Cu"
		)
		(hatch none 0.5)
		(connect_pads
			(clearance 0)
		)
		(min_thickness 0.25)
		(keepout
			(tracks not_allowed)
			(vias allowed)
			(pads allowed)
			(copperpour not_allowed)
			(footprints allowed)
		)
		(placement
			(enabled no)
			(sheetname "")
		)
		(fill yes
			(thermal_gap 0.5)
			(thermal_bridge_width 0.5)
			(island_removal_mode 0)
		)
		(polygon
			(pts
				(arc
					(start 93.539056 -345.261184)
					(mid 91.761056 -345.261184)
					(end 93.539056 -345.261184)
				)
			)
		)
	)
	(zone
		(layers "In1.Cu" "In3.Cu" "In5.Cu" "In7.Cu" "In8.Cu" "In9.Cu" "In10.Cu"
			"In12.Cu" "In14.Cu" "In16.Cu"
		)
		(hatch none 0.5)
		(connect_pads
			(clearance 0)
		)
		(min_thickness 0.25)
		(keepout
			(tracks not_allowed)
			(vias allowed)
			(pads allowed)
			(copperpour not_allowed)
			(footprints allowed)
		)
		(placement
			(enabled no)
			(sheetname "")
		)
		(fill yes
			(thermal_gap 0.5)
			(thermal_bridge_width 0.5)
			(island_removal_mode 0)
		)
		(polygon
			(pts
				(arc
					(start 322.94576 -338.534248)
					(mid 321.16776 -338.534248)
					(end 322.94576 -338.534248)
				)
			)
		)
	)
	(zone
		(layers "In1.Cu" "In3.Cu" "In5.Cu" "In7.Cu" "In8.Cu" "In9.Cu" "In10.Cu"
			"In12.Cu" "In14.Cu" "In16.Cu"
		)
		(hatch none 0.5)
		(connect_pads
			(clearance 0)
		)
		(min_thickness 0.25)
		(keepout
			(tracks not_allowed)
			(vias allowed)
			(pads allowed)
			(copperpour not_allowed)
			(footprints allowed)
		)
		(placement
			(enabled no)
			(sheetname "")
		)
		(fill yes
			(thermal_gap 0.5)
			(thermal_bridge_width 0.5)
			(island_removal_mode 0)
		)
		(polygon
			(pts
				(arc
					(start 64.977264 -12.43711)
					(mid 63.199264 -12.43711)
					(end 64.977264 -12.43711)
				)
			)
		)
	)
	(zone
		(layers "In1.Cu" "In3.Cu" "In5.Cu" "In7.Cu" "In8.Cu" "In9.Cu" "In10.Cu"
			"In12.Cu" "In14.Cu" "In16.Cu"
		)
		(hatch none 0.5)
		(connect_pads
			(clearance 0)
		)
		(min_thickness 0.25)
		(keepout
			(tracks not_allowed)
			(vias allowed)
			(pads allowed)
			(copperpour not_allowed)
			(footprints allowed)
		)
		(placement
			(enabled no)
			(sheetname "")
		)
		(fill yes
			(thermal_gap 0.5)
			(thermal_bridge_width 0.5)
			(island_removal_mode 0)
		)
		(polygon
			(pts
				(arc
					(start 186.986418 -354.478844)
					(mid 185.208418 -354.478844)
					(end 186.986418 -354.478844)
				)
			)
		)
	)
	(zone
		(layers "In1.Cu" "In3.Cu" "In5.Cu" "In7.Cu" "In8.Cu" "In9.Cu" "In10.Cu"
			"In12.Cu" "In14.Cu" "In16.Cu"
		)
		(hatch none 0.5)
		(connect_pads
			(clearance 0)
		)
		(min_thickness 0.25)
		(keepout
			(tracks not_allowed)
			(vias allowed)
			(pads allowed)
			(copperpour not_allowed)
			(footprints allowed)
		)
		(placement
			(enabled no)
			(sheetname "")
		)
		(fill yes
			(thermal_gap 0.5)
			(thermal_bridge_width 0.5)
			(island_removal_mode 0)
		)
		(polygon
			(pts
				(arc
					(start 288.302446 -349.518732)
					(mid 286.524446 -349.518732)
					(end 288.302446 -349.518732)
				)
			)
		)
	)
	(zone
		(layers "In1.Cu" "In3.Cu" "In5.Cu" "In7.Cu" "In8.Cu" "In9.Cu" "In10.Cu"
			"In12.Cu" "In14.Cu" "In16.Cu"
		)
		(hatch none 0.5)
		(connect_pads
			(clearance 0)
		)
		(min_thickness 0.25)
		(keepout
			(tracks not_allowed)
			(vias allowed)
			(pads allowed)
			(copperpour not_allowed)
			(footprints allowed)
		)
		(placement
			(enabled no)
			(sheetname "")
		)
		(fill yes
			(thermal_gap 0.5)
			(thermal_bridge_width 0.5)
			(island_removal_mode 0)
		)
		(polygon
			(pts
				(arc
					(start 396.778988 -175.182784)
					(mid 395.018768 -175.182784)
					(end 396.778988 -175.182784)
				)
			)
		)
	)
	(zone
		(layers "In1.Cu" "In3.Cu" "In5.Cu" "In7.Cu" "In8.Cu" "In9.Cu" "In10.Cu"
			"In12.Cu" "In14.Cu" "In16.Cu"
		)
		(hatch none 0.5)
		(connect_pads
			(clearance 0)
		)
		(min_thickness 0.25)
		(keepout
			(tracks not_allowed)
			(vias allowed)
			(pads allowed)
			(copperpour not_allowed)
			(footprints allowed)
		)
		(placement
			(enabled no)
			(sheetname "")
		)
		(fill yes
			(thermal_gap 0.5)
			(thermal_bridge_width 0.5)
			(island_removal_mode 0)
		)
		(polygon
			(pts
				(arc
					(start 353.745038 -166.312596)
					(mid 351.967038 -166.312596)
					(end 353.745038 -166.312596)
				)
			)
		)
	)
	(zone
		(layers "In1.Cu" "In3.Cu" "In5.Cu" "In7.Cu" "In8.Cu" "In9.Cu" "In10.Cu"
			"In12.Cu" "In14.Cu" "In16.Cu"
		)
		(hatch none 0.5)
		(connect_pads
			(clearance 0)
		)
		(min_thickness 0.25)
		(keepout
			(tracks not_allowed)
			(vias allowed)
			(pads allowed)
			(copperpour not_allowed)
			(footprints allowed)
		)
		(placement
			(enabled no)
			(sheetname "")
		)
		(fill yes
			(thermal_gap 0.5)
			(thermal_bridge_width 0.5)
			(island_removal_mode 0)
		)
		(polygon
			(pts
				(arc
					(start 370.851684 -165.19398)
					(mid 369.073684 -165.19398)
					(end 370.851684 -165.19398)
				)
			)
		)
	)
	(zone
		(layers "In1.Cu" "In3.Cu" "In5.Cu" "In7.Cu" "In8.Cu" "In9.Cu" "In10.Cu"
			"In12.Cu" "In14.Cu" "In16.Cu"
		)
		(hatch none 0.5)
		(connect_pads
			(clearance 0)
		)
		(min_thickness 0.25)
		(keepout
			(tracks not_allowed)
			(vias allowed)
			(pads allowed)
			(copperpour not_allowed)
			(footprints allowed)
		)
		(placement
			(enabled no)
			(sheetname "")
		)
		(fill yes
			(thermal_gap 0.5)
			(thermal_bridge_width 0.5)
			(island_removal_mode 0)
		)
		(polygon
			(pts
				(arc
					(start 107.23245 -343.450164)
					(mid 105.45445 -343.450164)
					(end 107.23245 -343.450164)
				)
			)
		)
	)
	(zone
		(layers "In1.Cu" "In3.Cu" "In5.Cu" "In7.Cu" "In8.Cu" "In9.Cu" "In10.Cu"
			"In12.Cu" "In14.Cu" "In16.Cu"
		)
		(hatch none 0.5)
		(connect_pads
			(clearance 0)
		)
		(min_thickness 0.25)
		(keepout
			(tracks not_allowed)
			(vias allowed)
			(pads allowed)
			(copperpour not_allowed)
			(footprints allowed)
		)
		(placement
			(enabled no)
			(sheetname "")
		)
		(fill yes
			(thermal_gap 0.5)
			(thermal_bridge_width 0.5)
			(island_removal_mode 0)
		)
		(polygon
			(pts
				(arc
					(start 369.581684 -165.19398)
					(mid 367.803684 -165.19398)
					(end 369.581684 -165.19398)
				)
			)
		)
	)
	(zone
		(layers "In1.Cu" "In3.Cu" "In5.Cu" "In7.Cu" "In8.Cu" "In9.Cu" "In10.Cu"
			"In12.Cu" "In14.Cu" "In16.Cu"
		)
		(hatch none 0.5)
		(connect_pads
			(clearance 0)
		)
		(min_thickness 0.25)
		(keepout
			(tracks not_allowed)
			(vias allowed)
			(pads allowed)
			(copperpour not_allowed)
			(footprints allowed)
		)
		(placement
			(enabled no)
			(sheetname "")
		)
		(fill yes
			(thermal_gap 0.5)
			(thermal_bridge_width 0.5)
			(island_removal_mode 0)
		)
		(polygon
			(pts
				(arc
					(start 120.353074 -152.022556)
					(mid 118.575074 -152.022556)
					(end 120.353074 -152.022556)
				)
			)
		)
	)
	(zone
		(layers "In1.Cu" "In3.Cu" "In5.Cu" "In7.Cu" "In8.Cu" "In9.Cu" "In10.Cu"
			"In12.Cu" "In14.Cu" "In16.Cu"
		)
		(hatch none 0.5)
		(connect_pads
			(clearance 0)
		)
		(min_thickness 0.25)
		(keepout
			(tracks not_allowed)
			(vias allowed)
			(pads allowed)
			(copperpour not_allowed)
			(footprints allowed)
		)
		(placement
			(enabled no)
			(sheetname "")
		)
		(fill yes
			(thermal_gap 0.5)
			(thermal_bridge_width 0.5)
			(island_removal_mode 0)
		)
		(polygon
			(pts
				(arc
					(start 105.717594 -174.574454)
					(mid 103.939594 -174.574454)
					(end 105.717594 -174.574454)
				)
			)
		)
	)
	(zone
		(layers "In1.Cu" "In3.Cu" "In5.Cu" "In7.Cu" "In8.Cu" "In9.Cu" "In10.Cu"
			"In12.Cu" "In14.Cu" "In16.Cu"
		)
		(hatch none 0.5)
		(connect_pads
			(clearance 0)
		)
		(min_thickness 0.25)
		(keepout
			(tracks not_allowed)
			(vias allowed)
			(pads allowed)
			(copperpour not_allowed)
			(footprints allowed)
		)
		(placement
			(enabled no)
			(sheetname "")
		)
		(fill yes
			(thermal_gap 0.5)
			(thermal_bridge_width 0.5)
			(island_removal_mode 0)
		)
		(polygon
			(pts
				(arc
					(start 289.79495 -355.279198)
					(mid 288.01695 -355.279198)
					(end 289.79495 -355.279198)
				)
			)
		)
	)
	(zone
		(layers "In1.Cu" "In3.Cu" "In5.Cu" "In7.Cu" "In8.Cu" "In9.Cu" "In10.Cu"
			"In12.Cu" "In14.Cu" "In16.Cu"
		)
		(hatch none 0.5)
		(connect_pads
			(clearance 0)
		)
		(min_thickness 0.25)
		(keepout
			(tracks not_allowed)
			(vias allowed)
			(pads allowed)
			(copperpour not_allowed)
			(footprints allowed)
		)
		(placement
			(enabled no)
			(sheetname "")
		)
		(fill yes
			(thermal_gap 0.5)
			(thermal_bridge_width 0.5)
			(island_removal_mode 0)
		)
		(polygon
			(pts
				(arc
					(start 67.663822 -19.692366)
					(mid 65.885822 -19.692366)
					(end 67.663822 -19.692366)
				)
			)
		)
	)
	(zone
		(layers "In1.Cu" "In3.Cu" "In5.Cu" "In7.Cu" "In8.Cu" "In9.Cu" "In10.Cu"
			"In12.Cu" "In14.Cu" "In16.Cu"
		)
		(hatch none 0.5)
		(connect_pads
			(clearance 0)
		)
		(min_thickness 0.25)
		(keepout
			(tracks not_allowed)
			(vias allowed)
			(pads allowed)
			(copperpour not_allowed)
			(footprints allowed)
		)
		(placement
			(enabled no)
			(sheetname "")
		)
		(fill yes
			(thermal_gap 0.5)
			(thermal_bridge_width 0.5)
			(island_removal_mode 0)
		)
		(polygon
			(pts
				(arc
					(start 89.927684 -336.966814)
					(mid 88.167464 -336.966814)
					(end 89.927684 -336.966814)
				)
			)
		)
	)
	(zone
		(layers "In1.Cu" "In3.Cu" "In5.Cu" "In7.Cu" "In8.Cu" "In9.Cu" "In10.Cu"
			"In12.Cu" "In14.Cu" "In16.Cu"
		)
		(hatch none 0.5)
		(connect_pads
			(clearance 0)
		)
		(min_thickness 0.25)
		(keepout
			(tracks not_allowed)
			(vias allowed)
			(pads allowed)
			(copperpour not_allowed)
			(footprints allowed)
		)
		(placement
			(enabled no)
			(sheetname "")
		)
		(fill yes
			(thermal_gap 0.5)
			(thermal_bridge_width 0.5)
			(island_removal_mode 0)
		)
		(polygon
			(pts
				(arc
					(start 388.817358 -157.001972)
					(mid 387.039358 -157.001972)
					(end 388.817358 -157.001972)
				)
			)
		)
	)
	(zone
		(layers "In1.Cu" "In3.Cu" "In5.Cu" "In7.Cu" "In8.Cu" "In9.Cu" "In10.Cu"
			"In12.Cu" "In14.Cu" "In16.Cu"
		)
		(hatch none 0.5)
		(connect_pads
			(clearance 0)
		)
		(min_thickness 0.25)
		(keepout
			(tracks not_allowed)
			(vias allowed)
			(pads allowed)
			(copperpour not_allowed)
			(footprints allowed)
		)
		(placement
			(enabled no)
			(sheetname "")
		)
		(fill yes
			(thermal_gap 0.5)
			(thermal_bridge_width 0.5)
			(island_removal_mode 0)
		)
		(polygon
			(pts
				(arc
					(start 304.964846 -348.782132)
					(mid 303.186846 -348.782132)
					(end 304.964846 -348.782132)
				)
			)
		)
	)
	(zone
		(layers "In1.Cu" "In3.Cu" "In5.Cu" "In7.Cu" "In8.Cu" "In9.Cu" "In10.Cu"
			"In12.Cu" "In14.Cu" "In16.Cu"
		)
		(hatch none 0.5)
		(connect_pads
			(clearance 0)
		)
		(min_thickness 0.25)
		(keepout
			(tracks not_allowed)
			(vias allowed)
			(pads allowed)
			(copperpour not_allowed)
			(footprints allowed)
		)
		(placement
			(enabled no)
			(sheetname "")
		)
		(fill yes
			(thermal_gap 0.5)
			(thermal_bridge_width 0.5)
			(island_removal_mode 0)
		)
		(polygon
			(pts
				(arc
					(start 50.92573 -357.457502)
					(mid 49.14773 -357.457502)
					(end 50.92573 -357.457502)
				)
			)
		)
	)
	(zone
		(layers "In1.Cu" "In3.Cu" "In5.Cu" "In7.Cu" "In8.Cu" "In9.Cu" "In10.Cu"
			"In12.Cu" "In14.Cu" "In16.Cu"
		)
		(hatch none 0.5)
		(connect_pads
			(clearance 0)
		)
		(min_thickness 0.25)
		(keepout
			(tracks not_allowed)
			(vias allowed)
			(pads allowed)
			(copperpour not_allowed)
			(footprints allowed)
		)
		(placement
			(enabled no)
			(sheetname "")
		)
		(fill yes
			(thermal_gap 0.5)
			(thermal_bridge_width 0.5)
			(island_removal_mode 0)
		)
		(polygon
			(pts
				(arc
					(start 250.091448 -40.945816)
					(mid 248.313448 -40.945816)
					(end 250.091448 -40.945816)
				)
			)
		)
	)
	(zone
		(layers "In1.Cu" "In3.Cu" "In5.Cu" "In7.Cu" "In8.Cu" "In9.Cu" "In10.Cu"
			"In12.Cu" "In14.Cu" "In16.Cu"
		)
		(hatch none 0.5)
		(connect_pads
			(clearance 0)
		)
		(min_thickness 0.25)
		(keepout
			(tracks not_allowed)
			(vias allowed)
			(pads allowed)
			(copperpour not_allowed)
			(footprints allowed)
		)
		(placement
			(enabled no)
			(sheetname "")
		)
		(fill yes
			(thermal_gap 0.5)
			(thermal_bridge_width 0.5)
			(island_removal_mode 0)
		)
		(polygon
			(pts
				(arc
					(start 355.707188 -342.355932)
					(mid 353.929188 -342.355932)
					(end 355.707188 -342.355932)
				)
			)
		)
	)
	(zone
		(layers "In1.Cu" "In3.Cu" "In5.Cu" "In7.Cu" "In8.Cu" "In9.Cu" "In10.Cu"
			"In12.Cu" "In14.Cu" "In16.Cu"
		)
		(hatch none 0.5)
		(connect_pads
			(clearance 0)
		)
		(min_thickness 0.25)
		(keepout
			(tracks not_allowed)
			(vias allowed)
			(pads allowed)
			(copperpour not_allowed)
			(footprints allowed)
		)
		(placement
			(enabled no)
			(sheetname "")
		)
		(fill yes
			(thermal_gap 0.5)
			(thermal_bridge_width 0.5)
			(island_removal_mode 0)
		)
		(polygon
			(pts
				(arc
					(start 82.281014 -337.853782)
					(mid 80.503014 -337.853782)
					(end 82.281014 -337.853782)
				)
			)
		)
	)
	(zone
		(layers "In1.Cu" "In3.Cu" "In5.Cu" "In7.Cu" "In8.Cu" "In9.Cu" "In10.Cu"
			"In12.Cu" "In14.Cu" "In16.Cu"
		)
		(hatch none 0.5)
		(connect_pads
			(clearance 0)
		)
		(min_thickness 0.25)
		(keepout
			(tracks not_allowed)
			(vias allowed)
			(pads allowed)
			(copperpour not_allowed)
			(footprints allowed)
		)
		(placement
			(enabled no)
			(sheetname "")
		)
		(fill yes
			(thermal_gap 0.5)
			(thermal_bridge_width 0.5)
			(island_removal_mode 0)
		)
		(polygon
			(pts
				(arc
					(start 295.524682 -350.313752)
					(mid 293.746682 -350.313752)
					(end 295.524682 -350.313752)
				)
			)
		)
	)
	(zone
		(layers "In1.Cu" "In3.Cu" "In5.Cu" "In7.Cu" "In8.Cu" "In9.Cu" "In10.Cu"
			"In12.Cu" "In14.Cu" "In16.Cu"
		)
		(hatch none 0.5)
		(connect_pads
			(clearance 0)
		)
		(min_thickness 0.25)
		(keepout
			(tracks not_allowed)
			(vias allowed)
			(pads allowed)
			(copperpour not_allowed)
			(footprints allowed)
		)
		(placement
			(enabled no)
			(sheetname "")
		)
		(fill yes
			(thermal_gap 0.5)
			(thermal_bridge_width 0.5)
			(island_removal_mode 0)
		)
		(polygon
			(pts
				(arc
					(start 356.265988 -342.736932)
					(mid 354.487988 -342.736932)
					(end 356.265988 -342.736932)
				)
			)
		)
	)
	(zone
		(layers "In1.Cu" "In3.Cu" "In5.Cu" "In7.Cu" "In8.Cu" "In9.Cu" "In10.Cu"
			"In12.Cu" "In14.Cu" "In16.Cu"
		)
		(hatch none 0.5)
		(connect_pads
			(clearance 0)
		)
		(min_thickness 0.25)
		(keepout
			(tracks not_allowed)
			(vias allowed)
			(pads allowed)
			(copperpour not_allowed)
			(footprints allowed)
		)
		(placement
			(enabled no)
			(sheetname "")
		)
		(fill yes
			(thermal_gap 0.5)
			(thermal_bridge_width 0.5)
			(island_removal_mode 0)
		)
		(polygon
			(pts
				(arc
					(start 330.21778 -338.585556)
					(mid 328.43978 -338.585556)
					(end 330.21778 -338.585556)
				)
			)
		)
	)
	(zone
		(layers "In1.Cu" "In3.Cu" "In5.Cu" "In7.Cu" "In8.Cu" "In9.Cu" "In10.Cu"
			"In12.Cu" "In14.Cu" "In16.Cu"
		)
		(hatch none 0.5)
		(connect_pads
			(clearance 0)
		)
		(min_thickness 0.25)
		(keepout
			(tracks not_allowed)
			(vias allowed)
			(pads allowed)
			(copperpour not_allowed)
			(footprints allowed)
		)
		(placement
			(enabled no)
			(sheetname "")
		)
		(fill yes
			(thermal_gap 0.5)
			(thermal_bridge_width 0.5)
			(island_removal_mode 0)
		)
		(polygon
			(pts
				(arc
					(start 88.943434 -179.814982)
					(mid 87.165434 -179.814982)
					(end 88.943434 -179.814982)
				)
			)
		)
	)
	(zone
		(layers "In1.Cu" "In3.Cu" "In5.Cu" "In7.Cu" "In8.Cu" "In9.Cu" "In10.Cu"
			"In12.Cu" "In14.Cu" "In16.Cu"
		)
		(hatch none 0.5)
		(connect_pads
			(clearance 0)
		)
		(min_thickness 0.25)
		(keepout
			(tracks not_allowed)
			(vias allowed)
			(pads allowed)
			(copperpour not_allowed)
			(footprints allowed)
		)
		(placement
			(enabled no)
			(sheetname "")
		)
		(fill yes
			(thermal_gap 0.5)
			(thermal_bridge_width 0.5)
			(island_removal_mode 0)
		)
		(polygon
			(pts
				(arc
					(start 436.358538 -359.972102)
					(mid 434.580538 -359.972102)
					(end 436.358538 -359.972102)
				)
			)
		)
	)
	(zone
		(layers "In1.Cu" "In3.Cu" "In5.Cu" "In7.Cu" "In8.Cu" "In9.Cu" "In10.Cu"
			"In12.Cu" "In14.Cu" "In16.Cu"
		)
		(hatch none 0.5)
		(connect_pads
			(clearance 0)
		)
		(min_thickness 0.25)
		(keepout
			(tracks not_allowed)
			(vias allowed)
			(pads allowed)
			(copperpour not_allowed)
			(footprints allowed)
		)
		(placement
			(enabled no)
			(sheetname "")
		)
		(fill yes
			(thermal_gap 0.5)
			(thermal_bridge_width 0.5)
			(island_removal_mode 0)
		)
		(polygon
			(pts
				(arc
					(start 330.21778 -337.848956)
					(mid 328.43978 -337.848956)
					(end 330.21778 -337.848956)
				)
			)
		)
	)
	(zone
		(layers "In1.Cu" "In3.Cu" "In5.Cu" "In7.Cu" "In8.Cu" "In9.Cu" "In10.Cu"
			"In12.Cu" "In14.Cu" "In16.Cu"
		)
		(hatch none 0.5)
		(connect_pads
			(clearance 0)
		)
		(min_thickness 0.25)
		(keepout
			(tracks not_allowed)
			(vias allowed)
			(pads allowed)
			(copperpour not_allowed)
			(footprints allowed)
		)
		(placement
			(enabled no)
			(sheetname "")
		)
		(fill yes
			(thermal_gap 0.5)
			(thermal_bridge_width 0.5)
			(island_removal_mode 0)
		)
		(polygon
			(pts
				(arc
					(start 122.761248 -164.62756)
					(mid 120.983248 -164.62756)
					(end 122.761248 -164.62756)
				)
			)
		)
	)
	(zone
		(layers "In1.Cu" "In3.Cu" "In5.Cu" "In7.Cu" "In8.Cu" "In9.Cu" "In10.Cu"
			"In12.Cu" "In14.Cu" "In16.Cu"
		)
		(hatch none 0.5)
		(connect_pads
			(clearance 0)
		)
		(min_thickness 0.25)
		(keepout
			(tracks not_allowed)
			(vias allowed)
			(pads allowed)
			(copperpour not_allowed)
			(footprints allowed)
		)
		(placement
			(enabled no)
			(sheetname "")
		)
		(fill yes
			(thermal_gap 0.5)
			(thermal_bridge_width 0.5)
			(island_removal_mode 0)
		)
		(polygon
			(pts
				(arc
					(start 313.296046 -350.255332)
					(mid 311.518046 -350.255332)
					(end 313.296046 -350.255332)
				)
			)
		)
	)
	(zone
		(layers "In1.Cu" "In3.Cu" "In5.Cu" "In7.Cu" "In8.Cu" "In9.Cu" "In10.Cu"
			"In12.Cu" "In14.Cu" "In16.Cu"
		)
		(hatch none 0.5)
		(connect_pads
			(clearance 0)
		)
		(min_thickness 0.25)
		(keepout
			(tracks not_allowed)
			(vias allowed)
			(pads allowed)
			(copperpour not_allowed)
			(footprints allowed)
		)
		(placement
			(enabled no)
			(sheetname "")
		)
		(fill yes
			(thermal_gap 0.5)
			(thermal_bridge_width 0.5)
			(island_removal_mode 0)
		)
		(polygon
			(pts
				(arc
					(start 371.62232 -180.803804)
					(mid 369.8621 -180.803804)
					(end 371.62232 -180.803804)
				)
			)
		)
	)
	(zone
		(layers "In1.Cu" "In3.Cu" "In5.Cu" "In7.Cu" "In8.Cu" "In9.Cu" "In10.Cu"
			"In12.Cu" "In14.Cu" "In16.Cu"
		)
		(hatch none 0.5)
		(connect_pads
			(clearance 0)
		)
		(min_thickness 0.25)
		(keepout
			(tracks not_allowed)
			(vias allowed)
			(pads allowed)
			(copperpour not_allowed)
			(footprints allowed)
		)
		(placement
			(enabled no)
			(sheetname "")
		)
		(fill yes
			(thermal_gap 0.5)
			(thermal_bridge_width 0.5)
			(island_removal_mode 0)
		)
		(polygon
			(pts
				(arc
					(start 405.102568 -166.605458)
					(mid 403.342348 -166.605458)
					(end 405.102568 -166.605458)
				)
			)
		)
	)
	(zone
		(layers "In1.Cu" "In3.Cu" "In5.Cu" "In7.Cu" "In8.Cu" "In9.Cu" "In10.Cu"
			"In12.Cu" "In14.Cu" "In16.Cu"
		)
		(hatch none 0.5)
		(connect_pads
			(clearance 0)
		)
		(min_thickness 0.25)
		(keepout
			(tracks not_allowed)
			(vias allowed)
			(pads allowed)
			(copperpour not_allowed)
			(footprints allowed)
		)
		(placement
			(enabled no)
			(sheetname "")
		)
		(fill yes
			(thermal_gap 0.5)
			(thermal_bridge_width 0.5)
			(island_removal_mode 0)
		)
		(polygon
			(pts
				(arc
					(start 378.256038 -180.678074)
					(mid 376.478038 -180.678074)
					(end 378.256038 -180.678074)
				)
			)
		)
	)
	(zone
		(layers "In1.Cu" "In3.Cu" "In5.Cu" "In7.Cu" "In8.Cu" "In9.Cu" "In10.Cu"
			"In12.Cu" "In14.Cu" "In16.Cu"
		)
		(hatch none 0.5)
		(connect_pads
			(clearance 0)
		)
		(min_thickness 0.25)
		(keepout
			(tracks not_allowed)
			(vias allowed)
			(pads allowed)
			(copperpour not_allowed)
			(footprints allowed)
		)
		(placement
			(enabled no)
			(sheetname "")
		)
		(fill yes
			(thermal_gap 0.5)
			(thermal_bridge_width 0.5)
			(island_removal_mode 0)
		)
		(polygon
			(pts
				(arc
					(start 66.474594 -349.523558)
					(mid 64.696594 -349.523558)
					(end 66.474594 -349.523558)
				)
			)
		)
	)
	(zone
		(layers "In1.Cu" "In3.Cu" "In5.Cu" "In7.Cu" "In8.Cu" "In9.Cu" "In10.Cu"
			"In12.Cu" "In14.Cu" "In16.Cu"
		)
		(hatch none 0.5)
		(connect_pads
			(clearance 0)
		)
		(min_thickness 0.25)
		(keepout
			(tracks not_allowed)
			(vias allowed)
			(pads allowed)
			(copperpour not_allowed)
			(footprints allowed)
		)
		(placement
			(enabled no)
			(sheetname "")
		)
		(fill yes
			(thermal_gap 0.5)
			(thermal_bridge_width 0.5)
			(island_removal_mode 0)
		)
		(polygon
			(pts
				(arc
					(start 425.83227 -353.10318)
					(mid 424.07205 -353.10318)
					(end 425.83227 -353.10318)
				)
			)
		)
	)
	(zone
		(layers "In1.Cu" "In3.Cu" "In5.Cu" "In7.Cu" "In8.Cu" "In9.Cu" "In10.Cu"
			"In12.Cu" "In14.Cu" "In16.Cu"
		)
		(hatch none 0.5)
		(connect_pads
			(clearance 0)
		)
		(min_thickness 0.25)
		(keepout
			(tracks not_allowed)
			(vias allowed)
			(pads allowed)
			(copperpour not_allowed)
			(footprints allowed)
		)
		(placement
			(enabled no)
			(sheetname "")
		)
		(fill yes
			(thermal_gap 0.5)
			(thermal_bridge_width 0.5)
			(island_removal_mode 0)
		)
		(polygon
			(pts
				(arc
					(start 295.035986 -347.222572)
					(mid 293.257986 -347.222572)
					(end 295.035986 -347.222572)
				)
			)
		)
	)
	(zone
		(layers "In1.Cu" "In3.Cu" "In5.Cu" "In7.Cu" "In8.Cu" "In9.Cu" "In10.Cu"
			"In12.Cu" "In14.Cu" "In16.Cu"
		)
		(hatch none 0.5)
		(connect_pads
			(clearance 0)
		)
		(min_thickness 0.25)
		(keepout
			(tracks not_allowed)
			(vias allowed)
			(pads allowed)
			(copperpour not_allowed)
			(footprints allowed)
		)
		(placement
			(enabled no)
			(sheetname "")
		)
		(fill yes
			(thermal_gap 0.5)
			(thermal_bridge_width 0.5)
			(island_removal_mode 0)
		)
		(polygon
			(pts
				(arc
					(start 68.29171 -12.489434)
					(mid 66.51371 -12.489434)
					(end 68.29171 -12.489434)
				)
			)
		)
	)
	(zone
		(layers "In1.Cu" "In3.Cu" "In5.Cu" "In7.Cu" "In8.Cu" "In9.Cu" "In10.Cu"
			"In12.Cu" "In14.Cu" "In16.Cu"
		)
		(hatch none 0.5)
		(connect_pads
			(clearance 0)
		)
		(min_thickness 0.25)
		(keepout
			(tracks not_allowed)
			(vias allowed)
			(pads allowed)
			(copperpour not_allowed)
			(footprints allowed)
		)
		(placement
			(enabled no)
			(sheetname "")
		)
		(fill yes
			(thermal_gap 0.5)
			(thermal_bridge_width 0.5)
			(island_removal_mode 0)
		)
		(polygon
			(pts
				(arc
					(start 80.546194 -179.146454)
					(mid 78.768194 -179.146454)
					(end 80.546194 -179.146454)
				)
			)
		)
	)
	(zone
		(layers "In1.Cu" "In3.Cu" "In5.Cu" "In7.Cu" "In8.Cu" "In9.Cu" "In10.Cu"
			"In12.Cu" "In14.Cu" "In16.Cu"
		)
		(hatch none 0.5)
		(connect_pads
			(clearance 0)
		)
		(min_thickness 0.25)
		(keepout
			(tracks not_allowed)
			(vias allowed)
			(pads allowed)
			(copperpour not_allowed)
			(footprints allowed)
		)
		(placement
			(enabled no)
			(sheetname "")
		)
		(fill yes
			(thermal_gap 0.5)
			(thermal_bridge_width 0.5)
			(island_removal_mode 0)
		)
		(polygon
			(pts
				(arc
					(start 98.64598 -180.704744)
					(mid 96.88576 -180.704744)
					(end 98.64598 -180.704744)
				)
			)
		)
	)
	(zone
		(layers "In1.Cu" "In3.Cu" "In5.Cu" "In7.Cu" "In8.Cu" "In9.Cu" "In10.Cu"
			"In12.Cu" "In14.Cu" "In16.Cu"
		)
		(hatch none 0.5)
		(connect_pads
			(clearance 0)
		)
		(min_thickness 0.25)
		(keepout
			(tracks not_allowed)
			(vias allowed)
			(pads allowed)
			(copperpour not_allowed)
			(footprints allowed)
		)
		(placement
			(enabled no)
			(sheetname "")
		)
		(fill yes
			(thermal_gap 0.5)
			(thermal_bridge_width 0.5)
			(island_removal_mode 0)
		)
		(polygon
			(pts
				(arc
					(start 65.866264 -12.43711)
					(mid 64.088264 -12.43711)
					(end 65.866264 -12.43711)
				)
			)
		)
	)
	(zone
		(layers "In1.Cu" "In3.Cu" "In5.Cu" "In7.Cu" "In8.Cu" "In9.Cu" "In10.Cu"
			"In12.Cu" "In14.Cu" "In16.Cu"
		)
		(hatch none 0.5)
		(connect_pads
			(clearance 0)
		)
		(min_thickness 0.25)
		(keepout
			(tracks not_allowed)
			(vias allowed)
			(pads allowed)
			(copperpour not_allowed)
			(footprints allowed)
		)
		(placement
			(enabled no)
			(sheetname "")
		)
		(fill yes
			(thermal_gap 0.5)
			(thermal_bridge_width 0.5)
			(island_removal_mode 0)
		)
		(polygon
			(pts
				(arc
					(start 195.846446 -353.386644)
					(mid 194.068446 -353.386644)
					(end 195.846446 -353.386644)
				)
			)
		)
	)
	(zone
		(layers "In1.Cu" "In3.Cu" "In5.Cu" "In7.Cu" "In8.Cu" "In9.Cu" "In10.Cu"
			"In12.Cu" "In14.Cu" "In16.Cu"
		)
		(hatch none 0.5)
		(connect_pads
			(clearance 0)
		)
		(min_thickness 0.25)
		(keepout
			(tracks not_allowed)
			(vias allowed)
			(pads allowed)
			(copperpour not_allowed)
			(footprints allowed)
		)
		(placement
			(enabled no)
			(sheetname "")
		)
		(fill yes
			(thermal_gap 0.5)
			(thermal_bridge_width 0.5)
			(island_removal_mode 0)
		)
		(polygon
			(pts
				(arc
					(start 80.952848 -336.981292)
					(mid 79.192628 -336.981292)
					(end 80.952848 -336.981292)
				)
			)
		)
	)
	(zone
		(layers "In1.Cu" "In3.Cu" "In5.Cu" "In7.Cu" "In8.Cu" "In9.Cu" "In10.Cu"
			"In12.Cu" "In14.Cu" "In16.Cu"
		)
		(hatch none 0.5)
		(connect_pads
			(clearance 0)
		)
		(min_thickness 0.25)
		(keepout
			(tracks not_allowed)
			(vias allowed)
			(pads allowed)
			(copperpour not_allowed)
			(footprints allowed)
		)
		(placement
			(enabled no)
			(sheetname "")
		)
		(fill yes
			(thermal_gap 0.5)
			(thermal_bridge_width 0.5)
			(island_removal_mode 0)
		)
		(polygon
			(pts
				(arc
					(start 322.94576 -337.797648)
					(mid 321.16776 -337.797648)
					(end 322.94576 -337.797648)
				)
			)
		)
	)
	(zone
		(layers "In1.Cu" "In3.Cu" "In5.Cu" "In7.Cu" "In8.Cu" "In9.Cu" "In10.Cu"
			"In12.Cu" "In14.Cu" "In16.Cu"
		)
		(hatch none 0.5)
		(connect_pads
			(clearance 0)
		)
		(min_thickness 0.25)
		(keepout
			(tracks not_allowed)
			(vias allowed)
			(pads allowed)
			(copperpour not_allowed)
			(footprints allowed)
		)
		(placement
			(enabled no)
			(sheetname "")
		)
		(fill yes
			(thermal_gap 0.5)
			(thermal_bridge_width 0.5)
			(island_removal_mode 0)
		)
		(polygon
			(pts
				(arc
					(start 201.22134 -378.160534)
					(mid 199.44334 -378.160534)
					(end 201.22134 -378.160534)
				)
			)
		)
	)
	(zone
		(layers "In1.Cu" "In3.Cu" "In5.Cu" "In7.Cu" "In8.Cu" "In9.Cu" "In10.Cu"
			"In12.Cu" "In14.Cu" "In16.Cu"
		)
		(hatch none 0.5)
		(connect_pads
			(clearance 0)
		)
		(min_thickness 0.25)
		(keepout
			(tracks not_allowed)
			(vias allowed)
			(pads allowed)
			(copperpour not_allowed)
			(footprints allowed)
		)
		(placement
			(enabled no)
			(sheetname "")
		)
		(fill yes
			(thermal_gap 0.5)
			(thermal_bridge_width 0.5)
			(island_removal_mode 0)
		)
		(polygon
			(pts
				(arc
					(start 192.816734 -13.106908)
					(mid 191.038734 -13.106908)
					(end 192.816734 -13.106908)
				)
			)
		)
	)
	(zone
		(layers "In1.Cu" "In3.Cu" "In5.Cu" "In7.Cu" "In8.Cu" "In9.Cu" "In10.Cu"
			"In12.Cu" "In14.Cu" "In16.Cu"
		)
		(hatch none 0.5)
		(connect_pads
			(clearance 0)
		)
		(min_thickness 0.25)
		(keepout
			(tracks not_allowed)
			(vias allowed)
			(pads allowed)
			(copperpour not_allowed)
			(footprints allowed)
		)
		(placement
			(enabled no)
			(sheetname "")
		)
		(fill yes
			(thermal_gap 0.5)
			(thermal_bridge_width 0.5)
			(island_removal_mode 0)
		)
		(polygon
			(pts
				(arc
					(start 194.762882 -354.918264)
					(mid 192.984882 -354.918264)
					(end 194.762882 -354.918264)
				)
			)
		)
	)
	(zone
		(layers "In1.Cu" "In3.Cu" "In5.Cu" "In7.Cu" "In8.Cu" "In9.Cu" "In10.Cu"
			"In12.Cu" "In14.Cu" "In16.Cu"
		)
		(hatch none 0.5)
		(connect_pads
			(clearance 0)
		)
		(min_thickness 0.25)
		(keepout
			(tracks not_allowed)
			(vias allowed)
			(pads allowed)
			(copperpour not_allowed)
			(footprints allowed)
		)
		(placement
			(enabled no)
			(sheetname "")
		)
		(fill yes
			(thermal_gap 0.5)
			(thermal_bridge_width 0.5)
			(island_removal_mode 0)
		)
		(polygon
			(pts
				(arc
					(start 123.53798 -163.204144)
					(mid 121.77776 -163.204144)
					(end 123.53798 -163.204144)
				)
			)
		)
	)
	(zone
		(layers "In1.Cu" "In3.Cu" "In5.Cu" "In7.Cu" "In8.Cu" "In9.Cu" "In10.Cu"
			"In12.Cu" "In14.Cu" "In16.Cu"
		)
		(hatch none 0.5)
		(connect_pads
			(clearance 0)
		)
		(min_thickness 0.25)
		(keepout
			(tracks not_allowed)
			(vias allowed)
			(pads allowed)
			(copperpour not_allowed)
			(footprints allowed)
		)
		(placement
			(enabled no)
			(sheetname "")
		)
		(fill yes
			(thermal_gap 0.5)
			(thermal_bridge_width 0.5)
			(island_removal_mode 0)
		)
		(polygon
			(pts
				(arc
					(start 121.70283 -162.771074)
					(mid 119.92483 -162.771074)
					(end 121.70283 -162.771074)
				)
			)
		)
	)
	(zone
		(layers "In1.Cu" "In3.Cu" "In5.Cu" "In7.Cu" "In8.Cu" "In9.Cu" "In10.Cu"
			"In12.Cu" "In14.Cu" "In16.Cu"
		)
		(hatch none 0.5)
		(connect_pads
			(clearance 0)
		)
		(min_thickness 0.25)
		(keepout
			(tracks not_allowed)
			(vias allowed)
			(pads allowed)
			(copperpour not_allowed)
			(footprints allowed)
		)
		(placement
			(enabled no)
			(sheetname "")
		)
		(fill yes
			(thermal_gap 0.5)
			(thermal_bridge_width 0.5)
			(island_removal_mode 0)
		)
		(polygon
			(pts
				(arc
					(start 428.244 -354.65385)
					(mid 426.466 -354.65385)
					(end 428.244 -354.65385)
				)
			)
		)
	)
	(zone
		(layers "In1.Cu" "In3.Cu" "In5.Cu" "In7.Cu" "In8.Cu" "In9.Cu" "In10.Cu"
			"In12.Cu" "In14.Cu" "In16.Cu"
		)
		(hatch none 0.5)
		(connect_pads
			(clearance 0)
		)
		(min_thickness 0.25)
		(keepout
			(tracks not_allowed)
			(vias allowed)
			(pads allowed)
			(copperpour not_allowed)
			(footprints allowed)
		)
		(placement
			(enabled no)
			(sheetname "")
		)
		(fill yes
			(thermal_gap 0.5)
			(thermal_bridge_width 0.5)
			(island_removal_mode 0)
		)
		(polygon
			(pts
				(arc
					(start 248.729246 -51.320446)
					(mid 246.951246 -51.320446)
					(end 248.729246 -51.320446)
				)
			)
		)
	)
	(zone
		(layers "In1.Cu" "In3.Cu" "In5.Cu" "In7.Cu" "In8.Cu" "In9.Cu" "In10.Cu"
			"In12.Cu" "In14.Cu" "In16.Cu"
		)
		(hatch none 0.5)
		(connect_pads
			(clearance 0)
		)
		(min_thickness 0.25)
		(keepout
			(tracks not_allowed)
			(vias allowed)
			(pads allowed)
			(copperpour not_allowed)
			(footprints allowed)
		)
		(placement
			(enabled no)
			(sheetname "")
		)
		(fill yes
			(thermal_gap 0.5)
			(thermal_bridge_width 0.5)
			(island_removal_mode 0)
		)
		(polygon
			(pts
				(arc
					(start 90.44813 -164.097716)
					(mid 88.67013 -164.097716)
					(end 90.44813 -164.097716)
				)
			)
		)
	)
	(zone
		(layers "In1.Cu" "In3.Cu" "In5.Cu" "In7.Cu" "In8.Cu" "In9.Cu" "In10.Cu"
			"In12.Cu" "In14.Cu" "In16.Cu"
		)
		(hatch none 0.5)
		(connect_pads
			(clearance 0)
		)
		(min_thickness 0.25)
		(keepout
			(tracks not_allowed)
			(vias allowed)
			(pads allowed)
			(copperpour not_allowed)
			(footprints allowed)
		)
		(placement
			(enabled no)
			(sheetname "")
		)
		(fill yes
			(thermal_gap 0.5)
			(thermal_bridge_width 0.5)
			(island_removal_mode 0)
		)
		(polygon
			(pts
				(arc
					(start 396.119858 -172.819314)
					(mid 394.341858 -172.819314)
					(end 396.119858 -172.819314)
				)
			)
		)
	)
	(zone
		(layers "In1.Cu" "In3.Cu" "In5.Cu" "In7.Cu" "In8.Cu" "In9.Cu" "In10.Cu"
			"In12.Cu" "In14.Cu" "In16.Cu"
		)
		(hatch none 0.5)
		(connect_pads
			(clearance 0)
		)
		(min_thickness 0.25)
		(keepout
			(tracks not_allowed)
			(vias allowed)
			(pads allowed)
			(copperpour not_allowed)
			(footprints allowed)
		)
		(placement
			(enabled no)
			(sheetname "")
		)
		(fill yes
			(thermal_gap 0.5)
			(thermal_bridge_width 0.5)
			(island_removal_mode 0)
		)
		(polygon
			(pts
				(arc
					(start 39.069264 -348.709488)
					(mid 37.309044 -348.709488)
					(end 39.069264 -348.709488)
				)
			)
		)
	)
	(zone
		(layers "In1.Cu" "In3.Cu" "In5.Cu" "In7.Cu" "In8.Cu" "In9.Cu" "In10.Cu"
			"In12.Cu" "In14.Cu" "In16.Cu"
		)
		(hatch none 0.5)
		(connect_pads
			(clearance 0)
		)
		(min_thickness 0.25)
		(keepout
			(tracks not_allowed)
			(vias allowed)
			(pads allowed)
			(copperpour not_allowed)
			(footprints allowed)
		)
		(placement
			(enabled no)
			(sheetname "")
		)
		(fill yes
			(thermal_gap 0.5)
			(thermal_bridge_width 0.5)
			(island_removal_mode 0)
		)
		(polygon
			(pts
				(arc
					(start 104.63403 -175.369474)
					(mid 102.85603 -175.369474)
					(end 104.63403 -175.369474)
				)
			)
		)
	)
	(zone
		(layers "In1.Cu" "In3.Cu" "In5.Cu" "In7.Cu" "In8.Cu" "In9.Cu" "In10.Cu"
			"In12.Cu" "In14.Cu" "In16.Cu"
		)
		(hatch none 0.5)
		(connect_pads
			(clearance 0)
		)
		(min_thickness 0.25)
		(keepout
			(tracks not_allowed)
			(vias allowed)
			(pads allowed)
			(copperpour not_allowed)
			(footprints allowed)
		)
		(placement
			(enabled no)
			(sheetname "")
		)
		(fill yes
			(thermal_gap 0.5)
			(thermal_bridge_width 0.5)
			(island_removal_mode 0)
		)
		(polygon
			(pts
				(arc
					(start 241.102134 -44.802806)
					(mid 239.324134 -44.802806)
					(end 241.102134 -44.802806)
				)
			)
		)
	)
	(zone
		(layers "In1.Cu" "In3.Cu" "In5.Cu" "In7.Cu" "In8.Cu" "In9.Cu" "In10.Cu"
			"In12.Cu" "In14.Cu" "In16.Cu"
		)
		(hatch none 0.5)
		(connect_pads
			(clearance 0)
		)
		(min_thickness 0.25)
		(keepout
			(tracks not_allowed)
			(vias allowed)
			(pads allowed)
			(copperpour not_allowed)
			(footprints allowed)
		)
		(placement
			(enabled no)
			(sheetname "")
		)
		(fill yes
			(thermal_gap 0.5)
			(thermal_bridge_width 0.5)
			(island_removal_mode 0)
		)
		(polygon
			(pts
				(arc
					(start 396.085822 -174.310294)
					(mid 394.307822 -174.310294)
					(end 396.085822 -174.310294)
				)
			)
		)
	)
	(zone
		(layers "In1.Cu" "In3.Cu" "In5.Cu" "In7.Cu" "In8.Cu" "In9.Cu" "In10.Cu"
			"In12.Cu" "In14.Cu" "In16.Cu"
		)
		(hatch none 0.5)
		(connect_pads
			(clearance 0)
		)
		(min_thickness 0.25)
		(keepout
			(tracks not_allowed)
			(vias allowed)
			(pads allowed)
			(copperpour not_allowed)
			(footprints allowed)
		)
		(placement
			(enabled no)
			(sheetname "")
		)
		(fill yes
			(thermal_gap 0.5)
			(thermal_bridge_width 0.5)
			(island_removal_mode 0)
		)
		(polygon
			(pts
				(arc
					(start 81.858104 -335.509108)
					(mid 80.097884 -335.509108)
					(end 81.858104 -335.509108)
				)
			)
		)
	)
	(zone
		(layers "In1.Cu" "In3.Cu" "In5.Cu" "In7.Cu" "In8.Cu" "In9.Cu" "In10.Cu"
			"In12.Cu" "In14.Cu" "In16.Cu"
		)
		(hatch none 0.5)
		(connect_pads
			(clearance 0)
		)
		(min_thickness 0.25)
		(keepout
			(tracks not_allowed)
			(vias allowed)
			(pads allowed)
			(copperpour not_allowed)
			(footprints allowed)
		)
		(placement
			(enabled no)
			(sheetname "")
		)
		(fill yes
			(thermal_gap 0.5)
			(thermal_bridge_width 0.5)
			(island_removal_mode 0)
		)
		(polygon
			(pts
				(arc
					(start 413.375856 -162.494214)
					(mid 411.597856 -162.494214)
					(end 413.375856 -162.494214)
				)
			)
		)
	)
	(zone
		(layers "In1.Cu" "In3.Cu" "In5.Cu" "In7.Cu" "In8.Cu" "In9.Cu" "In10.Cu"
			"In12.Cu" "In14.Cu" "In16.Cu"
		)
		(hatch none 0.5)
		(connect_pads
			(clearance 0)
		)
		(min_thickness 0.25)
		(keepout
			(tracks not_allowed)
			(vias allowed)
			(pads allowed)
			(copperpour not_allowed)
			(footprints allowed)
		)
		(placement
			(enabled no)
			(sheetname "")
		)
		(fill yes
			(thermal_gap 0.5)
			(thermal_bridge_width 0.5)
			(island_removal_mode 0)
		)
		(polygon
			(pts
				(arc
					(start 346.512896 -336.317336)
					(mid 344.734896 -336.317336)
					(end 346.512896 -336.317336)
				)
			)
		)
	)
	(zone
		(layers "In1.Cu" "In3.Cu" "In5.Cu" "In7.Cu" "In8.Cu" "In9.Cu" "In10.Cu"
			"In12.Cu" "In14.Cu" "In16.Cu"
		)
		(hatch none 0.5)
		(connect_pads
			(clearance 0)
		)
		(min_thickness 0.25)
		(keepout
			(tracks not_allowed)
			(vias allowed)
			(pads allowed)
			(copperpour not_allowed)
			(footprints allowed)
		)
		(placement
			(enabled no)
			(sheetname "")
		)
		(fill yes
			(thermal_gap 0.5)
			(thermal_bridge_width 0.5)
			(island_removal_mode 0)
		)
		(polygon
			(pts
				(arc
					(start 344.96121 -337.012788)
					(mid 343.20099 -337.012788)
					(end 344.96121 -337.012788)
				)
			)
		)
	)
	(zone
		(layers "In1.Cu" "In3.Cu" "In5.Cu" "In7.Cu" "In8.Cu" "In9.Cu" "In10.Cu"
			"In12.Cu" "In14.Cu" "In16.Cu"
		)
		(hatch none 0.5)
		(connect_pads
			(clearance 0)
		)
		(min_thickness 0.25)
		(keepout
			(tracks not_allowed)
			(vias allowed)
			(pads allowed)
			(copperpour not_allowed)
			(footprints allowed)
		)
		(placement
			(enabled no)
			(sheetname "")
		)
		(fill yes
			(thermal_gap 0.5)
			(thermal_bridge_width 0.5)
			(island_removal_mode 0)
		)
		(polygon
			(pts
				(arc
					(start 443.796674 -25.982422)
					(mid 442.018674 -25.982422)
					(end 443.796674 -25.982422)
				)
			)
		)
	)
	(zone
		(layers "In1.Cu" "In3.Cu" "In5.Cu" "In7.Cu" "In8.Cu" "In9.Cu" "In10.Cu"
			"In12.Cu" "In14.Cu" "In16.Cu"
		)
		(hatch none 0.5)
		(connect_pads
			(clearance 0)
		)
		(min_thickness 0.25)
		(keepout
			(tracks not_allowed)
			(vias allowed)
			(pads allowed)
			(copperpour not_allowed)
			(footprints allowed)
		)
		(placement
			(enabled no)
			(sheetname "")
		)
		(fill yes
			(thermal_gap 0.5)
			(thermal_bridge_width 0.5)
			(island_removal_mode 0)
		)
		(polygon
			(pts
				(arc
					(start 92.855288 -345.96959)
					(mid 91.077288 -345.96959)
					(end 92.855288 -345.96959)
				)
			)
		)
	)
	(zone
		(layers "In1.Cu" "In3.Cu" "In5.Cu" "In7.Cu" "In8.Cu" "In9.Cu" "In10.Cu"
			"In12.Cu" "In14.Cu" "In16.Cu"
		)
		(hatch none 0.5)
		(connect_pads
			(clearance 0)
		)
		(min_thickness 0.25)
		(keepout
			(tracks not_allowed)
			(vias allowed)
			(pads allowed)
			(copperpour not_allowed)
			(footprints allowed)
		)
		(placement
			(enabled no)
			(sheetname "")
		)
		(fill yes
			(thermal_gap 0.5)
			(thermal_bridge_width 0.5)
			(island_removal_mode 0)
		)
		(polygon
			(pts
				(arc
					(start 360.98226 -152.71242)
					(mid 358.18826 -152.71242)
					(end 360.98226 -152.71242)
				)
			)
		)
	)
	(zone
		(layers "In1.Cu" "In3.Cu" "In5.Cu" "In7.Cu" "In8.Cu" "In9.Cu" "In10.Cu"
			"In12.Cu" "In14.Cu" "In16.Cu"
		)
		(hatch none 0.5)
		(connect_pads
			(clearance 0)
		)
		(min_thickness 0.25)
		(keepout
			(tracks not_allowed)
			(vias allowed)
			(pads allowed)
			(copperpour not_allowed)
			(footprints allowed)
		)
		(placement
			(enabled no)
			(sheetname "")
		)
		(fill yes
			(thermal_gap 0.5)
			(thermal_bridge_width 0.5)
			(island_removal_mode 0)
		)
		(polygon
			(pts
				(arc
					(start 186.961018 -353.716844)
					(mid 185.183018 -353.716844)
					(end 186.961018 -353.716844)
				)
			)
		)
	)
	(zone
		(layers "In1.Cu" "In3.Cu" "In5.Cu" "In7.Cu" "In8.Cu" "In9.Cu" "In10.Cu"
			"In12.Cu" "In14.Cu" "In16.Cu"
		)
		(hatch none 0.5)
		(connect_pads
			(clearance 0)
		)
		(min_thickness 0.25)
		(keepout
			(tracks not_allowed)
			(vias allowed)
			(pads allowed)
			(copperpour not_allowed)
			(footprints allowed)
		)
		(placement
			(enabled no)
			(sheetname "")
		)
		(fill yes
			(thermal_gap 0.5)
			(thermal_bridge_width 0.5)
			(island_removal_mode 0)
		)
		(polygon
			(pts
				(arc
					(start 370.38661 -178.036474)
					(mid 368.60861 -178.036474)
					(end 370.38661 -178.036474)
				)
			)
		)
	)
	(zone
		(layers "In1.Cu" "In3.Cu" "In5.Cu" "In7.Cu" "In8.Cu" "In9.Cu" "In10.Cu"
			"In12.Cu" "In14.Cu" "In16.Cu"
		)
		(hatch none 0.5)
		(connect_pads
			(clearance 0)
		)
		(min_thickness 0.25)
		(keepout
			(tracks not_allowed)
			(vias allowed)
			(pads allowed)
			(copperpour not_allowed)
			(footprints allowed)
		)
		(placement
			(enabled no)
			(sheetname "")
		)
		(fill yes
			(thermal_gap 0.5)
			(thermal_bridge_width 0.5)
			(island_removal_mode 0)
		)
		(polygon
			(pts
				(arc
					(start 99.494594 -337.450684)
					(mid 97.716594 -337.450684)
					(end 99.494594 -337.450684)
				)
			)
		)
	)
	(zone
		(layers "In1.Cu" "In3.Cu" "In5.Cu" "In7.Cu" "In8.Cu" "In9.Cu" "In10.Cu"
			"In12.Cu" "In14.Cu" "In16.Cu"
		)
		(hatch none 0.5)
		(connect_pads
			(clearance 0)
		)
		(min_thickness 0.25)
		(keepout
			(tracks not_allowed)
			(vias allowed)
			(pads allowed)
			(copperpour not_allowed)
			(footprints allowed)
		)
		(placement
			(enabled no)
			(sheetname "")
		)
		(fill yes
			(thermal_gap 0.5)
			(thermal_bridge_width 0.5)
			(island_removal_mode 0)
		)
		(polygon
			(pts
				(arc
					(start 72.597264 -336.988404)
					(mid 70.837044 -336.988404)
					(end 72.597264 -336.988404)
				)
			)
		)
	)
	(zone
		(layers "In1.Cu" "In3.Cu" "In5.Cu" "In7.Cu" "In8.Cu" "In9.Cu" "In10.Cu"
			"In12.Cu" "In14.Cu" "In16.Cu"
		)
		(hatch none 0.5)
		(connect_pads
			(clearance 0)
		)
		(min_thickness 0.25)
		(keepout
			(tracks not_allowed)
			(vias allowed)
			(pads allowed)
			(copperpour not_allowed)
			(footprints allowed)
		)
		(placement
			(enabled no)
			(sheetname "")
		)
		(fill yes
			(thermal_gap 0.5)
			(thermal_bridge_width 0.5)
			(island_removal_mode 0)
		)
		(polygon
			(pts
				(arc
					(start 370.38661 -178.798474)
					(mid 368.60861 -178.798474)
					(end 370.38661 -178.798474)
				)
			)
		)
	)
	(zone
		(layers "In1.Cu" "In3.Cu" "In5.Cu" "In7.Cu" "In8.Cu" "In9.Cu" "In10.Cu"
			"In12.Cu" "In14.Cu" "In16.Cu"
		)
		(hatch none 0.5)
		(connect_pads
			(clearance 0)
		)
		(min_thickness 0.25)
		(keepout
			(tracks not_allowed)
			(vias allowed)
			(pads allowed)
			(copperpour not_allowed)
			(footprints allowed)
		)
		(placement
			(enabled no)
			(sheetname "")
		)
		(fill yes
			(thermal_gap 0.5)
			(thermal_bridge_width 0.5)
			(island_removal_mode 0)
		)
		(polygon
			(pts
				(arc
					(start 49.786794 -349.523558)
					(mid 48.008794 -349.523558)
					(end 49.786794 -349.523558)
				)
			)
		)
	)
	(zone
		(layers "In1.Cu" "In3.Cu" "In5.Cu" "In7.Cu" "In8.Cu" "In9.Cu" "In10.Cu"
			"In12.Cu" "In14.Cu" "In16.Cu"
		)
		(hatch none 0.5)
		(connect_pads
			(clearance 0)
		)
		(min_thickness 0.25)
		(keepout
			(tracks not_allowed)
			(vias allowed)
			(pads allowed)
			(copperpour not_allowed)
			(footprints allowed)
		)
		(placement
			(enabled no)
			(sheetname "")
		)
		(fill yes
			(thermal_gap 0.5)
			(thermal_bridge_width 0.5)
			(island_removal_mode 0)
		)
		(polygon
			(pts
				(arc
					(start 67.669664 -24.88311)
					(mid 65.891664 -24.88311)
					(end 67.669664 -24.88311)
				)
			)
		)
	)
	(zone
		(layers "In1.Cu" "In3.Cu" "In5.Cu" "In7.Cu" "In8.Cu" "In9.Cu" "In10.Cu"
			"In12.Cu" "In14.Cu" "In16.Cu"
		)
		(hatch none 0.5)
		(connect_pads
			(clearance 0)
		)
		(min_thickness 0.25)
		(keepout
			(tracks not_allowed)
			(vias allowed)
			(pads allowed)
			(copperpour not_allowed)
			(footprints allowed)
		)
		(placement
			(enabled no)
			(sheetname "")
		)
		(fill yes
			(thermal_gap 0.5)
			(thermal_bridge_width 0.5)
			(island_removal_mode 0)
		)
		(polygon
			(pts
				(arc
					(start 414.719008 -161.779458)
					(mid 412.958788 -161.779458)
					(end 414.719008 -161.779458)
				)
			)
		)
	)
	(zone
		(layers "In1.Cu" "In3.Cu" "In5.Cu" "In7.Cu" "In8.Cu" "In9.Cu" "In10.Cu"
			"In12.Cu" "In14.Cu" "In16.Cu"
		)
		(hatch none 0.5)
		(connect_pads
			(clearance 0)
		)
		(min_thickness 0.25)
		(keepout
			(tracks not_allowed)
			(vias allowed)
			(pads allowed)
			(copperpour not_allowed)
			(footprints allowed)
		)
		(placement
			(enabled no)
			(sheetname "")
		)
		(fill yes
			(thermal_gap 0.5)
			(thermal_bridge_width 0.5)
			(island_removal_mode 0)
		)
		(polygon
			(pts
				(arc
					(start 355.732588 -343.117932)
					(mid 353.954588 -343.117932)
					(end 355.732588 -343.117932)
				)
			)
		)
	)
	(zone
		(layers "In1.Cu" "In3.Cu" "In5.Cu" "In7.Cu" "In8.Cu" "In9.Cu" "In10.Cu"
			"In12.Cu" "In14.Cu" "In16.Cu"
		)
		(hatch none 0.5)
		(connect_pads
			(clearance 0)
		)
		(min_thickness 0.25)
		(keepout
			(tracks not_allowed)
			(vias allowed)
			(pads allowed)
			(copperpour not_allowed)
			(footprints allowed)
		)
		(placement
			(enabled no)
			(sheetname "")
		)
		(fill yes
			(thermal_gap 0.5)
			(thermal_bridge_width 0.5)
			(island_removal_mode 0)
		)
		(polygon
			(pts
				(arc
					(start 302.553116 -348.704662)
					(mid 300.792896 -348.704662)
					(end 302.553116 -348.704662)
				)
			)
		)
	)
	(zone
		(layers "In1.Cu" "In3.Cu" "In5.Cu" "In7.Cu" "In8.Cu" "In9.Cu" "In10.Cu"
			"In12.Cu" "In14.Cu" "In16.Cu"
		)
		(hatch none 0.5)
		(connect_pads
			(clearance 0)
		)
		(min_thickness 0.25)
		(keepout
			(tracks not_allowed)
			(vias allowed)
			(pads allowed)
			(copperpour not_allowed)
			(footprints allowed)
		)
		(placement
			(enabled no)
			(sheetname "")
		)
		(fill yes
			(thermal_gap 0.5)
			(thermal_bridge_width 0.5)
			(island_removal_mode 0)
		)
		(polygon
			(pts
				(arc
					(start 92.904056 -345.261184)
					(mid 91.126056 -345.261184)
					(end 92.904056 -345.261184)
				)
			)
		)
	)
	(zone
		(layers "In1.Cu" "In3.Cu" "In5.Cu" "In7.Cu" "In8.Cu" "In9.Cu" "In10.Cu"
			"In12.Cu" "In14.Cu" "In16.Cu"
		)
		(hatch none 0.5)
		(connect_pads
			(clearance 0)
		)
		(min_thickness 0.25)
		(keepout
			(tracks not_allowed)
			(vias allowed)
			(pads allowed)
			(copperpour not_allowed)
			(footprints allowed)
		)
		(placement
			(enabled no)
			(sheetname "")
		)
		(fill yes
			(thermal_gap 0.5)
			(thermal_bridge_width 0.5)
			(island_removal_mode 0)
		)
		(polygon
			(pts
				(arc
					(start 361.492038 -175.705516)
					(mid 359.714038 -175.705516)
					(end 361.492038 -175.705516)
				)
			)
		)
	)
	(zone
		(layers "In1.Cu" "In3.Cu" "In5.Cu" "In7.Cu" "In8.Cu" "In9.Cu" "In10.Cu"
			"In12.Cu" "In14.Cu" "In16.Cu"
		)
		(hatch none 0.5)
		(connect_pads
			(clearance 0)
		)
		(min_thickness 0.25)
		(keepout
			(tracks not_allowed)
			(vias allowed)
			(pads allowed)
			(copperpour not_allowed)
			(footprints allowed)
		)
		(placement
			(enabled no)
			(sheetname "")
		)
		(fill yes
			(thermal_gap 0.5)
			(thermal_bridge_width 0.5)
			(island_removal_mode 0)
		)
		(polygon
			(pts
				(arc
					(start 442.907674 -25.982422)
					(mid 441.129674 -25.982422)
					(end 442.907674 -25.982422)
				)
			)
		)
	)
	(zone
		(layers "In1.Cu" "In3.Cu" "In5.Cu" "In7.Cu" "In8.Cu" "In9.Cu" "In10.Cu"
			"In12.Cu" "In14.Cu" "In16.Cu"
		)
		(hatch none 0.5)
		(connect_pads
			(clearance 0)
		)
		(min_thickness 0.25)
		(keepout
			(tracks not_allowed)
			(vias allowed)
			(pads allowed)
			(copperpour not_allowed)
			(footprints allowed)
		)
		(placement
			(enabled no)
			(sheetname "")
		)
		(fill yes
			(thermal_gap 0.5)
			(thermal_bridge_width 0.5)
			(island_removal_mode 0)
		)
		(polygon
			(pts
				(arc
					(start 240.467134 -44.802806)
					(mid 238.689134 -44.802806)
					(end 240.467134 -44.802806)
				)
			)
		)
	)
	(zone
		(layers "In1.Cu" "In3.Cu" "In5.Cu" "In7.Cu" "In8.Cu" "In9.Cu" "In10.Cu"
			"In12.Cu" "In14.Cu" "In16.Cu"
		)
		(hatch none 0.5)
		(connect_pads
			(clearance 0)
		)
		(min_thickness 0.25)
		(keepout
			(tracks not_allowed)
			(vias allowed)
			(pads allowed)
			(copperpour not_allowed)
			(footprints allowed)
		)
		(placement
			(enabled no)
			(sheetname "")
		)
		(fill yes
			(thermal_gap 0.5)
			(thermal_bridge_width 0.5)
			(island_removal_mode 0)
		)
		(polygon
			(pts
				(arc
					(start 186.923172 -362.234988)
					(mid 185.145172 -362.234988)
					(end 186.923172 -362.234988)
				)
			)
		)
	)
	(zone
		(layers "In1.Cu" "In3.Cu" "In5.Cu" "In7.Cu" "In8.Cu" "In9.Cu" "In10.Cu"
			"In12.Cu" "In14.Cu" "In16.Cu"
		)
		(hatch none 0.5)
		(connect_pads
			(clearance 0)
		)
		(min_thickness 0.25)
		(keepout
			(tracks not_allowed)
			(vias allowed)
			(pads allowed)
			(copperpour not_allowed)
			(footprints allowed)
		)
		(placement
			(enabled no)
			(sheetname "")
		)
		(fill yes
			(thermal_gap 0.5)
			(thermal_bridge_width 0.5)
			(island_removal_mode 0)
		)
		(polygon
			(pts
				(arc
					(start 436.570628 -353.20605)
					(mid 434.792628 -353.20605)
					(end 436.570628 -353.20605)
				)
			)
		)
	)
	(zone
		(layers "In1.Cu" "In3.Cu" "In5.Cu" "In7.Cu" "In8.Cu" "In9.Cu" "In10.Cu"
			"In12.Cu" "In14.Cu" "In16.Cu"
		)
		(hatch none 0.5)
		(connect_pads
			(clearance 0)
		)
		(min_thickness 0.25)
		(keepout
			(tracks not_allowed)
			(vias allowed)
			(pads allowed)
			(copperpour not_allowed)
			(footprints allowed)
		)
		(placement
			(enabled no)
			(sheetname "")
		)
		(fill yes
			(thermal_gap 0.5)
			(thermal_bridge_width 0.5)
			(island_removal_mode 0)
		)
		(polygon
			(pts
				(arc
					(start 287.26511 -355.949758)
					(mid 285.48711 -355.949758)
					(end 287.26511 -355.949758)
				)
			)
		)
	)
	(zone
		(layers "In1.Cu" "In3.Cu" "In5.Cu" "In7.Cu" "In8.Cu" "In9.Cu" "In10.Cu"
			"In12.Cu" "In14.Cu" "In16.Cu"
		)
		(hatch none 0.5)
		(connect_pads
			(clearance 0)
		)
		(min_thickness 0.25)
		(keepout
			(tracks not_allowed)
			(vias allowed)
			(pads allowed)
			(copperpour not_allowed)
			(footprints allowed)
		)
		(placement
			(enabled no)
			(sheetname "")
		)
		(fill yes
			(thermal_gap 0.5)
			(thermal_bridge_width 0.5)
			(island_removal_mode 0)
		)
		(polygon
			(pts
				(arc
					(start 452.943976 -17.798542)
					(mid 451.165976 -17.798542)
					(end 452.943976 -17.798542)
				)
			)
		)
	)
	(zone
		(layers "In1.Cu" "In3.Cu" "In5.Cu" "In7.Cu" "In8.Cu" "In9.Cu" "In10.Cu"
			"In12.Cu" "In14.Cu" "In16.Cu"
		)
		(hatch none 0.5)
		(connect_pads
			(clearance 0)
		)
		(min_thickness 0.25)
		(keepout
			(tracks not_allowed)
			(vias allowed)
			(pads allowed)
			(copperpour not_allowed)
			(footprints allowed)
		)
		(placement
			(enabled no)
			(sheetname "")
		)
		(fill yes
			(thermal_gap 0.5)
			(thermal_bridge_width 0.5)
			(island_removal_mode 0)
		)
		(polygon
			(pts
				(arc
					(start 371.588284 -165.19398)
					(mid 369.810284 -165.19398)
					(end 371.588284 -165.19398)
				)
			)
		)
	)
	(zone
		(layers "In1.Cu" "In3.Cu" "In5.Cu" "In7.Cu" "In8.Cu" "In9.Cu" "In10.Cu"
			"In12.Cu" "In14.Cu" "In16.Cu"
		)
		(hatch none 0.5)
		(connect_pads
			(clearance 0)
		)
		(min_thickness 0.25)
		(keepout
			(tracks not_allowed)
			(vias allowed)
			(pads allowed)
			(copperpour not_allowed)
			(footprints allowed)
		)
		(placement
			(enabled no)
			(sheetname "")
		)
		(fill yes
			(thermal_gap 0.5)
			(thermal_bridge_width 0.5)
			(island_removal_mode 0)
		)
		(polygon
			(pts
				(arc
					(start 117.147594 -152.657556)
					(mid 115.369594 -152.657556)
					(end 117.147594 -152.657556)
				)
			)
		)
	)
	(zone
		(layers "In1.Cu" "In3.Cu" "In5.Cu" "In7.Cu" "In8.Cu" "In9.Cu" "In10.Cu"
			"In12.Cu" "In14.Cu" "In16.Cu"
		)
		(hatch none 0.5)
		(connect_pads
			(clearance 0)
		)
		(min_thickness 0.25)
		(keepout
			(tracks not_allowed)
			(vias allowed)
			(pads allowed)
			(copperpour not_allowed)
			(footprints allowed)
		)
		(placement
			(enabled no)
			(sheetname "")
		)
		(fill yes
			(thermal_gap 0.5)
			(thermal_bridge_width 0.5)
			(island_removal_mode 0)
		)
		(polygon
			(pts
				(arc
					(start 354.295202 -166.635176)
					(mid 352.517202 -166.635176)
					(end 354.295202 -166.635176)
				)
			)
		)
	)
	(zone
		(layers "In1.Cu" "In3.Cu" "In5.Cu" "In7.Cu" "In8.Cu" "In9.Cu" "In10.Cu"
			"In12.Cu" "In14.Cu" "In16.Cu"
		)
		(hatch none 0.5)
		(connect_pads
			(clearance 0)
		)
		(min_thickness 0.25)
		(keepout
			(tracks not_allowed)
			(vias allowed)
			(pads allowed)
			(copperpour not_allowed)
			(footprints allowed)
		)
		(placement
			(enabled no)
			(sheetname "")
		)
		(fill yes
			(thermal_gap 0.5)
			(thermal_bridge_width 0.5)
			(island_removal_mode 0)
		)
		(polygon
			(pts
				(arc
					(start 104.63403 -176.106074)
					(mid 102.85603 -176.106074)
					(end 104.63403 -176.106074)
				)
			)
		)
	)
	(zone
		(layers "In1.Cu" "In3.Cu" "In5.Cu" "In7.Cu" "In8.Cu" "In9.Cu" "In10.Cu"
			"In12.Cu" "In14.Cu" "In16.Cu"
		)
		(hatch none 0.5)
		(connect_pads
			(clearance 0)
		)
		(min_thickness 0.25)
		(keepout
			(tracks not_allowed)
			(vias allowed)
			(pads allowed)
			(copperpour not_allowed)
			(footprints allowed)
		)
		(placement
			(enabled no)
			(sheetname "")
		)
		(fill yes
			(thermal_gap 0.5)
			(thermal_bridge_width 0.5)
			(island_removal_mode 0)
		)
		(polygon
			(pts
				(arc
					(start 428.244 -353.18065)
					(mid 426.466 -353.18065)
					(end 428.244 -353.18065)
				)
			)
		)
	)
	(zone
		(layers "In1.Cu" "In3.Cu" "In5.Cu" "In7.Cu" "In8.Cu" "In9.Cu" "In10.Cu"
			"In12.Cu" "In14.Cu" "In16.Cu"
		)
		(hatch none 0.5)
		(connect_pads
			(clearance 0)
		)
		(min_thickness 0.25)
		(keepout
			(tracks not_allowed)
			(vias allowed)
			(pads allowed)
			(copperpour not_allowed)
			(footprints allowed)
		)
		(placement
			(enabled no)
			(sheetname "")
		)
		(fill yes
			(thermal_gap 0.5)
			(thermal_bridge_width 0.5)
			(island_removal_mode 0)
		)
		(polygon
			(pts
				(arc
					(start 106.814112 -340.492842)
					(mid 105.053892 -340.492842)
					(end 106.814112 -340.492842)
				)
			)
		)
	)
	(zone
		(layers "In1.Cu" "In3.Cu" "In5.Cu" "In7.Cu" "In8.Cu" "In9.Cu" "In10.Cu"
			"In12.Cu" "In14.Cu" "In16.Cu"
		)
		(hatch none 0.5)
		(connect_pads
			(clearance 0)
		)
		(min_thickness 0.25)
		(keepout
			(tracks not_allowed)
			(vias allowed)
			(pads allowed)
			(copperpour not_allowed)
			(footprints allowed)
		)
		(placement
			(enabled no)
			(sheetname "")
		)
		(fill yes
			(thermal_gap 0.5)
			(thermal_bridge_width 0.5)
			(island_removal_mode 0)
		)
		(polygon
			(pts
				(arc
					(start 92.182442 -346.639896)
					(mid 90.404442 -346.639896)
					(end 92.182442 -346.639896)
				)
			)
		)
	)
	(zone
		(layers "In1.Cu" "In3.Cu" "In5.Cu" "In7.Cu" "In8.Cu" "In9.Cu" "In10.Cu"
			"In12.Cu" "In14.Cu" "In16.Cu"
		)
		(hatch none 0.5)
		(connect_pads
			(clearance 0)
		)
		(min_thickness 0.25)
		(keepout
			(tracks not_allowed)
			(vias allowed)
			(pads allowed)
			(copperpour not_allowed)
			(footprints allowed)
		)
		(placement
			(enabled no)
			(sheetname "")
		)
		(fill yes
			(thermal_gap 0.5)
			(thermal_bridge_width 0.5)
			(island_removal_mode 0)
		)
		(polygon
			(pts
				(arc
					(start 71.13905 -174.086774)
					(mid 69.36105 -174.086774)
					(end 71.13905 -174.086774)
				)
			)
		)
	)
	(zone
		(layers "In1.Cu" "In3.Cu" "In5.Cu" "In7.Cu" "In8.Cu" "In9.Cu" "In10.Cu"
			"In12.Cu" "In14.Cu" "In16.Cu"
		)
		(hatch none 0.5)
		(connect_pads
			(clearance 0)
		)
		(min_thickness 0.25)
		(keepout
			(tracks not_allowed)
			(vias allowed)
			(pads allowed)
			(copperpour not_allowed)
			(footprints allowed)
		)
		(placement
			(enabled no)
			(sheetname "")
		)
		(fill yes
			(thermal_gap 0.5)
			(thermal_bridge_width 0.5)
			(island_removal_mode 0)
		)
		(polygon
			(pts
				(arc
					(start 193.578734 -13.106908)
					(mid 191.800734 -13.106908)
					(end 193.578734 -13.106908)
				)
			)
		)
	)
	(zone
		(layers "In1.Cu" "In3.Cu" "In5.Cu" "In7.Cu" "In8.Cu" "In9.Cu" "In10.Cu"
			"In12.Cu" "In14.Cu" "In16.Cu"
		)
		(hatch none 0.5)
		(connect_pads
			(clearance 0)
		)
		(min_thickness 0.25)
		(keepout
			(tracks not_allowed)
			(vias allowed)
			(pads allowed)
			(copperpour not_allowed)
			(footprints allowed)
		)
		(placement
			(enabled no)
			(sheetname "")
		)
		(fill yes
			(thermal_gap 0.5)
			(thermal_bridge_width 0.5)
			(island_removal_mode 0)
		)
		(polygon
			(pts
				(arc
					(start 339.65896 -337.039458)
					(mid 337.88096 -337.039458)
					(end 339.65896 -337.039458)
				)
			)
		)
	)
	(zone
		(layers "In1.Cu" "In3.Cu" "In5.Cu" "In7.Cu" "In8.Cu" "In9.Cu" "In10.Cu"
			"In12.Cu" "In14.Cu" "In16.Cu"
		)
		(hatch none 0.5)
		(connect_pads
			(clearance 0)
		)
		(min_thickness 0.25)
		(keepout
			(tracks not_allowed)
			(vias allowed)
			(pads allowed)
			(copperpour not_allowed)
			(footprints allowed)
		)
		(placement
			(enabled no)
			(sheetname "")
		)
		(fill yes
			(thermal_gap 0.5)
			(thermal_bridge_width 0.5)
			(island_removal_mode 0)
		)
		(polygon
			(pts
				(arc
					(start 48.70323 -350.318578)
					(mid 46.92523 -350.318578)
					(end 48.70323 -350.318578)
				)
			)
		)
	)
	(zone
		(layers "In1.Cu" "In3.Cu" "In5.Cu" "In7.Cu" "In8.Cu" "In9.Cu" "In10.Cu"
			"In12.Cu" "In14.Cu" "In16.Cu"
		)
		(hatch none 0.5)
		(connect_pads
			(clearance 0)
		)
		(min_thickness 0.25)
		(keepout
			(tracks not_allowed)
			(vias allowed)
			(pads allowed)
			(copperpour not_allowed)
			(footprints allowed)
		)
		(placement
			(enabled no)
			(sheetname "")
		)
		(fill yes
			(thermal_gap 0.5)
			(thermal_bridge_width 0.5)
			(island_removal_mode 0)
		)
		(polygon
			(pts
				(arc
					(start 329.348084 -349.43161)
					(mid 326.554084 -349.43161)
					(end 329.348084 -349.43161)
				)
			)
		)
	)
	(zone
		(layers "In1.Cu" "In3.Cu" "In5.Cu" "In7.Cu" "In8.Cu" "In9.Cu" "In10.Cu"
			"In12.Cu" "In14.Cu" "In16.Cu"
		)
		(hatch none 0.5)
		(connect_pads
			(clearance 0)
		)
		(min_thickness 0.25)
		(keepout
			(tracks not_allowed)
			(vias allowed)
			(pads allowed)
			(copperpour not_allowed)
			(footprints allowed)
		)
		(placement
			(enabled no)
			(sheetname "")
		)
		(fill yes
			(thermal_gap 0.5)
			(thermal_bridge_width 0.5)
			(island_removal_mode 0)
		)
		(polygon
			(pts
				(arc
					(start 295.524682 -349.577152)
					(mid 293.746682 -349.577152)
					(end 295.524682 -349.577152)
				)
			)
		)
	)
	(zone
		(layers "In1.Cu" "In3.Cu" "In5.Cu" "In7.Cu" "In8.Cu" "In9.Cu" "In10.Cu"
			"In12.Cu" "In14.Cu" "In16.Cu"
		)
		(hatch none 0.5)
		(connect_pads
			(clearance 0)
		)
		(min_thickness 0.25)
		(keepout
			(tracks not_allowed)
			(vias allowed)
			(pads allowed)
			(copperpour not_allowed)
			(footprints allowed)
		)
		(placement
			(enabled no)
			(sheetname "")
		)
		(fill yes
			(thermal_gap 0.5)
			(thermal_bridge_width 0.5)
			(island_removal_mode 0)
		)
		(polygon
			(pts
				(arc
					(start 114.64036 -169.935144)
					(mid 112.88014 -169.935144)
					(end 114.64036 -169.935144)
				)
			)
		)
	)
	(zone
		(layers "In1.Cu" "In3.Cu" "In5.Cu" "In7.Cu" "In8.Cu" "In9.Cu" "In10.Cu"
			"In12.Cu" "In14.Cu" "In16.Cu"
		)
		(hatch none 0.5)
		(connect_pads
			(clearance 0)
		)
		(min_thickness 0.25)
		(keepout
			(tracks not_allowed)
			(vias allowed)
			(pads allowed)
			(copperpour not_allowed)
			(footprints allowed)
		)
		(placement
			(enabled no)
			(sheetname "")
		)
		(fill yes
			(thermal_gap 0.5)
			(thermal_bridge_width 0.5)
			(island_removal_mode 0)
		)
		(polygon
			(pts
				(arc
					(start 303.415446 -347.265752)
					(mid 301.637446 -347.265752)
					(end 303.415446 -347.265752)
				)
			)
		)
	)
	(zone
		(layers "In1.Cu" "In3.Cu" "In5.Cu" "In7.Cu" "In8.Cu" "In9.Cu" "In10.Cu"
			"In12.Cu" "In14.Cu" "In16.Cu"
		)
		(hatch none 0.5)
		(connect_pads
			(clearance 0)
		)
		(min_thickness 0.25)
		(keepout
			(tracks not_allowed)
			(vias allowed)
			(pads allowed)
			(copperpour not_allowed)
			(footprints allowed)
		)
		(placement
			(enabled no)
			(sheetname "")
		)
		(fill yes
			(thermal_gap 0.5)
			(thermal_bridge_width 0.5)
			(island_removal_mode 0)
		)
		(polygon
			(pts
				(arc
					(start 371.575584 -163.89858)
					(mid 369.797584 -163.89858)
					(end 371.575584 -163.89858)
				)
			)
		)
	)
	(zone
		(layers "In1.Cu" "In3.Cu" "In5.Cu" "In7.Cu" "In8.Cu" "In9.Cu" "In10.Cu"
			"In12.Cu" "In14.Cu" "In16.Cu"
		)
		(hatch none 0.5)
		(connect_pads
			(clearance 0)
		)
		(min_thickness 0.25)
		(keepout
			(tracks not_allowed)
			(vias allowed)
			(pads allowed)
			(copperpour not_allowed)
			(footprints allowed)
		)
		(placement
			(enabled no)
			(sheetname "")
		)
		(fill yes
			(thermal_gap 0.5)
			(thermal_bridge_width 0.5)
			(island_removal_mode 0)
		)
		(polygon
			(pts
				(arc
					(start 61.911738 -393.292838)
					(mid 62.216538 -393.597638)
					(end 62.521338 -393.292838)
				)
				(arc
					(start 62.521338 -392.429238)
					(mid 62.216538 -392.124438)
					(end 61.911738 -392.429238)
				)
			)
		)
	)
	(zone
		(layers "In1.Cu" "In3.Cu" "In5.Cu" "In7.Cu" "In8.Cu" "In9.Cu" "In10.Cu"
			"In12.Cu" "In14.Cu" "In16.Cu"
		)
		(hatch none 0.5)
		(connect_pads
			(clearance 0)
		)
		(min_thickness 0.25)
		(keepout
			(tracks not_allowed)
			(vias allowed)
			(pads allowed)
			(copperpour not_allowed)
			(footprints allowed)
		)
		(placement
			(enabled no)
			(sheetname "")
		)
		(fill yes
			(thermal_gap 0.5)
			(thermal_bridge_width 0.5)
			(island_removal_mode 0)
		)
		(polygon
			(pts
				(arc
					(start 57.05983 -350.318578)
					(mid 55.28183 -350.318578)
					(end 57.05983 -350.318578)
				)
			)
		)
	)
	(zone
		(layers "In1.Cu" "In3.Cu" "In5.Cu" "In7.Cu" "In8.Cu" "In9.Cu" "In10.Cu"
			"In12.Cu" "In14.Cu" "In16.Cu"
		)
		(hatch none 0.5)
		(connect_pads
			(clearance 0)
		)
		(min_thickness 0.25)
		(keepout
			(tracks not_allowed)
			(vias allowed)
			(pads allowed)
			(copperpour not_allowed)
			(footprints allowed)
		)
		(placement
			(enabled no)
			(sheetname "")
		)
		(fill yes
			(thermal_gap 0.5)
			(thermal_bridge_width 0.5)
			(island_removal_mode 0)
		)
		(polygon
			(pts
				(arc
					(start 338.169504 -336.253836)
					(mid 336.391504 -336.253836)
					(end 338.169504 -336.253836)
				)
			)
		)
	)
	(zone
		(layers "In1.Cu" "In3.Cu" "In5.Cu" "In7.Cu" "In8.Cu" "In9.Cu" "In10.Cu"
			"In12.Cu" "In14.Cu" "In16.Cu"
		)
		(hatch none 0.5)
		(connect_pads
			(clearance 0)
		)
		(min_thickness 0.25)
		(keepout
			(tracks not_allowed)
			(vias allowed)
			(pads allowed)
			(copperpour not_allowed)
			(footprints allowed)
		)
		(placement
			(enabled no)
			(sheetname "")
		)
		(fill yes
			(thermal_gap 0.5)
			(thermal_bridge_width 0.5)
			(island_removal_mode 0)
		)
		(polygon
			(pts
				(arc
					(start 71.67245 -174.442374)
					(mid 69.89445 -174.442374)
					(end 71.67245 -174.442374)
				)
			)
		)
	)
	(zone
		(layers "In1.Cu" "In3.Cu" "In5.Cu" "In7.Cu" "In8.Cu" "In9.Cu" "In10.Cu"
			"In12.Cu" "In14.Cu" "In16.Cu"
		)
		(hatch none 0.5)
		(connect_pads
			(clearance 0)
		)
		(min_thickness 0.25)
		(keepout
			(tracks not_allowed)
			(vias allowed)
			(pads allowed)
			(copperpour not_allowed)
			(footprints allowed)
		)
		(placement
			(enabled no)
			(sheetname "")
		)
		(fill yes
			(thermal_gap 0.5)
			(thermal_bridge_width 0.5)
			(island_removal_mode 0)
		)
		(polygon
			(pts
				(arc
					(start 388.817358 -156.366972)
					(mid 387.039358 -156.366972)
					(end 388.817358 -156.366972)
				)
			)
		)
	)
	(zone
		(layers "In1.Cu" "In3.Cu" "In5.Cu" "In7.Cu" "In8.Cu" "In9.Cu" "In10.Cu"
			"In12.Cu" "In14.Cu" "In16.Cu"
		)
		(hatch none 0.5)
		(connect_pads
			(clearance 0)
		)
		(min_thickness 0.25)
		(keepout
			(tracks not_allowed)
			(vias allowed)
			(pads allowed)
			(copperpour not_allowed)
			(footprints allowed)
		)
		(placement
			(enabled no)
			(sheetname "")
		)
		(fill yes
			(thermal_gap 0.5)
			(thermal_bridge_width 0.5)
			(island_removal_mode 0)
		)
		(polygon
			(pts
				(arc
					(start 194.762882 -354.181664)
					(mid 192.984882 -354.181664)
					(end 194.762882 -354.181664)
				)
			)
		)
	)
	(zone
		(layers "In1.Cu" "In3.Cu" "In5.Cu" "In7.Cu" "In8.Cu" "In9.Cu" "In10.Cu"
			"In12.Cu" "In14.Cu" "In16.Cu"
		)
		(hatch none 0.5)
		(connect_pads
			(clearance 0)
		)
		(min_thickness 0.25)
		(keepout
			(tracks not_allowed)
			(vias allowed)
			(pads allowed)
			(copperpour not_allowed)
			(footprints allowed)
		)
		(placement
			(enabled no)
			(sheetname "")
		)
		(fill yes
			(thermal_gap 0.5)
			(thermal_bridge_width 0.5)
			(island_removal_mode 0)
		)
		(polygon
			(pts
				(arc
					(start 378.814838 -180.322474)
					(mid 377.036838 -180.322474)
					(end 378.814838 -180.322474)
				)
			)
		)
	)
	(zone
		(layers "In1.Cu" "In3.Cu" "In5.Cu" "In7.Cu" "In8.Cu" "In9.Cu" "In10.Cu"
			"In12.Cu" "In14.Cu" "In16.Cu"
		)
		(hatch none 0.5)
		(connect_pads
			(clearance 0)
		)
		(min_thickness 0.25)
		(keepout
			(tracks not_allowed)
			(vias allowed)
			(pads allowed)
			(copperpour not_allowed)
			(footprints allowed)
		)
		(placement
			(enabled no)
			(sheetname "")
		)
		(fill yes
			(thermal_gap 0.5)
			(thermal_bridge_width 0.5)
			(island_removal_mode 0)
		)
		(polygon
			(pts
				(arc
					(start 321.4497 -336.239612)
					(mid 319.6717 -336.239612)
					(end 321.4497 -336.239612)
				)
			)
		)
	)
	(zone
		(layers "In1.Cu" "In3.Cu" "In5.Cu" "In7.Cu" "In8.Cu" "In9.Cu" "In10.Cu"
			"In12.Cu" "In14.Cu" "In16.Cu"
		)
		(hatch none 0.5)
		(connect_pads
			(clearance 0)
		)
		(min_thickness 0.25)
		(keepout
			(tracks not_allowed)
			(vias allowed)
			(pads allowed)
			(copperpour not_allowed)
			(footprints allowed)
		)
		(placement
			(enabled no)
			(sheetname "")
		)
		(fill yes
			(thermal_gap 0.5)
			(thermal_bridge_width 0.5)
			(island_removal_mode 0)
		)
		(polygon
			(pts
				(arc
					(start 194.17792 -351.827084)
					(mid 192.39992 -351.827084)
					(end 194.17792 -351.827084)
				)
			)
		)
	)
	(zone
		(layers "In1.Cu" "In3.Cu" "In5.Cu" "In7.Cu" "In8.Cu" "In9.Cu" "In10.Cu"
			"In12.Cu" "In14.Cu" "In16.Cu"
		)
		(hatch none 0.5)
		(connect_pads
			(clearance 0)
		)
		(min_thickness 0.25)
		(keepout
			(tracks not_allowed)
			(vias allowed)
			(pads allowed)
			(copperpour not_allowed)
			(footprints allowed)
		)
		(placement
			(enabled no)
			(sheetname "")
		)
		(fill yes
			(thermal_gap 0.5)
			(thermal_bridge_width 0.5)
			(island_removal_mode 0)
		)
		(polygon
			(pts
				(arc
					(start 122.92076 -163.204144)
					(mid 121.16054 -163.204144)
					(end 122.92076 -163.204144)
				)
			)
		)
	)
	(zone
		(layers "In1.Cu" "In3.Cu" "In5.Cu" "In7.Cu" "In8.Cu" "In9.Cu" "In10.Cu"
			"In12.Cu" "In14.Cu" "In16.Cu"
		)
		(hatch none 0.5)
		(connect_pads
			(clearance 0)
		)
		(min_thickness 0.25)
		(keepout
			(tracks not_allowed)
			(vias allowed)
			(pads allowed)
			(copperpour not_allowed)
			(footprints allowed)
		)
		(placement
			(enabled no)
			(sheetname "")
		)
		(fill yes
			(thermal_gap 0.5)
			(thermal_bridge_width 0.5)
			(island_removal_mode 0)
		)
		(polygon
			(pts
				(arc
					(start 427.7106 -354.29825)
					(mid 425.9326 -354.29825)
					(end 427.7106 -354.29825)
				)
			)
		)
	)
	(zone
		(layers "In1.Cu" "In3.Cu" "In5.Cu" "In7.Cu" "In8.Cu" "In9.Cu" "In10.Cu"
			"In12.Cu" "In14.Cu" "In16.Cu"
		)
		(hatch none 0.5)
		(connect_pads
			(clearance 0)
		)
		(min_thickness 0.25)
		(keepout
			(tracks not_allowed)
			(vias allowed)
			(pads allowed)
			(copperpour not_allowed)
			(footprints allowed)
		)
		(placement
			(enabled no)
			(sheetname "")
		)
		(fill yes
			(thermal_gap 0.5)
			(thermal_bridge_width 0.5)
			(island_removal_mode 0)
		)
		(polygon
			(pts
				(arc
					(start 98.96983 -337.890104)
					(mid 97.19183 -337.890104)
					(end 98.96983 -337.890104)
				)
			)
		)
	)
	(zone
		(layers "In1.Cu" "In3.Cu" "In5.Cu" "In7.Cu" "In8.Cu" "In9.Cu" "In10.Cu"
			"In12.Cu" "In14.Cu" "In16.Cu"
		)
		(hatch none 0.5)
		(connect_pads
			(clearance 0)
		)
		(min_thickness 0.25)
		(keepout
			(tracks not_allowed)
			(vias allowed)
			(pads allowed)
			(copperpour not_allowed)
			(footprints allowed)
		)
		(placement
			(enabled no)
			(sheetname "")
		)
		(fill yes
			(thermal_gap 0.5)
			(thermal_bridge_width 0.5)
			(island_removal_mode 0)
		)
		(polygon
			(pts
				(arc
					(start 388.363968 -180.755544)
					(mid 386.603748 -180.755544)
					(end 388.363968 -180.755544)
				)
			)
		)
	)
	(zone
		(layers "In1.Cu" "In3.Cu" "In5.Cu" "In7.Cu" "In8.Cu" "In9.Cu" "In10.Cu"
			"In12.Cu" "In14.Cu" "In16.Cu"
		)
		(hatch none 0.5)
		(connect_pads
			(clearance 0)
		)
		(min_thickness 0.25)
		(keepout
			(tracks not_allowed)
			(vias allowed)
			(pads allowed)
			(copperpour not_allowed)
			(footprints allowed)
		)
		(placement
			(enabled no)
			(sheetname "")
		)
		(fill yes
			(thermal_gap 0.5)
			(thermal_bridge_width 0.5)
			(island_removal_mode 0)
		)
		(polygon
			(pts
				(arc
					(start 443.260734 -19.459702)
					(mid 441.482734 -19.459702)
					(end 443.260734 -19.459702)
				)
			)
		)
	)
	(zone
		(layers "In1.Cu" "In3.Cu" "In5.Cu" "In7.Cu" "In8.Cu" "In9.Cu" "In10.Cu"
			"In12.Cu" "In14.Cu" "In16.Cu"
		)
		(hatch none 0.5)
		(connect_pads
			(clearance 0)
		)
		(min_thickness 0.25)
		(keepout
			(tracks not_allowed)
			(vias allowed)
			(pads allowed)
			(copperpour not_allowed)
			(footprints allowed)
		)
		(placement
			(enabled no)
			(sheetname "")
		)
		(fill yes
			(thermal_gap 0.5)
			(thermal_bridge_width 0.5)
			(island_removal_mode 0)
		)
		(polygon
			(pts
				(arc
					(start 90.63863 -337.839304)
					(mid 88.86063 -337.839304)
					(end 90.63863 -337.839304)
				)
			)
		)
	)
	(zone
		(layers "In1.Cu" "In3.Cu" "In5.Cu" "In7.Cu" "In8.Cu" "In9.Cu" "In10.Cu"
			"In12.Cu" "In14.Cu" "In16.Cu"
		)
		(hatch none 0.5)
		(connect_pads
			(clearance 0)
		)
		(min_thickness 0.25)
		(keepout
			(tracks not_allowed)
			(vias allowed)
			(pads allowed)
			(copperpour not_allowed)
			(footprints allowed)
		)
		(placement
			(enabled no)
			(sheetname "")
		)
		(fill yes
			(thermal_gap 0.5)
			(thermal_bridge_width 0.5)
			(island_removal_mode 0)
		)
		(polygon
			(pts
				(arc
					(start 42.306494 -357.263192)
					(mid 40.528494 -357.263192)
					(end 42.306494 -357.263192)
				)
			)
		)
	)
	(zone
		(layers "In1.Cu" "In3.Cu" "In5.Cu" "In7.Cu" "In8.Cu" "In9.Cu" "In10.Cu"
			"In12.Cu" "In14.Cu" "In16.Cu"
		)
		(hatch none 0.5)
		(connect_pads
			(clearance 0)
		)
		(min_thickness 0.25)
		(keepout
			(tracks not_allowed)
			(vias allowed)
			(pads allowed)
			(copperpour not_allowed)
			(footprints allowed)
		)
		(placement
			(enabled no)
			(sheetname "")
		)
		(fill yes
			(thermal_gap 0.5)
			(thermal_bridge_width 0.5)
			(island_removal_mode 0)
		)
		(polygon
			(pts
				(arc
					(start 322.38696 -337.416648)
					(mid 320.60896 -337.416648)
					(end 322.38696 -337.416648)
				)
			)
		)
	)
	(zone
		(layers "In1.Cu" "In3.Cu" "In5.Cu" "In7.Cu" "In8.Cu" "In9.Cu" "In10.Cu"
			"In12.Cu" "In14.Cu" "In16.Cu"
		)
		(hatch none 0.5)
		(connect_pads
			(clearance 0)
		)
		(min_thickness 0.25)
		(keepout
			(tracks not_allowed)
			(vias allowed)
			(pads allowed)
			(copperpour not_allowed)
			(footprints allowed)
		)
		(placement
			(enabled no)
			(sheetname "")
		)
		(fill yes
			(thermal_gap 0.5)
			(thermal_bridge_width 0.5)
			(island_removal_mode 0)
		)
		(polygon
			(pts
				(arc
					(start 396.085822 -173.573694)
					(mid 394.307822 -173.573694)
					(end 396.085822 -173.573694)
				)
			)
		)
	)
	(zone
		(layers "In1.Cu" "In3.Cu" "In5.Cu" "In7.Cu" "In8.Cu" "In9.Cu" "In10.Cu"
			"In12.Cu" "In14.Cu" "In16.Cu"
		)
		(hatch none 0.5)
		(connect_pads
			(clearance 0)
		)
		(min_thickness 0.25)
		(keepout
			(tracks not_allowed)
			(vias allowed)
			(pads allowed)
			(copperpour not_allowed)
			(footprints allowed)
		)
		(placement
			(enabled no)
			(sheetname "")
		)
		(fill yes
			(thermal_gap 0.5)
			(thermal_bridge_width 0.5)
			(island_removal_mode 0)
		)
		(polygon
			(pts
				(arc
					(start 329.506834 -336.976466)
					(mid 327.746614 -336.976466)
					(end 329.506834 -336.976466)
				)
			)
		)
	)
	(zone
		(layers "In1.Cu" "In3.Cu" "In5.Cu" "In7.Cu" "In8.Cu" "In9.Cu" "In10.Cu"
			"In12.Cu" "In14.Cu" "In16.Cu"
		)
		(hatch none 0.5)
		(connect_pads
			(clearance 0)
		)
		(min_thickness 0.25)
		(keepout
			(tracks not_allowed)
			(vias allowed)
			(pads allowed)
			(copperpour not_allowed)
			(footprints allowed)
		)
		(placement
			(enabled no)
			(sheetname "")
		)
		(fill yes
			(thermal_gap 0.5)
			(thermal_bridge_width 0.5)
			(island_removal_mode 0)
		)
		(polygon
			(pts
				(arc
					(start 287.743646 -349.137732)
					(mid 285.965646 -349.137732)
					(end 287.743646 -349.137732)
				)
			)
		)
	)
	(zone
		(layers "In1.Cu" "In3.Cu" "In5.Cu" "In7.Cu" "In8.Cu" "In9.Cu" "In10.Cu"
			"In12.Cu" "In14.Cu" "In16.Cu"
		)
		(hatch none 0.5)
		(connect_pads
			(clearance 0)
		)
		(min_thickness 0.25)
		(keepout
			(tracks not_allowed)
			(vias allowed)
			(pads allowed)
			(copperpour not_allowed)
			(footprints allowed)
		)
		(placement
			(enabled no)
			(sheetname "")
		)
		(fill yes
			(thermal_gap 0.5)
			(thermal_bridge_width 0.5)
			(island_removal_mode 0)
		)
		(polygon
			(pts
				(arc
					(start 246.746522 -52.022502)
					(mid 244.968522 -52.022502)
					(end 246.746522 -52.022502)
				)
			)
		)
	)
	(zone
		(layers "In1.Cu" "In3.Cu" "In5.Cu" "In7.Cu" "In8.Cu" "In9.Cu" "In10.Cu"
			"In12.Cu" "In14.Cu" "In16.Cu"
		)
		(hatch none 0.5)
		(connect_pads
			(clearance 0)
		)
		(min_thickness 0.25)
		(keepout
			(tracks not_allowed)
			(vias allowed)
			(pads allowed)
			(copperpour not_allowed)
			(footprints allowed)
		)
		(placement
			(enabled no)
			(sheetname "")
		)
		(fill yes
			(thermal_gap 0.5)
			(thermal_bridge_width 0.5)
			(island_removal_mode 0)
		)
		(polygon
			(pts
				(arc
					(start 437.120538 -361.496102)
					(mid 435.342538 -361.496102)
					(end 437.120538 -361.496102)
				)
			)
		)
	)
	(zone
		(layers "In1.Cu" "In3.Cu" "In5.Cu" "In7.Cu" "In8.Cu" "In9.Cu" "In10.Cu"
			"In12.Cu" "In14.Cu" "In16.Cu"
		)
		(hatch none 0.5)
		(connect_pads
			(clearance 0)
		)
		(min_thickness 0.25)
		(keepout
			(tracks not_allowed)
			(vias allowed)
			(pads allowed)
			(copperpour not_allowed)
			(footprints allowed)
		)
		(placement
			(enabled no)
			(sheetname "")
		)
		(fill yes
			(thermal_gap 0.5)
			(thermal_bridge_width 0.5)
			(island_removal_mode 0)
		)
		(polygon
			(pts
				(arc
					(start 178.361594 -21.85289)
					(mid 176.583594 -21.85289)
					(end 178.361594 -21.85289)
				)
			)
		)
	)
	(zone
		(layers "In1.Cu" "In3.Cu" "In5.Cu" "In7.Cu" "In8.Cu" "In9.Cu" "In10.Cu"
			"In12.Cu" "In14.Cu" "In16.Cu"
		)
		(hatch none 0.5)
		(connect_pads
			(clearance 0)
		)
		(min_thickness 0.25)
		(keepout
			(tracks not_allowed)
			(vias allowed)
			(pads allowed)
			(copperpour not_allowed)
			(footprints allowed)
		)
		(placement
			(enabled no)
			(sheetname "")
		)
		(fill yes
			(thermal_gap 0.5)
			(thermal_bridge_width 0.5)
			(island_removal_mode 0)
		)
		(polygon
			(pts
				(arc
					(start 107.90301 -343.986104)
					(mid 106.12501 -343.986104)
					(end 107.90301 -343.986104)
				)
			)
		)
	)
	(zone
		(layers "In1.Cu" "In3.Cu" "In5.Cu" "In7.Cu" "In8.Cu" "In9.Cu" "In10.Cu"
			"In12.Cu" "In14.Cu" "In16.Cu"
		)
		(hatch none 0.5)
		(connect_pads
			(clearance 0)
		)
		(min_thickness 0.25)
		(keepout
			(tracks not_allowed)
			(vias allowed)
			(pads allowed)
			(copperpour not_allowed)
			(footprints allowed)
		)
		(placement
			(enabled no)
			(sheetname "")
		)
		(fill yes
			(thermal_gap 0.5)
			(thermal_bridge_width 0.5)
			(island_removal_mode 0)
		)
		(polygon
			(pts
				(arc
					(start 328.272394 -336.976466)
					(mid 326.512174 -336.976466)
					(end 328.272394 -336.976466)
				)
			)
		)
	)
	(zone
		(layers "In1.Cu" "In3.Cu" "In5.Cu" "In7.Cu" "In8.Cu" "In9.Cu" "In10.Cu"
			"In12.Cu" "In14.Cu" "In16.Cu"
		)
		(hatch none 0.5)
		(connect_pads
			(clearance 0)
		)
		(min_thickness 0.25)
		(keepout
			(tracks not_allowed)
			(vias allowed)
			(pads allowed)
			(copperpour not_allowed)
			(footprints allowed)
		)
		(placement
			(enabled no)
			(sheetname "")
		)
		(fill yes
			(thermal_gap 0.5)
			(thermal_bridge_width 0.5)
			(island_removal_mode 0)
		)
		(polygon
			(pts
				(arc
					(start 87.92845 -163.447476)
					(mid 86.15045 -163.447476)
					(end 87.92845 -163.447476)
				)
			)
		)
	)
	(zone
		(layers "In1.Cu" "In3.Cu" "In5.Cu" "In7.Cu" "In8.Cu" "In9.Cu" "In10.Cu"
			"In12.Cu" "In14.Cu" "In16.Cu"
		)
		(hatch none 0.5)
		(connect_pads
			(clearance 0)
		)
		(min_thickness 0.25)
		(keepout
			(tracks not_allowed)
			(vias allowed)
			(pads allowed)
			(copperpour not_allowed)
			(footprints allowed)
		)
		(placement
			(enabled no)
			(sheetname "")
		)
		(fill yes
			(thermal_gap 0.5)
			(thermal_bridge_width 0.5)
			(island_removal_mode 0)
		)
		(polygon
			(pts
				(arc
					(start 92.269056 -345.261184)
					(mid 90.491056 -345.261184)
					(end 92.269056 -345.261184)
				)
			)
		)
	)
	(zone
		(layers "In1.Cu" "In3.Cu" "In5.Cu" "In7.Cu" "In8.Cu" "In9.Cu" "In10.Cu"
			"In12.Cu" "In14.Cu" "In16.Cu"
		)
		(hatch none 0.5)
		(connect_pads
			(clearance 0)
		)
		(min_thickness 0.25)
		(keepout
			(tracks not_allowed)
			(vias allowed)
			(pads allowed)
			(copperpour not_allowed)
			(footprints allowed)
		)
		(placement
			(enabled no)
			(sheetname "")
		)
		(fill yes
			(thermal_gap 0.5)
			(thermal_bridge_width 0.5)
			(island_removal_mode 0)
		)
		(polygon
			(pts
				(arc
					(start 304.406046 -349.137732)
					(mid 302.628046 -349.137732)
					(end 304.406046 -349.137732)
				)
			)
		)
	)
	(zone
		(layers "In1.Cu" "In3.Cu" "In5.Cu" "In7.Cu" "In8.Cu" "In9.Cu" "In10.Cu"
			"In12.Cu" "In14.Cu" "In16.Cu"
		)
		(hatch none 0.5)
		(connect_pads
			(clearance 0)
		)
		(min_thickness 0.25)
		(keepout
			(tracks not_allowed)
			(vias allowed)
			(pads allowed)
			(copperpour not_allowed)
			(footprints allowed)
		)
		(placement
			(enabled no)
			(sheetname "")
		)
		(fill yes
			(thermal_gap 0.5)
			(thermal_bridge_width 0.5)
			(island_removal_mode 0)
		)
		(polygon
			(pts
				(arc
					(start 363.160056 -177.254916)
					(mid 361.382056 -177.254916)
					(end 363.160056 -177.254916)
				)
			)
		)
	)
	(zone
		(layers "In1.Cu" "In3.Cu" "In5.Cu" "In7.Cu" "In8.Cu" "In9.Cu" "In10.Cu"
			"In12.Cu" "In14.Cu" "In16.Cu"
		)
		(hatch none 0.5)
		(connect_pads
			(clearance 0)
		)
		(min_thickness 0.25)
		(keepout
			(tracks not_allowed)
			(vias allowed)
			(pads allowed)
			(copperpour not_allowed)
			(footprints allowed)
		)
		(placement
			(enabled no)
			(sheetname "")
		)
		(fill yes
			(thermal_gap 0.5)
			(thermal_bridge_width 0.5)
			(island_removal_mode 0)
		)
		(polygon
			(pts
				(arc
					(start 78.400402 -352.269806)
					(mid 76.622402 -352.269806)
					(end 78.400402 -352.269806)
				)
			)
		)
	)
	(zone
		(layers "In1.Cu" "In3.Cu" "In5.Cu" "In7.Cu" "In8.Cu" "In9.Cu" "In10.Cu"
			"In12.Cu" "In14.Cu" "In16.Cu"
		)
		(hatch none 0.5)
		(connect_pads
			(clearance 0)
		)
		(min_thickness 0.25)
		(keepout
			(tracks not_allowed)
			(vias allowed)
			(pads allowed)
			(copperpour not_allowed)
			(footprints allowed)
		)
		(placement
			(enabled no)
			(sheetname "")
		)
		(fill yes
			(thermal_gap 0.5)
			(thermal_bridge_width 0.5)
			(island_removal_mode 0)
		)
		(polygon
			(pts
				(arc
					(start 338.575396 -338.571078)
					(mid 336.797396 -338.571078)
					(end 338.575396 -338.571078)
				)
			)
		)
	)
	(zone
		(layers "In1.Cu" "In3.Cu" "In5.Cu" "In7.Cu" "In8.Cu" "In9.Cu" "In10.Cu"
			"In12.Cu" "In14.Cu" "In16.Cu"
		)
		(hatch none 0.5)
		(connect_pads
			(clearance 0)
		)
		(min_thickness 0.25)
		(keepout
			(tracks not_allowed)
			(vias allowed)
			(pads allowed)
			(copperpour not_allowed)
			(footprints allowed)
		)
		(placement
			(enabled no)
			(sheetname "")
		)
		(fill yes
			(thermal_gap 0.5)
			(thermal_bridge_width 0.5)
			(island_removal_mode 0)
		)
		(polygon
			(pts
				(arc
					(start 342.152224 -351.453196)
					(mid 340.374224 -351.453196)
					(end 342.152224 -351.453196)
				)
			)
		)
	)
	(zone
		(layers "In1.Cu" "In3.Cu" "In5.Cu" "In7.Cu" "In8.Cu" "In9.Cu" "In10.Cu"
			"In12.Cu" "In14.Cu" "In16.Cu"
		)
		(hatch none 0.5)
		(connect_pads
			(clearance 0)
		)
		(min_thickness 0.25)
		(keepout
			(tracks not_allowed)
			(vias allowed)
			(pads allowed)
			(copperpour not_allowed)
			(footprints allowed)
		)
		(placement
			(enabled no)
			(sheetname "")
		)
		(fill yes
			(thermal_gap 0.5)
			(thermal_bridge_width 0.5)
			(island_removal_mode 0)
		)
		(polygon
			(pts
				(arc
					(start 117.147594 -152.022556)
					(mid 115.369594 -152.022556)
					(end 117.147594 -152.022556)
				)
			)
		)
	)
	(zone
		(layers "In1.Cu" "In3.Cu" "In5.Cu" "In7.Cu" "In8.Cu" "In9.Cu" "In10.Cu"
			"In12.Cu" "In14.Cu" "In16.Cu"
		)
		(hatch none 0.5)
		(connect_pads
			(clearance 0)
		)
		(min_thickness 0.25)
		(keepout
			(tracks not_allowed)
			(vias allowed)
			(pads allowed)
			(copperpour not_allowed)
			(footprints allowed)
		)
		(placement
			(enabled no)
			(sheetname "")
		)
		(fill yes
			(thermal_gap 0.5)
			(thermal_bridge_width 0.5)
			(island_removal_mode 0)
		)
		(polygon
			(pts
				(arc
					(start 99.088194 -339.358224)
					(mid 97.310194 -339.358224)
					(end 99.088194 -339.358224)
				)
			)
		)
	)
	(zone
		(layers "In1.Cu" "In3.Cu" "In5.Cu" "In7.Cu" "In8.Cu" "In9.Cu" "In10.Cu"
			"In12.Cu" "In14.Cu" "In16.Cu"
		)
		(hatch none 0.5)
		(connect_pads
			(clearance 0)
		)
		(min_thickness 0.25)
		(keepout
			(tracks not_allowed)
			(vias allowed)
			(pads allowed)
			(copperpour not_allowed)
			(footprints allowed)
		)
		(placement
			(enabled no)
			(sheetname "")
		)
		(fill yes
			(thermal_gap 0.5)
			(thermal_bridge_width 0.5)
			(island_removal_mode 0)
		)
		(polygon
			(pts
				(arc
					(start 347.45676 -338.969858)
					(mid 345.67876 -338.969858)
					(end 347.45676 -338.969858)
				)
			)
		)
	)
	(zone
		(layers "In1.Cu" "In3.Cu" "In5.Cu" "In7.Cu" "In8.Cu" "In9.Cu" "In10.Cu"
			"In12.Cu" "In14.Cu" "In16.Cu"
		)
		(hatch none 0.5)
		(connect_pads
			(clearance 0)
		)
		(min_thickness 0.25)
		(keepout
			(tracks not_allowed)
			(vias allowed)
			(pads allowed)
			(copperpour not_allowed)
			(footprints allowed)
		)
		(placement
			(enabled no)
			(sheetname "")
		)
		(fill yes
			(thermal_gap 0.5)
			(thermal_bridge_width 0.5)
			(island_removal_mode 0)
		)
		(polygon
			(pts
				(arc
					(start 436.358538 -360.734102)
					(mid 434.580538 -360.734102)
					(end 436.358538 -360.734102)
				)
			)
		)
	)
	(zone
		(layers "In1.Cu" "In3.Cu" "In5.Cu" "In7.Cu" "In8.Cu" "In9.Cu" "In10.Cu"
			"In12.Cu" "In14.Cu" "In16.Cu"
		)
		(hatch none 0.5)
		(connect_pads
			(clearance 0)
		)
		(min_thickness 0.25)
		(keepout
			(tracks not_allowed)
			(vias allowed)
			(pads allowed)
			(copperpour not_allowed)
			(footprints allowed)
		)
		(placement
			(enabled no)
			(sheetname "")
		)
		(fill yes
			(thermal_gap 0.5)
			(thermal_bridge_width 0.5)
			(island_removal_mode 0)
		)
		(polygon
			(pts
				(arc
					(start 293.579296 -348.704662)
					(mid 291.819076 -348.704662)
					(end 293.579296 -348.704662)
				)
			)
		)
	)
	(zone
		(layers "In1.Cu" "In3.Cu" "In5.Cu" "In7.Cu" "In8.Cu" "In9.Cu" "In10.Cu"
			"In12.Cu" "In14.Cu" "In16.Cu"
		)
		(hatch none 0.5)
		(connect_pads
			(clearance 0)
		)
		(min_thickness 0.25)
		(keepout
			(tracks not_allowed)
			(vias allowed)
			(pads allowed)
			(copperpour not_allowed)
			(footprints allowed)
		)
		(placement
			(enabled no)
			(sheetname "")
		)
		(fill yes
			(thermal_gap 0.5)
			(thermal_bridge_width 0.5)
			(island_removal_mode 0)
		)
		(polygon
			(pts
				(arc
					(start 379.924056 -181.494176)
					(mid 378.146056 -181.494176)
					(end 379.924056 -181.494176)
				)
			)
		)
	)
	(zone
		(layers "In1.Cu" "In3.Cu" "In5.Cu" "In7.Cu" "In8.Cu" "In9.Cu" "In10.Cu"
			"In12.Cu" "In14.Cu" "In16.Cu"
		)
		(hatch none 0.5)
		(connect_pads
			(clearance 0)
		)
		(min_thickness 0.25)
		(keepout
			(tracks not_allowed)
			(vias allowed)
			(pads allowed)
			(copperpour not_allowed)
			(footprints allowed)
		)
		(placement
			(enabled no)
			(sheetname "")
		)
		(fill yes
			(thermal_gap 0.5)
			(thermal_bridge_width 0.5)
			(island_removal_mode 0)
		)
		(polygon
			(pts
				(arc
					(start 97.024444 -337.017614)
					(mid 95.264224 -337.017614)
					(end 97.024444 -337.017614)
				)
			)
		)
	)
	(zone
		(layers "In1.Cu" "In3.Cu" "In5.Cu" "In7.Cu" "In8.Cu" "In9.Cu" "In10.Cu"
			"In12.Cu" "In14.Cu" "In16.Cu"
		)
		(hatch none 0.5)
		(connect_pads
			(clearance 0)
		)
		(min_thickness 0.25)
		(keepout
			(tracks not_allowed)
			(vias allowed)
			(pads allowed)
			(copperpour not_allowed)
			(footprints allowed)
		)
		(placement
			(enabled no)
			(sheetname "")
		)
		(fill yes
			(thermal_gap 0.5)
			(thermal_bridge_width 0.5)
			(island_removal_mode 0)
		)
		(polygon
			(pts
				(arc
					(start 311.756806 -348.002352)
					(mid 309.978806 -348.002352)
					(end 311.756806 -348.002352)
				)
			)
		)
	)
	(zone
		(layers "In1.Cu" "In3.Cu" "In5.Cu" "In7.Cu" "In8.Cu" "In9.Cu" "In10.Cu"
			"In12.Cu" "In14.Cu" "In16.Cu"
		)
		(hatch none 0.5)
		(connect_pads
			(clearance 0)
		)
		(min_thickness 0.25)
		(keepout
			(tracks not_allowed)
			(vias allowed)
			(pads allowed)
			(copperpour not_allowed)
			(footprints allowed)
		)
		(placement
			(enabled no)
			(sheetname "")
		)
		(fill yes
			(thermal_gap 0.5)
			(thermal_bridge_width 0.5)
			(island_removal_mode 0)
		)
		(polygon
			(pts
				(arc
					(start 49.65573 -356.822502)
					(mid 47.87773 -356.822502)
					(end 49.65573 -356.822502)
				)
			)
		)
	)
	(zone
		(layers "In1.Cu" "In3.Cu" "In5.Cu" "In7.Cu" "In8.Cu" "In9.Cu" "In10.Cu"
			"In12.Cu" "In14.Cu" "In16.Cu"
		)
		(hatch none 0.5)
		(connect_pads
			(clearance 0)
		)
		(min_thickness 0.25)
		(keepout
			(tracks not_allowed)
			(vias allowed)
			(pads allowed)
			(copperpour not_allowed)
			(footprints allowed)
		)
		(placement
			(enabled no)
			(sheetname "")
		)
		(fill yes
			(thermal_gap 0.5)
			(thermal_bridge_width 0.5)
			(island_removal_mode 0)
		)
		(polygon
			(pts
				(arc
					(start 353.237038 -341.922862)
					(mid 351.476818 -341.922862)
					(end 353.237038 -341.922862)
				)
			)
		)
	)
	(zone
		(layers "In1.Cu" "In3.Cu" "In5.Cu" "In7.Cu" "In8.Cu" "In9.Cu" "In10.Cu"
			"In12.Cu" "In14.Cu" "In16.Cu"
		)
		(hatch none 0.5)
		(connect_pads
			(clearance 0)
		)
		(min_thickness 0.25)
		(keepout
			(tracks not_allowed)
			(vias allowed)
			(pads allowed)
			(copperpour not_allowed)
			(footprints allowed)
		)
		(placement
			(enabled no)
			(sheetname "")
		)
		(fill yes
			(thermal_gap 0.5)
			(thermal_bridge_width 0.5)
			(island_removal_mode 0)
		)
		(polygon
			(pts
				(arc
					(start 341.556848 -353.010216)
					(mid 339.778848 -353.010216)
					(end 341.556848 -353.010216)
				)
			)
		)
	)
	(zone
		(layers "In1.Cu" "In3.Cu" "In5.Cu" "In7.Cu" "In8.Cu" "In9.Cu" "In10.Cu"
			"In12.Cu" "In14.Cu" "In16.Cu"
		)
		(hatch none 0.5)
		(connect_pads
			(clearance 0)
		)
		(min_thickness 0.25)
		(keepout
			(tracks not_allowed)
			(vias allowed)
			(pads allowed)
			(copperpour not_allowed)
			(footprints allowed)
		)
		(placement
			(enabled no)
			(sheetname "")
		)
		(fill yes
			(thermal_gap 0.5)
			(thermal_bridge_width 0.5)
			(island_removal_mode 0)
		)
		(polygon
			(pts
				(arc
					(start 62.82563 -165.38956)
					(mid 61.04763 -165.38956)
					(end 62.82563 -165.38956)
				)
			)
		)
	)
	(zone
		(layers "In1.Cu" "In3.Cu" "In5.Cu" "In7.Cu" "In8.Cu" "In9.Cu" "In10.Cu"
			"In12.Cu" "In14.Cu" "In16.Cu"
		)
		(hatch none 0.5)
		(connect_pads
			(clearance 0)
		)
		(min_thickness 0.25)
		(keepout
			(tracks not_allowed)
			(vias allowed)
			(pads allowed)
			(copperpour not_allowed)
			(footprints allowed)
		)
		(placement
			(enabled no)
			(sheetname "")
		)
		(fill yes
			(thermal_gap 0.5)
			(thermal_bridge_width 0.5)
			(island_removal_mode 0)
		)
		(polygon
			(pts
				(arc
					(start 42.306494 -357.898192)
					(mid 40.528494 -357.898192)
					(end 42.306494 -357.898192)
				)
			)
		)
	)
	(zone
		(layers "In1.Cu" "In3.Cu" "In5.Cu" "In7.Cu" "In8.Cu" "In9.Cu" "In10.Cu"
			"In12.Cu" "In14.Cu" "In16.Cu"
		)
		(hatch none 0.5)
		(connect_pads
			(clearance 0)
		)
		(min_thickness 0.25)
		(keepout
			(tracks not_allowed)
			(vias allowed)
			(pads allowed)
			(copperpour not_allowed)
			(footprints allowed)
		)
		(placement
			(enabled no)
			(sheetname "")
		)
		(fill yes
			(thermal_gap 0.5)
			(thermal_bridge_width 0.5)
			(island_removal_mode 0)
		)
		(polygon
			(pts
				(arc
					(start 42.316146 -359.2576)
					(mid 40.538146 -359.2576)
					(end 42.316146 -359.2576)
				)
			)
		)
	)
	(zone
		(layers "In1.Cu" "In3.Cu" "In5.Cu" "In7.Cu" "In8.Cu" "In9.Cu" "In10.Cu"
			"In12.Cu" "In14.Cu" "In16.Cu"
		)
		(hatch none 0.5)
		(connect_pads
			(clearance 0)
		)
		(min_thickness 0.25)
		(keepout
			(tracks not_allowed)
			(vias allowed)
			(pads allowed)
			(copperpour not_allowed)
			(footprints allowed)
		)
		(placement
			(enabled no)
			(sheetname "")
		)
		(fill yes
			(thermal_gap 0.5)
			(thermal_bridge_width 0.5)
			(island_removal_mode 0)
		)
		(polygon
			(pts
				(arc
					(start 79.74203 -178.036474)
					(mid 77.96403 -178.036474)
					(end 79.74203 -178.036474)
				)
			)
		)
	)
	(zone
		(layers "In1.Cu" "In3.Cu" "In5.Cu" "In7.Cu" "In8.Cu" "In9.Cu" "In10.Cu"
			"In12.Cu" "In14.Cu" "In16.Cu"
		)
		(hatch none 0.5)
		(connect_pads
			(clearance 0)
		)
		(min_thickness 0.25)
		(keepout
			(tracks not_allowed)
			(vias allowed)
			(pads allowed)
			(copperpour not_allowed)
			(footprints allowed)
		)
		(placement
			(enabled no)
			(sheetname "")
		)
		(fill yes
			(thermal_gap 0.5)
			(thermal_bridge_width 0.5)
			(island_removal_mode 0)
		)
		(polygon
			(pts
				(arc
					(start 388.817358 -154.428952)
					(mid 387.039358 -154.428952)
					(end 388.817358 -154.428952)
				)
			)
		)
	)
	(zone
		(layers "In1.Cu" "In3.Cu" "In5.Cu" "In7.Cu" "In8.Cu" "In9.Cu" "In10.Cu"
			"In12.Cu" "In14.Cu" "In16.Cu"
		)
		(hatch none 0.5)
		(connect_pads
			(clearance 0)
		)
		(min_thickness 0.25)
		(keepout
			(tracks not_allowed)
			(vias allowed)
			(pads allowed)
			(copperpour not_allowed)
			(footprints allowed)
		)
		(placement
			(enabled no)
			(sheetname "")
		)
		(fill yes
			(thermal_gap 0.5)
			(thermal_bridge_width 0.5)
			(island_removal_mode 0)
		)
		(polygon
			(pts
				(arc
					(start 85.734652 -348.861126)
					(mid 83.956652 -348.861126)
					(end 85.734652 -348.861126)
				)
			)
		)
	)
	(zone
		(layers "In1.Cu" "In3.Cu" "In5.Cu" "In7.Cu" "In8.Cu" "In9.Cu" "In10.Cu"
			"In12.Cu" "In14.Cu" "In16.Cu"
		)
		(hatch none 0.5)
		(connect_pads
			(clearance 0)
		)
		(min_thickness 0.25)
		(keepout
			(tracks not_allowed)
			(vias allowed)
			(pads allowed)
			(copperpour not_allowed)
			(footprints allowed)
		)
		(placement
			(enabled no)
			(sheetname "")
		)
		(fill yes
			(thermal_gap 0.5)
			(thermal_bridge_width 0.5)
			(island_removal_mode 0)
		)
		(polygon
			(pts
				(arc
					(start 83.364578 -337.795362)
					(mid 81.586578 -337.795362)
					(end 83.364578 -337.795362)
				)
			)
		)
	)
	(zone
		(layers "In1.Cu" "In3.Cu" "In5.Cu" "In7.Cu" "In8.Cu" "In9.Cu" "In10.Cu"
			"In12.Cu" "In14.Cu" "In16.Cu"
		)
		(hatch none 0.5)
		(connect_pads
			(clearance 0)
		)
		(min_thickness 0.25)
		(keepout
			(tracks not_allowed)
			(vias allowed)
			(pads allowed)
			(copperpour not_allowed)
			(footprints allowed)
		)
		(placement
			(enabled no)
			(sheetname "")
		)
		(fill yes
			(thermal_gap 0.5)
			(thermal_bridge_width 0.5)
			(island_removal_mode 0)
		)
		(polygon
			(pts
				(arc
					(start 97.335594 -179.832254)
					(mid 95.557594 -179.832254)
					(end 97.335594 -179.832254)
				)
			)
		)
	)
	(zone
		(layers "In1.Cu" "In3.Cu" "In5.Cu" "In7.Cu" "In8.Cu" "In9.Cu" "In10.Cu"
			"In12.Cu" "In14.Cu" "In16.Cu"
		)
		(hatch none 0.5)
		(connect_pads
			(clearance 0)
		)
		(min_thickness 0.25)
		(keepout
			(tracks not_allowed)
			(vias allowed)
			(pads allowed)
			(copperpour not_allowed)
			(footprints allowed)
		)
		(placement
			(enabled no)
			(sheetname "")
		)
		(fill yes
			(thermal_gap 0.5)
			(thermal_bridge_width 0.5)
			(island_removal_mode 0)
		)
		(polygon
			(pts
				(arc
					(start 44.872656 -357.224838)
					(mid 43.094656 -357.224838)
					(end 44.872656 -357.224838)
				)
			)
		)
	)
	(zone
		(layers "In1.Cu" "In3.Cu" "In5.Cu" "In7.Cu" "In8.Cu" "In9.Cu" "In10.Cu"
			"In12.Cu" "In14.Cu" "In16.Cu"
		)
		(hatch none 0.5)
		(connect_pads
			(clearance 0)
		)
		(min_thickness 0.25)
		(keepout
			(tracks not_allowed)
			(vias allowed)
			(pads allowed)
			(copperpour not_allowed)
			(footprints allowed)
		)
		(placement
			(enabled no)
			(sheetname "")
		)
		(fill yes
			(thermal_gap 0.5)
			(thermal_bridge_width 0.5)
			(island_removal_mode 0)
		)
		(polygon
			(pts
				(arc
					(start 380.649988 -180.755544)
					(mid 378.889768 -180.755544)
					(end 380.649988 -180.755544)
				)
			)
		)
	)
	(zone
		(layers "In1.Cu" "In3.Cu" "In5.Cu" "In7.Cu" "In8.Cu" "In9.Cu" "In10.Cu"
			"In12.Cu" "In14.Cu" "In16.Cu"
		)
		(hatch none 0.5)
		(connect_pads
			(clearance 0)
		)
		(min_thickness 0.25)
		(keepout
			(tracks not_allowed)
			(vias allowed)
			(pads allowed)
			(copperpour not_allowed)
			(footprints allowed)
		)
		(placement
			(enabled no)
			(sheetname "")
		)
		(fill yes
			(thermal_gap 0.5)
			(thermal_bridge_width 0.5)
			(island_removal_mode 0)
		)
		(polygon
			(pts
				(arc
					(start 347.917008 -159.151066)
					(mid 346.156788 -159.151066)
					(end 347.917008 -159.151066)
				)
			)
		)
	)
	(zone
		(layers "In1.Cu" "In3.Cu" "In5.Cu" "In7.Cu" "In8.Cu" "In9.Cu" "In10.Cu"
			"In12.Cu" "In14.Cu" "In16.Cu"
		)
		(hatch none 0.5)
		(connect_pads
			(clearance 0)
		)
		(min_thickness 0.25)
		(keepout
			(tracks not_allowed)
			(vias allowed)
			(pads allowed)
			(copperpour not_allowed)
			(footprints allowed)
		)
		(placement
			(enabled no)
			(sheetname "")
		)
		(fill yes
			(thermal_gap 0.5)
			(thermal_bridge_width 0.5)
			(island_removal_mode 0)
		)
		(polygon
			(pts
				(arc
					(start 177.857912 -20.714208)
					(mid 176.079912 -20.714208)
					(end 177.857912 -20.714208)
				)
			)
		)
	)
	(zone
		(layers "In1.Cu" "In3.Cu" "In5.Cu" "In7.Cu" "In8.Cu" "In9.Cu" "In10.Cu"
			"In12.Cu" "In14.Cu" "In16.Cu"
		)
		(hatch none 0.5)
		(connect_pads
			(clearance 0)
		)
		(min_thickness 0.25)
		(keepout
			(tracks not_allowed)
			(vias allowed)
			(pads allowed)
			(copperpour not_allowed)
			(footprints allowed)
		)
		(placement
			(enabled no)
			(sheetname "")
		)
		(fill yes
			(thermal_gap 0.5)
			(thermal_bridge_width 0.5)
			(island_removal_mode 0)
		)
		(polygon
			(pts
				(arc
					(start 395.561058 -174.749714)
					(mid 393.783058 -174.749714)
					(end 395.561058 -174.749714)
				)
			)
		)
	)
	(zone
		(layers "In1.Cu" "In3.Cu" "In5.Cu" "In7.Cu" "In8.Cu" "In9.Cu" "In10.Cu"
			"In12.Cu" "In14.Cu" "In16.Cu"
		)
		(hatch none 0.5)
		(connect_pads
			(clearance 0)
		)
		(min_thickness 0.25)
		(keepout
			(tracks not_allowed)
			(vias allowed)
			(pads allowed)
			(copperpour not_allowed)
			(footprints allowed)
		)
		(placement
			(enabled no)
			(sheetname "")
		)
		(fill yes
			(thermal_gap 0.5)
			(thermal_bridge_width 0.5)
			(island_removal_mode 0)
		)
		(polygon
			(pts
				(arc
					(start 354.788724 -340.49081)
					(mid 353.010724 -340.49081)
					(end 354.788724 -340.49081)
				)
			)
		)
	)
	(zone
		(layers "In1.Cu" "In3.Cu" "In5.Cu" "In7.Cu" "In8.Cu" "In9.Cu" "In10.Cu"
			"In12.Cu" "In14.Cu" "In16.Cu"
		)
		(hatch none 0.5)
		(connect_pads
			(clearance 0)
		)
		(min_thickness 0.25)
		(keepout
			(tracks not_allowed)
			(vias allowed)
			(pads allowed)
			(copperpour not_allowed)
			(footprints allowed)
		)
		(placement
			(enabled no)
			(sheetname "")
		)
		(fill yes
			(thermal_gap 0.5)
			(thermal_bridge_width 0.5)
			(island_removal_mode 0)
		)
		(polygon
			(pts
				(arc
					(start 74.475594 -338.183474)
					(mid 72.697594 -338.183474)
					(end 74.475594 -338.183474)
				)
			)
		)
	)
	(zone
		(layers "In1.Cu" "In3.Cu" "In5.Cu" "In7.Cu" "In8.Cu" "In9.Cu" "In10.Cu"
			"In12.Cu" "In14.Cu" "In16.Cu"
		)
		(hatch none 0.5)
		(connect_pads
			(clearance 0)
		)
		(min_thickness 0.25)
		(keepout
			(tracks not_allowed)
			(vias allowed)
			(pads allowed)
			(copperpour not_allowed)
			(footprints allowed)
		)
		(placement
			(enabled no)
			(sheetname "")
		)
		(fill yes
			(thermal_gap 0.5)
			(thermal_bridge_width 0.5)
			(island_removal_mode 0)
		)
		(polygon
			(pts
				(arc
					(start 331.301344 -337.053936)
					(mid 329.523344 -337.053936)
					(end 331.301344 -337.053936)
				)
			)
		)
	)
	(zone
		(layers "In1.Cu" "In3.Cu" "In5.Cu" "In7.Cu" "In8.Cu" "In9.Cu" "In10.Cu"
			"In12.Cu" "In14.Cu" "In16.Cu"
		)
		(hatch none 0.5)
		(connect_pads
			(clearance 0)
		)
		(min_thickness 0.25)
		(keepout
			(tracks not_allowed)
			(vias allowed)
			(pads allowed)
			(copperpour not_allowed)
			(footprints allowed)
		)
		(placement
			(enabled no)
			(sheetname "")
		)
		(fill yes
			(thermal_gap 0.5)
			(thermal_bridge_width 0.5)
			(island_removal_mode 0)
		)
		(polygon
			(pts
				(arc
					(start 78.73238 -16.55064)
					(mid 76.95438 -16.55064)
					(end 78.73238 -16.55064)
				)
			)
		)
	)
	(zone
		(layers "In1.Cu" "In3.Cu" "In5.Cu" "In7.Cu" "In8.Cu" "In9.Cu" "In10.Cu"
			"In12.Cu" "In14.Cu" "In16.Cu"
		)
		(hatch none 0.5)
		(connect_pads
			(clearance 0)
		)
		(min_thickness 0.25)
		(keepout
			(tracks not_allowed)
			(vias allowed)
			(pads allowed)
			(copperpour not_allowed)
			(footprints allowed)
		)
		(placement
			(enabled no)
			(sheetname "")
		)
		(fill yes
			(thermal_gap 0.5)
			(thermal_bridge_width 0.5)
			(island_removal_mode 0)
		)
		(polygon
			(pts
				(arc
					(start 107.6452 -176.183544)
					(mid 105.88498 -176.183544)
					(end 107.6452 -176.183544)
				)
			)
		)
	)
	(zone
		(layers "In1.Cu" "In3.Cu" "In5.Cu" "In7.Cu" "In8.Cu" "In9.Cu" "In10.Cu"
			"In12.Cu" "In14.Cu" "In16.Cu"
		)
		(hatch none 0.5)
		(connect_pads
			(clearance 0)
		)
		(min_thickness 0.25)
		(keepout
			(tracks not_allowed)
			(vias allowed)
			(pads allowed)
			(copperpour not_allowed)
			(footprints allowed)
		)
		(placement
			(enabled no)
			(sheetname "")
		)
		(fill yes
			(thermal_gap 0.5)
			(thermal_bridge_width 0.5)
			(island_removal_mode 0)
		)
		(polygon
			(pts
				(arc
					(start 378.789438 -179.560474)
					(mid 377.011438 -179.560474)
					(end 378.789438 -179.560474)
				)
			)
		)
	)
	(zone
		(layers "In1.Cu" "In3.Cu" "In5.Cu" "In7.Cu" "In8.Cu" "In9.Cu" "In10.Cu"
			"In12.Cu" "In14.Cu" "In16.Cu"
		)
		(hatch none 0.5)
		(connect_pads
			(clearance 0)
		)
		(min_thickness 0.25)
		(keepout
			(tracks not_allowed)
			(vias allowed)
			(pads allowed)
			(copperpour not_allowed)
			(footprints allowed)
		)
		(placement
			(enabled no)
			(sheetname "")
		)
		(fill yes
			(thermal_gap 0.5)
			(thermal_bridge_width 0.5)
			(island_removal_mode 0)
		)
		(polygon
			(pts
				(arc
					(start 46.757844 -348.709488)
					(mid 44.997624 -348.709488)
					(end 46.757844 -348.709488)
				)
			)
		)
	)
	(zone
		(layers "In1.Cu" "In3.Cu" "In5.Cu" "In7.Cu" "In8.Cu" "In9.Cu" "In10.Cu"
			"In12.Cu" "In14.Cu" "In16.Cu"
		)
		(hatch none 0.5)
		(connect_pads
			(clearance 0)
		)
		(min_thickness 0.25)
		(keepout
			(tracks not_allowed)
			(vias allowed)
			(pads allowed)
			(copperpour not_allowed)
			(footprints allowed)
		)
		(placement
			(enabled no)
			(sheetname "")
		)
		(fill yes
			(thermal_gap 0.5)
			(thermal_bridge_width 0.5)
			(island_removal_mode 0)
		)
		(polygon
			(pts
				(arc
					(start 346.573856 -159.896556)
					(mid 344.795856 -159.896556)
					(end 346.573856 -159.896556)
				)
			)
		)
	)
	(zone
		(layers "In1.Cu" "In3.Cu" "In5.Cu" "In7.Cu" "In8.Cu" "In9.Cu" "In10.Cu"
			"In12.Cu" "In14.Cu" "In16.Cu"
		)
		(hatch none 0.5)
		(connect_pads
			(clearance 0)
		)
		(min_thickness 0.25)
		(keepout
			(tracks not_allowed)
			(vias allowed)
			(pads allowed)
			(copperpour not_allowed)
			(footprints allowed)
		)
		(placement
			(enabled no)
			(sheetname "")
		)
		(fill yes
			(thermal_gap 0.5)
			(thermal_bridge_width 0.5)
			(island_removal_mode 0)
		)
		(polygon
			(pts
				(arc
					(start 279.488646 -349.899732)
					(mid 277.710646 -349.899732)
					(end 279.488646 -349.899732)
				)
			)
		)
	)
	(zone
		(layers "In1.Cu" "In3.Cu" "In5.Cu" "In7.Cu" "In8.Cu" "In9.Cu" "In10.Cu"
			"In12.Cu" "In14.Cu" "In16.Cu"
		)
		(hatch none 0.5)
		(connect_pads
			(clearance 0)
		)
		(min_thickness 0.25)
		(keepout
			(tracks not_allowed)
			(vias allowed)
			(pads allowed)
			(copperpour not_allowed)
			(footprints allowed)
		)
		(placement
			(enabled no)
			(sheetname "")
		)
		(fill yes
			(thermal_gap 0.5)
			(thermal_bridge_width 0.5)
			(island_removal_mode 0)
		)
		(polygon
			(pts
				(arc
					(start 386.587238 -179.941474)
					(mid 384.809238 -179.941474)
					(end 386.587238 -179.941474)
				)
			)
		)
	)
	(zone
		(layers "In1.Cu" "In3.Cu" "In5.Cu" "In7.Cu" "In8.Cu" "In9.Cu" "In10.Cu"
			"In12.Cu" "In14.Cu" "In16.Cu"
		)
		(hatch none 0.5)
		(connect_pads
			(clearance 0)
		)
		(min_thickness 0.25)
		(keepout
			(tracks not_allowed)
			(vias allowed)
			(pads allowed)
			(copperpour not_allowed)
			(footprints allowed)
		)
		(placement
			(enabled no)
			(sheetname "")
		)
		(fill yes
			(thermal_gap 0.5)
			(thermal_bridge_width 0.5)
			(island_removal_mode 0)
		)
		(polygon
			(pts
				(arc
					(start 436.570628 -354.67925)
					(mid 434.792628 -354.67925)
					(end 436.570628 -354.67925)
				)
			)
		)
	)
	(zone
		(layers "In1.Cu" "In3.Cu" "In5.Cu" "In7.Cu" "In8.Cu" "In9.Cu" "In10.Cu"
			"In12.Cu" "In14.Cu" "In16.Cu"
		)
		(hatch none 0.5)
		(connect_pads
			(clearance 0)
		)
		(min_thickness 0.25)
		(keepout
			(tracks not_allowed)
			(vias allowed)
			(pads allowed)
			(copperpour not_allowed)
			(footprints allowed)
		)
		(placement
			(enabled no)
			(sheetname "")
		)
		(fill yes
			(thermal_gap 0.5)
			(thermal_bridge_width 0.5)
			(island_removal_mode 0)
		)
		(polygon
			(pts
				(arc
					(start 321.862196 -337.856068)
					(mid 320.084196 -337.856068)
					(end 321.862196 -337.856068)
				)
			)
		)
	)
	(zone
		(layers "In1.Cu" "In3.Cu" "In5.Cu" "In7.Cu" "In8.Cu" "In9.Cu" "In10.Cu"
			"In12.Cu" "In14.Cu" "In16.Cu"
		)
		(hatch none 0.5)
		(connect_pads
			(clearance 0)
		)
		(min_thickness 0.25)
		(keepout
			(tracks not_allowed)
			(vias allowed)
			(pads allowed)
			(copperpour not_allowed)
			(footprints allowed)
		)
		(placement
			(enabled no)
			(sheetname "")
		)
		(fill yes
			(thermal_gap 0.5)
			(thermal_bridge_width 0.5)
			(island_removal_mode 0)
		)
		(polygon
			(pts
				(arc
					(start 122.761248 -163.89096)
					(mid 120.983248 -163.89096)
					(end 122.761248 -163.89096)
				)
			)
		)
	)
	(zone
		(layers "In1.Cu" "In3.Cu" "In5.Cu" "In7.Cu" "In8.Cu" "In9.Cu" "In10.Cu"
			"In12.Cu" "In14.Cu" "In16.Cu"
		)
		(hatch none 0.5)
		(connect_pads
			(clearance 0)
		)
		(min_thickness 0.25)
		(keepout
			(tracks not_allowed)
			(vias allowed)
			(pads allowed)
			(copperpour not_allowed)
			(footprints allowed)
		)
		(placement
			(enabled no)
			(sheetname "")
		)
		(fill yes
			(thermal_gap 0.5)
			(thermal_bridge_width 0.5)
			(island_removal_mode 0)
		)
		(polygon
			(pts
				(arc
					(start 64.520064 -13.09751)
					(mid 62.742064 -13.09751)
					(end 64.520064 -13.09751)
				)
			)
		)
	)
	(zone
		(layers "In1.Cu" "In3.Cu" "In5.Cu" "In7.Cu" "In8.Cu" "In9.Cu" "In10.Cu"
			"In12.Cu" "In14.Cu" "In16.Cu"
		)
		(hatch none 0.5)
		(connect_pads
			(clearance 0)
		)
		(min_thickness 0.25)
		(keepout
			(tracks not_allowed)
			(vias allowed)
			(pads allowed)
			(copperpour not_allowed)
			(footprints allowed)
		)
		(placement
			(enabled no)
			(sheetname "")
		)
		(fill yes
			(thermal_gap 0.5)
			(thermal_bridge_width 0.5)
			(island_removal_mode 0)
		)
		(polygon
			(pts
				(arc
					(start 396.670276 -176.657254)
					(mid 394.892276 -176.657254)
					(end 396.670276 -176.657254)
				)
			)
		)
	)
	(zone
		(layers "In1.Cu" "In3.Cu" "In5.Cu" "In7.Cu" "In8.Cu" "In9.Cu" "In10.Cu"
			"In12.Cu" "In14.Cu" "In16.Cu"
		)
		(hatch none 0.5)
		(connect_pads
			(clearance 0)
		)
		(min_thickness 0.25)
		(keepout
			(tracks not_allowed)
			(vias allowed)
			(pads allowed)
			(copperpour not_allowed)
			(footprints allowed)
		)
		(placement
			(enabled no)
			(sheetname "")
		)
		(fill yes
			(thermal_gap 0.5)
			(thermal_bridge_width 0.5)
			(island_removal_mode 0)
		)
		(polygon
			(pts
				(arc
					(start 64.680084 -348.709488)
					(mid 62.919864 -348.709488)
					(end 64.680084 -348.709488)
				)
			)
		)
	)
	(zone
		(layers "In1.Cu" "In3.Cu" "In5.Cu" "In7.Cu" "In8.Cu" "In9.Cu" "In10.Cu"
			"In12.Cu" "In14.Cu" "In16.Cu"
		)
		(hatch none 0.5)
		(connect_pads
			(clearance 0)
		)
		(min_thickness 0.25)
		(keepout
			(tracks not_allowed)
			(vias allowed)
			(pads allowed)
			(copperpour not_allowed)
			(footprints allowed)
		)
		(placement
			(enabled no)
			(sheetname "")
		)
		(fill yes
			(thermal_gap 0.5)
			(thermal_bridge_width 0.5)
			(island_removal_mode 0)
		)
		(polygon
			(pts
				(arc
					(start 443.260734 -18.824702)
					(mid 441.482734 -18.824702)
					(end 443.260734 -18.824702)
				)
			)
		)
	)
	(zone
		(layers "In1.Cu" "In3.Cu" "In5.Cu" "In7.Cu" "In8.Cu" "In9.Cu" "In10.Cu"
			"In12.Cu" "In14.Cu" "In16.Cu"
		)
		(hatch none 0.5)
		(connect_pads
			(clearance 0)
		)
		(min_thickness 0.25)
		(keepout
			(tracks not_allowed)
			(vias allowed)
			(pads allowed)
			(copperpour not_allowed)
			(footprints allowed)
		)
		(placement
			(enabled no)
			(sheetname "")
		)
		(fill yes
			(thermal_gap 0.5)
			(thermal_bridge_width 0.5)
			(island_removal_mode 0)
		)
		(polygon
			(pts
				(arc
					(start 194.620134 -15.781528)
					(mid 192.842134 -15.781528)
					(end 194.620134 -15.781528)
				)
			)
		)
	)
	(zone
		(layers "In1.Cu" "In3.Cu" "In5.Cu" "In7.Cu" "In8.Cu" "In9.Cu" "In10.Cu"
			"In12.Cu" "In14.Cu" "In16.Cu"
		)
		(hatch none 0.5)
		(connect_pads
			(clearance 0)
		)
		(min_thickness 0.25)
		(keepout
			(tracks not_allowed)
			(vias allowed)
			(pads allowed)
			(copperpour not_allowed)
			(footprints allowed)
		)
		(placement
			(enabled no)
			(sheetname "")
		)
		(fill yes
			(thermal_gap 0.5)
			(thermal_bridge_width 0.5)
			(island_removal_mode 0)
		)
		(polygon
			(pts
				(arc
					(start 63.35903 -165.74516)
					(mid 61.58103 -165.74516)
					(end 63.35903 -165.74516)
				)
			)
		)
	)
	(zone
		(layers "In1.Cu" "In3.Cu" "In5.Cu" "In7.Cu" "In8.Cu" "In9.Cu" "In10.Cu"
			"In12.Cu" "In14.Cu" "In16.Cu"
		)
		(hatch none 0.5)
		(connect_pads
			(clearance 0)
		)
		(min_thickness 0.25)
		(keepout
			(tracks not_allowed)
			(vias allowed)
			(pads allowed)
			(copperpour not_allowed)
			(footprints allowed)
		)
		(placement
			(enabled no)
			(sheetname "")
		)
		(fill yes
			(thermal_gap 0.5)
			(thermal_bridge_width 0.5)
			(island_removal_mode 0)
		)
		(polygon
			(pts
				(arc
					(start 388.981188 -180.755544)
					(mid 387.220968 -180.755544)
					(end 388.981188 -180.755544)
				)
			)
		)
	)
	(zone
		(layers "In1.Cu" "In3.Cu" "In5.Cu" "In7.Cu" "In8.Cu" "In9.Cu" "In10.Cu"
			"In12.Cu" "In14.Cu" "In16.Cu"
		)
		(hatch none 0.5)
		(connect_pads
			(clearance 0)
		)
		(min_thickness 0.25)
		(keepout
			(tracks not_allowed)
			(vias allowed)
			(pads allowed)
			(copperpour not_allowed)
			(footprints allowed)
		)
		(placement
			(enabled no)
			(sheetname "")
		)
		(fill yes
			(thermal_gap 0.5)
			(thermal_bridge_width 0.5)
			(island_removal_mode 0)
		)
		(polygon
			(pts
				(arc
					(start 379.339602 -179.883054)
					(mid 377.561602 -179.883054)
					(end 379.339602 -179.883054)
				)
			)
		)
	)
	(zone
		(layers "In1.Cu" "In3.Cu" "In5.Cu" "In7.Cu" "In8.Cu" "In9.Cu" "In10.Cu"
			"In12.Cu" "In14.Cu" "In16.Cu"
		)
		(hatch none 0.5)
		(connect_pads
			(clearance 0)
		)
		(min_thickness 0.25)
		(keepout
			(tracks not_allowed)
			(vias allowed)
			(pads allowed)
			(copperpour not_allowed)
			(footprints allowed)
		)
		(placement
			(enabled no)
			(sheetname "")
		)
		(fill yes
			(thermal_gap 0.5)
			(thermal_bridge_width 0.5)
			(island_removal_mode 0)
		)
		(polygon
			(pts
				(arc
					(start 361.492038 -174.232316)
					(mid 359.714038 -174.232316)
					(end 361.492038 -174.232316)
				)
			)
		)
	)
	(zone
		(layers "In1.Cu" "In3.Cu" "In5.Cu" "In7.Cu" "In8.Cu" "In9.Cu" "In10.Cu"
			"In12.Cu" "In14.Cu" "In16.Cu"
		)
		(hatch none 0.5)
		(connect_pads
			(clearance 0)
		)
		(min_thickness 0.25)
		(keepout
			(tracks not_allowed)
			(vias allowed)
			(pads allowed)
			(copperpour not_allowed)
			(footprints allowed)
		)
		(placement
			(enabled no)
			(sheetname "")
		)
		(fill yes
			(thermal_gap 0.5)
			(thermal_bridge_width 0.5)
			(island_removal_mode 0)
		)
		(polygon
			(pts
				(arc
					(start 200.959974 -30.720538)
					(mid 199.181974 -30.720538)
					(end 200.959974 -30.720538)
				)
			)
		)
	)
	(zone
		(layers "In1.Cu" "In3.Cu" "In5.Cu" "In7.Cu" "In8.Cu" "In9.Cu" "In10.Cu"
			"In12.Cu" "In14.Cu" "In16.Cu"
		)
		(hatch none 0.5)
		(connect_pads
			(clearance 0)
		)
		(min_thickness 0.25)
		(keepout
			(tracks not_allowed)
			(vias allowed)
			(pads allowed)
			(copperpour not_allowed)
			(footprints allowed)
		)
		(placement
			(enabled no)
			(sheetname "")
		)
		(fill yes
			(thermal_gap 0.5)
			(thermal_bridge_width 0.5)
			(island_removal_mode 0)
		)
		(polygon
			(pts
				(arc
					(start 285.273496 -348.704662)
					(mid 283.513276 -348.704662)
					(end 285.273496 -348.704662)
				)
			)
		)
	)
	(zone
		(layers "In1.Cu" "In3.Cu" "In5.Cu" "In7.Cu" "In8.Cu" "In9.Cu" "In10.Cu"
			"In12.Cu" "In14.Cu" "In16.Cu"
		)
		(hatch none 0.5)
		(connect_pads
			(clearance 0)
		)
		(min_thickness 0.25)
		(keepout
			(tracks not_allowed)
			(vias allowed)
			(pads allowed)
			(copperpour not_allowed)
			(footprints allowed)
		)
		(placement
			(enabled no)
			(sheetname "")
		)
		(fill yes
			(thermal_gap 0.5)
			(thermal_bridge_width 0.5)
			(island_removal_mode 0)
		)
		(polygon
			(pts
				(arc
					(start 186.923172 -361.472988)
					(mid 185.145172 -361.472988)
					(end 186.923172 -361.472988)
				)
			)
		)
	)
	(zone
		(layers "In1.Cu" "In3.Cu" "In5.Cu" "In7.Cu" "In8.Cu" "In9.Cu" "In10.Cu"
			"In12.Cu" "In14.Cu" "In16.Cu"
		)
		(hatch none 0.5)
		(connect_pads
			(clearance 0)
		)
		(min_thickness 0.25)
		(keepout
			(tracks not_allowed)
			(vias allowed)
			(pads allowed)
			(copperpour not_allowed)
			(footprints allowed)
		)
		(placement
			(enabled no)
			(sheetname "")
		)
		(fill yes
			(thermal_gap 0.5)
			(thermal_bridge_width 0.5)
			(island_removal_mode 0)
		)
		(polygon
			(pts
				(arc
					(start 286.758126 -347.245432)
					(mid 284.980126 -347.245432)
					(end 286.758126 -347.245432)
				)
			)
		)
	)
	(zone
		(layers "In1.Cu" "In3.Cu" "In5.Cu" "In7.Cu" "In8.Cu" "In9.Cu" "In10.Cu"
			"In12.Cu" "In14.Cu" "In16.Cu"
		)
		(hatch none 0.5)
		(connect_pads
			(clearance 0)
		)
		(min_thickness 0.25)
		(keepout
			(tracks not_allowed)
			(vias allowed)
			(pads allowed)
			(copperpour not_allowed)
			(footprints allowed)
		)
		(placement
			(enabled no)
			(sheetname "")
		)
		(fill yes
			(thermal_gap 0.5)
			(thermal_bridge_width 0.5)
			(island_removal_mode 0)
		)
		(polygon
			(pts
				(arc
					(start 322.94576 -337.061048)
					(mid 321.16776 -337.061048)
					(end 322.94576 -337.061048)
				)
			)
		)
	)
	(zone
		(layers "In1.Cu" "In3.Cu" "In5.Cu" "In7.Cu" "In8.Cu" "In9.Cu" "In10.Cu"
			"In12.Cu" "In14.Cu" "In16.Cu"
		)
		(hatch none 0.5)
		(connect_pads
			(clearance 0)
		)
		(min_thickness 0.25)
		(keepout
			(tracks not_allowed)
			(vias allowed)
			(pads allowed)
			(copperpour not_allowed)
			(footprints allowed)
		)
		(placement
			(enabled no)
			(sheetname "")
		)
		(fill yes
			(thermal_gap 0.5)
			(thermal_bridge_width 0.5)
			(island_removal_mode 0)
		)
		(polygon
			(pts
				(arc
					(start 93.784674 -165.962076)
					(mid 90.990674 -165.962076)
					(end 93.784674 -165.962076)
				)
			)
		)
	)
	(zone
		(layers "In1.Cu" "In3.Cu" "In5.Cu" "In7.Cu" "In8.Cu" "In9.Cu" "In10.Cu"
			"In12.Cu" "In14.Cu" "In16.Cu"
		)
		(hatch none 0.5)
		(connect_pads
			(clearance 0)
		)
		(min_thickness 0.25)
		(keepout
			(tracks not_allowed)
			(vias allowed)
			(pads allowed)
			(copperpour not_allowed)
			(footprints allowed)
		)
		(placement
			(enabled no)
			(sheetname "")
		)
		(fill yes
			(thermal_gap 0.5)
			(thermal_bridge_width 0.5)
			(island_removal_mode 0)
		)
		(polygon
			(pts
				(arc
					(start 452.943976 -18.535142)
					(mid 451.165976 -18.535142)
					(end 452.943976 -18.535142)
				)
			)
		)
	)
	(zone
		(layers "In1.Cu" "In3.Cu" "In5.Cu" "In7.Cu" "In8.Cu" "In9.Cu" "In10.Cu"
			"In12.Cu" "In14.Cu" "In16.Cu"
		)
		(hatch none 0.5)
		(connect_pads
			(clearance 0)
		)
		(min_thickness 0.25)
		(keepout
			(tracks not_allowed)
			(vias allowed)
			(pads allowed)
			(copperpour not_allowed)
			(footprints allowed)
		)
		(placement
			(enabled no)
			(sheetname "")
		)
		(fill yes
			(thermal_gap 0.5)
			(thermal_bridge_width 0.5)
			(island_removal_mode 0)
		)
		(polygon
			(pts
				(arc
					(start 113.947194 -168.326054)
					(mid 112.169194 -168.326054)
					(end 113.947194 -168.326054)
				)
			)
		)
	)
	(zone
		(layers "In1.Cu" "In3.Cu" "In5.Cu" "In7.Cu" "In8.Cu" "In9.Cu" "In10.Cu"
			"In12.Cu" "In14.Cu" "In16.Cu"
		)
		(hatch none 0.5)
		(connect_pads
			(clearance 0)
		)
		(min_thickness 0.25)
		(keepout
			(tracks not_allowed)
			(vias allowed)
			(pads allowed)
			(copperpour not_allowed)
			(footprints allowed)
		)
		(placement
			(enabled no)
			(sheetname "")
		)
		(fill yes
			(thermal_gap 0.5)
			(thermal_bridge_width 0.5)
			(island_removal_mode 0)
		)
		(polygon
			(pts
				(arc
					(start 289.17011 -356.584758)
					(mid 287.39211 -356.584758)
					(end 289.17011 -356.584758)
				)
			)
		)
	)
	(zone
		(layers "In1.Cu" "In3.Cu" "In5.Cu" "In7.Cu" "In8.Cu" "In9.Cu" "In10.Cu"
			"In12.Cu" "In14.Cu" "In16.Cu"
		)
		(hatch none 0.5)
		(connect_pads
			(clearance 0)
		)
		(min_thickness 0.25)
		(keepout
			(tracks not_allowed)
			(vias allowed)
			(pads allowed)
			(copperpour not_allowed)
			(footprints allowed)
		)
		(placement
			(enabled no)
			(sheetname "")
		)
		(fill yes
			(thermal_gap 0.5)
			(thermal_bridge_width 0.5)
			(island_removal_mode 0)
		)
		(polygon
			(pts
				(arc
					(start 40.39743 -349.581978)
					(mid 38.61943 -349.581978)
					(end 40.39743 -349.581978)
				)
			)
		)
	)
	(zone
		(layers "In1.Cu" "In3.Cu" "In5.Cu" "In7.Cu" "In8.Cu" "In9.Cu" "In10.Cu"
			"In12.Cu" "In14.Cu" "In16.Cu"
		)
		(hatch none 0.5)
		(connect_pads
			(clearance 0)
		)
		(min_thickness 0.25)
		(keepout
			(tracks not_allowed)
			(vias allowed)
			(pads allowed)
			(copperpour not_allowed)
			(footprints allowed)
		)
		(placement
			(enabled no)
			(sheetname "")
		)
		(fill yes
			(thermal_gap 0.5)
			(thermal_bridge_width 0.5)
			(island_removal_mode 0)
		)
		(polygon
			(pts
				(arc
					(start 49.786794 -348.786958)
					(mid 48.008794 -348.786958)
					(end 49.786794 -348.786958)
				)
			)
		)
	)
	(zone
		(layers "In1.Cu" "In3.Cu" "In5.Cu" "In7.Cu" "In8.Cu" "In9.Cu" "In10.Cu"
			"In12.Cu" "In14.Cu" "In16.Cu"
		)
		(hatch none 0.5)
		(connect_pads
			(clearance 0)
		)
		(min_thickness 0.25)
		(keepout
			(tracks not_allowed)
			(vias allowed)
			(pads allowed)
			(copperpour not_allowed)
			(footprints allowed)
		)
		(placement
			(enabled no)
			(sheetname "")
		)
		(fill yes
			(thermal_gap 0.5)
			(thermal_bridge_width 0.5)
			(island_removal_mode 0)
		)
		(polygon
			(pts
				(arc
					(start 178.491134 -25.949148)
					(mid 176.713134 -25.949148)
					(end 178.491134 -25.949148)
				)
			)
		)
	)
	(zone
		(layers "In1.Cu" "In3.Cu" "In5.Cu" "In7.Cu" "In8.Cu" "In9.Cu" "In10.Cu"
			"In12.Cu" "In14.Cu" "In16.Cu"
		)
		(hatch none 0.5)
		(connect_pads
			(clearance 0)
		)
		(min_thickness 0.25)
		(keepout
			(tracks not_allowed)
			(vias allowed)
			(pads allowed)
			(copperpour not_allowed)
			(footprints allowed)
		)
		(placement
			(enabled no)
			(sheetname "")
		)
		(fill yes
			(thermal_gap 0.5)
			(thermal_bridge_width 0.5)
			(island_removal_mode 0)
		)
		(polygon
			(pts
				(arc
					(start 296.074846 -349.899732)
					(mid 294.296846 -349.899732)
					(end 296.074846 -349.899732)
				)
			)
		)
	)
	(zone
		(layers "In1.Cu" "In3.Cu" "In5.Cu" "In7.Cu" "In8.Cu" "In9.Cu" "In10.Cu"
			"In12.Cu" "In14.Cu" "In16.Cu"
		)
		(hatch none 0.5)
		(connect_pads
			(clearance 0)
		)
		(min_thickness 0.25)
		(keepout
			(tracks not_allowed)
			(vias allowed)
			(pads allowed)
			(copperpour not_allowed)
			(footprints allowed)
		)
		(placement
			(enabled no)
			(sheetname "")
		)
		(fill yes
			(thermal_gap 0.5)
			(thermal_bridge_width 0.5)
			(island_removal_mode 0)
		)
		(polygon
			(pts
				(arc
					(start 412.791402 -160.170368)
					(mid 411.013402 -160.170368)
					(end 412.791402 -160.170368)
				)
			)
		)
	)
	(zone
		(layers "In1.Cu" "In3.Cu" "In5.Cu" "In7.Cu" "In8.Cu" "In9.Cu" "In10.Cu"
			"In12.Cu" "In14.Cu" "In16.Cu"
		)
		(hatch none 0.5)
		(connect_pads
			(clearance 0)
		)
		(min_thickness 0.25)
		(keepout
			(tracks not_allowed)
			(vias allowed)
			(pads allowed)
			(copperpour not_allowed)
			(footprints allowed)
		)
		(placement
			(enabled no)
			(sheetname "")
		)
		(fill yes
			(thermal_gap 0.5)
			(thermal_bridge_width 0.5)
			(island_removal_mode 0)
		)
		(polygon
			(pts
				(arc
					(start 239.181894 -44.802806)
					(mid 237.403894 -44.802806)
					(end 239.181894 -44.802806)
				)
			)
		)
	)
	(zone
		(layers "In1.Cu" "In3.Cu" "In5.Cu" "In7.Cu" "In8.Cu" "In9.Cu" "In10.Cu"
			"In12.Cu" "In14.Cu" "In16.Cu"
		)
		(hatch none 0.5)
		(connect_pads
			(clearance 0)
		)
		(min_thickness 0.25)
		(keepout
			(tracks not_allowed)
			(vias allowed)
			(pads allowed)
			(copperpour not_allowed)
			(footprints allowed)
		)
		(placement
			(enabled no)
			(sheetname "")
		)
		(fill yes
			(thermal_gap 0.5)
			(thermal_bridge_width 0.5)
			(island_removal_mode 0)
		)
		(polygon
			(pts
				(arc
					(start 91.509088 -345.96959)
					(mid 89.731088 -345.96959)
					(end 91.509088 -345.96959)
				)
			)
		)
	)
	(zone
		(layers "In1.Cu" "In3.Cu" "In5.Cu" "In7.Cu" "In8.Cu" "In9.Cu" "In10.Cu"
			"In12.Cu" "In14.Cu" "In16.Cu"
		)
		(hatch none 0.5)
		(connect_pads
			(clearance 0)
		)
		(min_thickness 0.25)
		(keepout
			(tracks not_allowed)
			(vias allowed)
			(pads allowed)
			(copperpour not_allowed)
			(footprints allowed)
		)
		(placement
			(enabled no)
			(sheetname "")
		)
		(fill yes
			(thermal_gap 0.5)
			(thermal_bridge_width 0.5)
			(island_removal_mode 0)
		)
		(polygon
			(pts
				(arc
					(start 59.511946 -393.292838)
					(mid 59.816746 -393.597638)
					(end 60.121546 -393.292838)
				)
				(arc
					(start 60.121546 -392.429238)
					(mid 59.816746 -392.124438)
					(end 59.511946 -392.429238)
				)
			)
		)
	)
	(zone
		(layers "In1.Cu" "In3.Cu" "In5.Cu" "In7.Cu" "In8.Cu" "In9.Cu" "In10.Cu"
			"In12.Cu" "In14.Cu" "In16.Cu"
		)
		(hatch none 0.5)
		(connect_pads
			(clearance 0)
		)
		(min_thickness 0.25)
		(keepout
			(tracks not_allowed)
			(vias allowed)
			(pads allowed)
			(copperpour not_allowed)
			(footprints allowed)
		)
		(placement
			(enabled no)
			(sheetname "")
		)
		(fill yes
			(thermal_gap 0.5)
			(thermal_bridge_width 0.5)
			(island_removal_mode 0)
		)
		(polygon
			(pts
				(arc
					(start 439.481214 -12.400788)
					(mid 437.703214 -12.400788)
					(end 439.481214 -12.400788)
				)
			)
		)
	)
	(zone
		(layers "In1.Cu" "In3.Cu" "In5.Cu" "In7.Cu" "In8.Cu" "In9.Cu" "In10.Cu"
			"In12.Cu" "In14.Cu" "In16.Cu"
		)
		(hatch none 0.5)
		(connect_pads
			(clearance 0)
		)
		(min_thickness 0.25)
		(keepout
			(tracks not_allowed)
			(vias allowed)
			(pads allowed)
			(copperpour not_allowed)
			(footprints allowed)
		)
		(placement
			(enabled no)
			(sheetname "")
		)
		(fill yes
			(thermal_gap 0.5)
			(thermal_bridge_width 0.5)
			(island_removal_mode 0)
		)
		(polygon
			(pts
				(arc
					(start 343.676224 -351.453196)
					(mid 341.898224 -351.453196)
					(end 343.676224 -351.453196)
				)
			)
		)
	)
	(zone
		(layers "In1.Cu" "In3.Cu" "In5.Cu" "In7.Cu" "In8.Cu" "In9.Cu" "In10.Cu"
			"In12.Cu" "In14.Cu" "In16.Cu"
		)
		(hatch none 0.5)
		(connect_pads
			(clearance 0)
		)
		(min_thickness 0.25)
		(keepout
			(tracks not_allowed)
			(vias allowed)
			(pads allowed)
			(copperpour not_allowed)
			(footprints allowed)
		)
		(placement
			(enabled no)
			(sheetname "")
		)
		(fill yes
			(thermal_gap 0.5)
			(thermal_bridge_width 0.5)
			(island_removal_mode 0)
		)
		(polygon
			(pts
				(arc
					(start 354.788724 -341.22741)
					(mid 353.010724 -341.22741)
					(end 354.788724 -341.22741)
				)
			)
		)
	)
	(zone
		(layers "In1.Cu" "In3.Cu" "In5.Cu" "In7.Cu" "In8.Cu" "In9.Cu" "In10.Cu"
			"In12.Cu" "In14.Cu" "In16.Cu"
		)
		(hatch none 0.5)
		(connect_pads
			(clearance 0)
		)
		(min_thickness 0.25)
		(keepout
			(tracks not_allowed)
			(vias allowed)
			(pads allowed)
			(copperpour not_allowed)
			(footprints allowed)
		)
		(placement
			(enabled no)
			(sheetname "")
		)
		(fill yes
			(thermal_gap 0.5)
			(thermal_bridge_width 0.5)
			(island_removal_mode 0)
		)
		(polygon
			(pts
				(arc
					(start 442.243718 -20.10156)
					(mid 440.465718 -20.10156)
					(end 442.243718 -20.10156)
				)
			)
		)
	)
	(zone
		(layers "In1.Cu" "In3.Cu" "In5.Cu" "In7.Cu" "In8.Cu" "In9.Cu" "In10.Cu"
			"In12.Cu" "In14.Cu" "In16.Cu"
		)
		(hatch none 0.5)
		(connect_pads
			(clearance 0)
		)
		(min_thickness 0.25)
		(keepout
			(tracks not_allowed)
			(vias allowed)
			(pads allowed)
			(copperpour not_allowed)
			(footprints allowed)
		)
		(placement
			(enabled no)
			(sheetname "")
		)
		(fill yes
			(thermal_gap 0.5)
			(thermal_bridge_width 0.5)
			(island_removal_mode 0)
		)
		(polygon
			(pts
				(arc
					(start 26.71445 -40.816276)
					(mid 24.93645 -40.816276)
					(end 26.71445 -40.816276)
				)
			)
		)
	)
	(zone
		(layers "In1.Cu" "In3.Cu" "In5.Cu" "In7.Cu" "In8.Cu" "In9.Cu" "In10.Cu"
			"In12.Cu" "In14.Cu" "In16.Cu"
		)
		(hatch none 0.5)
		(connect_pads
			(clearance 0)
		)
		(min_thickness 0.25)
		(keepout
			(tracks not_allowed)
			(vias allowed)
			(pads allowed)
			(copperpour not_allowed)
			(footprints allowed)
		)
		(placement
			(enabled no)
			(sheetname "")
		)
		(fill yes
			(thermal_gap 0.5)
			(thermal_bridge_width 0.5)
			(island_removal_mode 0)
		)
		(polygon
			(pts
				(arc
					(start 122.227594 -162.331654)
					(mid 120.449594 -162.331654)
					(end 122.227594 -162.331654)
				)
			)
		)
	)
	(zone
		(layers "In1.Cu" "In3.Cu" "In5.Cu" "In7.Cu" "In8.Cu" "In9.Cu" "In10.Cu"
			"In12.Cu" "In14.Cu" "In16.Cu"
		)
		(hatch none 0.5)
		(connect_pads
			(clearance 0)
		)
		(min_thickness 0.25)
		(keepout
			(tracks not_allowed)
			(vias allowed)
			(pads allowed)
			(copperpour not_allowed)
			(footprints allowed)
		)
		(placement
			(enabled no)
			(sheetname "")
		)
		(fill yes
			(thermal_gap 0.5)
			(thermal_bridge_width 0.5)
			(island_removal_mode 0)
		)
		(polygon
			(pts
				(arc
					(start 115.25758 -169.935144)
					(mid 113.49736 -169.935144)
					(end 115.25758 -169.935144)
				)
			)
		)
	)
	(zone
		(layers "In1.Cu" "In3.Cu" "In5.Cu" "In7.Cu" "In8.Cu" "In9.Cu" "In10.Cu"
			"In12.Cu" "In14.Cu" "In16.Cu"
		)
		(hatch none 0.5)
		(connect_pads
			(clearance 0)
		)
		(min_thickness 0.25)
		(keepout
			(tracks not_allowed)
			(vias allowed)
			(pads allowed)
			(copperpour not_allowed)
			(footprints allowed)
		)
		(placement
			(enabled no)
			(sheetname "")
		)
		(fill yes
			(thermal_gap 0.5)
			(thermal_bridge_width 0.5)
			(island_removal_mode 0)
		)
		(polygon
			(pts
				(arc
					(start 388.817358 -153.793952)
					(mid 387.039358 -153.793952)
					(end 388.817358 -153.793952)
				)
			)
		)
	)
	(zone
		(layers "In1.Cu" "In3.Cu" "In5.Cu" "In7.Cu" "In8.Cu" "In9.Cu" "In10.Cu"
			"In12.Cu" "In14.Cu" "In16.Cu"
		)
		(hatch none 0.5)
		(connect_pads
			(clearance 0)
		)
		(min_thickness 0.25)
		(keepout
			(tracks not_allowed)
			(vias allowed)
			(pads allowed)
			(copperpour not_allowed)
			(footprints allowed)
		)
		(placement
			(enabled no)
			(sheetname "")
		)
		(fill yes
			(thermal_gap 0.5)
			(thermal_bridge_width 0.5)
			(island_removal_mode 0)
		)
		(polygon
			(pts
				(arc
					(start 344.905838 -159.073596)
					(mid 343.127838 -159.073596)
					(end 344.905838 -159.073596)
				)
			)
		)
	)
	(zone
		(layers "In1.Cu" "In3.Cu" "In5.Cu" "In7.Cu" "In8.Cu" "In9.Cu" "In10.Cu"
			"In12.Cu" "In14.Cu" "In16.Cu"
		)
		(hatch none 0.5)
		(connect_pads
			(clearance 0)
		)
		(min_thickness 0.25)
		(keepout
			(tracks not_allowed)
			(vias allowed)
			(pads allowed)
			(copperpour not_allowed)
			(footprints allowed)
		)
		(placement
			(enabled no)
			(sheetname "")
		)
		(fill yes
			(thermal_gap 0.5)
			(thermal_bridge_width 0.5)
			(island_removal_mode 0)
		)
		(polygon
			(pts
				(arc
					(start 58.143394 -350.260158)
					(mid 56.365394 -350.260158)
					(end 58.143394 -350.260158)
				)
			)
		)
	)
	(zone
		(layers "In1.Cu" "In3.Cu" "In5.Cu" "In7.Cu" "In8.Cu" "In9.Cu" "In10.Cu"
			"In12.Cu" "In14.Cu" "In16.Cu"
		)
		(hatch none 0.5)
		(connect_pads
			(clearance 0)
		)
		(min_thickness 0.25)
		(keepout
			(tracks not_allowed)
			(vias allowed)
			(pads allowed)
			(copperpour not_allowed)
			(footprints allowed)
		)
		(placement
			(enabled no)
			(sheetname "")
		)
		(fill yes
			(thermal_gap 0.5)
			(thermal_bridge_width 0.5)
			(island_removal_mode 0)
		)
		(polygon
			(pts
				(arc
					(start 388.255256 -182.230776)
					(mid 386.477256 -182.230776)
					(end 388.255256 -182.230776)
				)
			)
		)
	)
	(zone
		(layers "In1.Cu" "In3.Cu" "In5.Cu" "In7.Cu" "In8.Cu" "In9.Cu" "In10.Cu"
			"In12.Cu" "In14.Cu" "In16.Cu"
		)
		(hatch none 0.5)
		(connect_pads
			(clearance 0)
		)
		(min_thickness 0.25)
		(keepout
			(tracks not_allowed)
			(vias allowed)
			(pads allowed)
			(copperpour not_allowed)
			(footprints allowed)
		)
		(placement
			(enabled no)
			(sheetname "")
		)
		(fill yes
			(thermal_gap 0.5)
			(thermal_bridge_width 0.5)
			(island_removal_mode 0)
		)
		(polygon
			(pts
				(arc
					(start 276.993096 -348.704662)
					(mid 275.232876 -348.704662)
					(end 276.993096 -348.704662)
				)
			)
		)
	)
	(zone
		(layers "In1.Cu" "In3.Cu" "In5.Cu" "In7.Cu" "In8.Cu" "In9.Cu" "In10.Cu"
			"In12.Cu" "In14.Cu" "In16.Cu"
		)
		(hatch none 0.5)
		(connect_pads
			(clearance 0)
		)
		(min_thickness 0.25)
		(keepout
			(tracks not_allowed)
			(vias allowed)
			(pads allowed)
			(copperpour not_allowed)
			(footprints allowed)
		)
		(placement
			(enabled no)
			(sheetname "")
		)
		(fill yes
			(thermal_gap 0.5)
			(thermal_bridge_width 0.5)
			(island_removal_mode 0)
		)
		(polygon
			(pts
				(arc
					(start 395.517878 -172.45711)
					(mid 393.739878 -172.45711)
					(end 395.517878 -172.45711)
				)
			)
		)
	)
	(zone
		(layers "In1.Cu" "In3.Cu" "In5.Cu" "In7.Cu" "In8.Cu" "In9.Cu" "In10.Cu"
			"In12.Cu" "In14.Cu" "In16.Cu"
		)
		(hatch none 0.5)
		(connect_pads
			(clearance 0)
		)
		(min_thickness 0.25)
		(keepout
			(tracks not_allowed)
			(vias allowed)
			(pads allowed)
			(copperpour not_allowed)
			(footprints allowed)
		)
		(placement
			(enabled no)
			(sheetname "")
		)
		(fill yes
			(thermal_gap 0.5)
			(thermal_bridge_width 0.5)
			(island_removal_mode 0)
		)
		(polygon
			(pts
				(arc
					(start 49.65573 -357.457502)
					(mid 47.87773 -357.457502)
					(end 49.65573 -357.457502)
				)
			)
		)
	)
	(zone
		(layers "In1.Cu" "In3.Cu" "In5.Cu" "In7.Cu" "In8.Cu" "In9.Cu" "In10.Cu"
			"In12.Cu" "In14.Cu" "In16.Cu"
		)
		(hatch none 0.5)
		(connect_pads
			(clearance 0)
		)
		(min_thickness 0.25)
		(keepout
			(tracks not_allowed)
			(vias allowed)
			(pads allowed)
			(copperpour not_allowed)
			(footprints allowed)
		)
		(placement
			(enabled no)
			(sheetname "")
		)
		(fill yes
			(thermal_gap 0.5)
			(thermal_bridge_width 0.5)
			(island_removal_mode 0)
		)
		(polygon
			(pts
				(arc
					(start 388.603998 -162.65271)
					(mid 385.809998 -162.65271)
					(end 388.603998 -162.65271)
				)
			)
		)
	)
	(zone
		(layers "In1.Cu" "In3.Cu" "In5.Cu" "In7.Cu" "In8.Cu" "In9.Cu" "In10.Cu"
			"In12.Cu" "In14.Cu" "In16.Cu"
		)
		(hatch none 0.5)
		(connect_pads
			(clearance 0)
		)
		(min_thickness 0.25)
		(keepout
			(tracks not_allowed)
			(vias allowed)
			(pads allowed)
			(copperpour not_allowed)
			(footprints allowed)
		)
		(placement
			(enabled no)
			(sheetname "")
		)
		(fill yes
			(thermal_gap 0.5)
			(thermal_bridge_width 0.5)
			(island_removal_mode 0)
		)
		(polygon
			(pts
				(arc
					(start 89.19845 -162.812476)
					(mid 87.42045 -162.812476)
					(end 89.19845 -162.812476)
				)
			)
		)
	)
	(zone
		(layers "In1.Cu" "In3.Cu" "In5.Cu" "In7.Cu" "In8.Cu" "In9.Cu" "In10.Cu"
			"In12.Cu" "In14.Cu" "In16.Cu"
		)
		(hatch none 0.5)
		(connect_pads
			(clearance 0)
		)
		(min_thickness 0.25)
		(keepout
			(tracks not_allowed)
			(vias allowed)
			(pads allowed)
			(copperpour not_allowed)
			(footprints allowed)
		)
		(placement
			(enabled no)
			(sheetname "")
		)
		(fill yes
			(thermal_gap 0.5)
			(thermal_bridge_width 0.5)
			(island_removal_mode 0)
		)
		(polygon
			(pts
				(arc
					(start 296.608246 -350.255332)
					(mid 294.830246 -350.255332)
					(end 296.608246 -350.255332)
				)
			)
		)
	)
	(zone
		(layers "In1.Cu" "In3.Cu" "In5.Cu" "In7.Cu" "In8.Cu" "In9.Cu" "In10.Cu"
			"In12.Cu" "In14.Cu" "In16.Cu"
		)
		(hatch none 0.5)
		(connect_pads
			(clearance 0)
		)
		(min_thickness 0.25)
		(keepout
			(tracks not_allowed)
			(vias allowed)
			(pads allowed)
			(copperpour not_allowed)
			(footprints allowed)
		)
		(placement
			(enabled no)
			(sheetname "")
		)
		(fill yes
			(thermal_gap 0.5)
			(thermal_bridge_width 0.5)
			(island_removal_mode 0)
		)
		(polygon
			(pts
				(arc
					(start 55.114444 -348.709488)
					(mid 53.354224 -348.709488)
					(end 55.114444 -348.709488)
				)
			)
		)
	)
	(zone
		(layers "In1.Cu" "In3.Cu" "In5.Cu" "In7.Cu" "In8.Cu" "In9.Cu" "In10.Cu"
			"In12.Cu" "In14.Cu" "In16.Cu"
		)
		(hatch none 0.5)
		(connect_pads
			(clearance 0)
		)
		(min_thickness 0.25)
		(keepout
			(tracks not_allowed)
			(vias allowed)
			(pads allowed)
			(copperpour not_allowed)
			(footprints allowed)
		)
		(placement
			(enabled no)
			(sheetname "")
		)
		(fill yes
			(thermal_gap 0.5)
			(thermal_bridge_width 0.5)
			(island_removal_mode 0)
		)
		(polygon
			(pts
				(arc
					(start 370.838984 -163.89858)
					(mid 369.060984 -163.89858)
					(end 370.838984 -163.89858)
				)
			)
		)
	)
	(zone
		(layers "In1.Cu" "In3.Cu" "In5.Cu" "In7.Cu" "In8.Cu" "In9.Cu" "In10.Cu"
			"In12.Cu" "In14.Cu" "In16.Cu"
		)
		(hatch none 0.5)
		(connect_pads
			(clearance 0)
		)
		(min_thickness 0.25)
		(keepout
			(tracks not_allowed)
			(vias allowed)
			(pads allowed)
			(copperpour not_allowed)
			(footprints allowed)
		)
		(placement
			(enabled no)
			(sheetname "")
		)
		(fill yes
			(thermal_gap 0.5)
			(thermal_bridge_width 0.5)
			(island_removal_mode 0)
		)
		(polygon
			(pts
				(arc
					(start 179.380134 -25.949148)
					(mid 177.602134 -25.949148)
					(end 179.380134 -25.949148)
				)
			)
		)
	)
	(zone
		(layers "In1.Cu" "In3.Cu" "In5.Cu" "In7.Cu" "In8.Cu" "In9.Cu" "In10.Cu"
			"In12.Cu" "In14.Cu" "In16.Cu"
		)
		(hatch none 0.5)
		(connect_pads
			(clearance 0)
		)
		(min_thickness 0.25)
		(keepout
			(tracks not_allowed)
			(vias allowed)
			(pads allowed)
			(copperpour not_allowed)
			(footprints allowed)
		)
		(placement
			(enabled no)
			(sheetname "")
		)
		(fill yes
			(thermal_gap 0.5)
			(thermal_bridge_width 0.5)
			(island_removal_mode 0)
		)
		(polygon
			(pts
				(arc
					(start 195.846446 -354.123244)
					(mid 194.068446 -354.123244)
					(end 195.846446 -354.123244)
				)
			)
		)
	)
	(zone
		(layers "In1.Cu" "In3.Cu" "In5.Cu" "In7.Cu" "In8.Cu" "In9.Cu" "In10.Cu"
			"In12.Cu" "In14.Cu" "In16.Cu"
		)
		(hatch none 0.5)
		(connect_pads
			(clearance 0)
		)
		(min_thickness 0.25)
		(keepout
			(tracks not_allowed)
			(vias allowed)
			(pads allowed)
			(copperpour not_allowed)
			(footprints allowed)
		)
		(placement
			(enabled no)
			(sheetname "")
		)
		(fill yes
			(thermal_gap 0.5)
			(thermal_bridge_width 0.5)
			(island_removal_mode 0)
		)
		(polygon
			(pts
				(arc
					(start 311.756806 -347.265752)
					(mid 309.978806 -347.265752)
					(end 311.756806 -347.265752)
				)
			)
		)
	)
	(zone
		(layers "In1.Cu" "In3.Cu" "In5.Cu" "In7.Cu" "In8.Cu" "In9.Cu" "In10.Cu"
			"In12.Cu" "In14.Cu" "In16.Cu"
		)
		(hatch none 0.5)
		(connect_pads
			(clearance 0)
		)
		(min_thickness 0.25)
		(keepout
			(tracks not_allowed)
			(vias allowed)
			(pads allowed)
			(copperpour not_allowed)
			(footprints allowed)
		)
		(placement
			(enabled no)
			(sheetname "")
		)
		(fill yes
			(thermal_gap 0.5)
			(thermal_bridge_width 0.5)
			(island_removal_mode 0)
		)
		(polygon
			(pts
				(arc
					(start 69.43344 -18.476214)
					(mid 67.65544 -18.476214)
					(end 69.43344 -18.476214)
				)
			)
		)
	)
	(zone
		(layers "In1.Cu" "In3.Cu" "In5.Cu" "In7.Cu" "In8.Cu" "In9.Cu" "In10.Cu"
			"In12.Cu" "In14.Cu" "In16.Cu"
		)
		(hatch none 0.5)
		(connect_pads
			(clearance 0)
		)
		(min_thickness 0.25)
		(keepout
			(tracks not_allowed)
			(vias allowed)
			(pads allowed)
			(copperpour not_allowed)
			(footprints allowed)
		)
		(placement
			(enabled no)
			(sheetname "")
		)
		(fill yes
			(thermal_gap 0.5)
			(thermal_bridge_width 0.5)
			(island_removal_mode 0)
		)
		(polygon
			(pts
				(arc
					(start 73.496424 -336.255868)
					(mid 71.736204 -336.255868)
					(end 73.496424 -336.255868)
				)
			)
		)
	)
	(zone
		(layers "In1.Cu" "In3.Cu" "In5.Cu" "In7.Cu" "In8.Cu" "In9.Cu" "In10.Cu"
			"In12.Cu" "In14.Cu" "In16.Cu"
		)
		(hatch none 0.5)
		(connect_pads
			(clearance 0)
		)
		(min_thickness 0.25)
		(keepout
			(tracks not_allowed)
			(vias allowed)
			(pads allowed)
			(copperpour not_allowed)
			(footprints allowed)
		)
		(placement
			(enabled no)
			(sheetname "")
		)
		(fill yes
			(thermal_gap 0.5)
			(thermal_bridge_width 0.5)
			(island_removal_mode 0)
		)
		(polygon
			(pts
				(arc
					(start 89.310464 -336.966814)
					(mid 87.550244 -336.966814)
					(end 89.310464 -336.966814)
				)
			)
		)
	)
	(zone
		(layers "In1.Cu" "In3.Cu" "In5.Cu" "In7.Cu" "In8.Cu" "In9.Cu" "In10.Cu"
			"In12.Cu" "In14.Cu" "In16.Cu"
		)
		(hatch none 0.5)
		(connect_pads
			(clearance 0)
		)
		(min_thickness 0.25)
		(keepout
			(tracks not_allowed)
			(vias allowed)
			(pads allowed)
			(copperpour not_allowed)
			(footprints allowed)
		)
		(placement
			(enabled no)
			(sheetname "")
		)
		(fill yes
			(thermal_gap 0.5)
			(thermal_bridge_width 0.5)
			(island_removal_mode 0)
		)
		(polygon
			(pts
				(arc
					(start 54.711854 -393.292838)
					(mid 55.016654 -393.597638)
					(end 55.321454 -393.292838)
				)
				(arc
					(start 55.321454 -392.429238)
					(mid 55.016654 -392.124438)
					(end 54.711854 -392.429238)
				)
			)
		)
	)
	(zone
		(layers "In1.Cu" "In3.Cu" "In5.Cu" "In7.Cu" "In8.Cu" "In9.Cu" "In10.Cu"
			"In12.Cu" "In14.Cu" "In16.Cu"
		)
		(hatch none 0.5)
		(connect_pads
			(clearance 0)
		)
		(min_thickness 0.25)
		(keepout
			(tracks not_allowed)
			(vias allowed)
			(pads allowed)
			(copperpour not_allowed)
			(footprints allowed)
		)
		(placement
			(enabled no)
			(sheetname "")
		)
		(fill yes
			(thermal_gap 0.5)
			(thermal_bridge_width 0.5)
			(island_removal_mode 0)
		)
		(polygon
			(pts
				(arc
					(start 39.939214 -347.237558)
					(mid 38.161214 -347.237558)
					(end 39.939214 -347.237558)
				)
			)
		)
	)
	(zone
		(layers "In1.Cu" "In3.Cu" "In5.Cu" "In7.Cu" "In8.Cu" "In9.Cu" "In10.Cu"
			"In12.Cu" "In14.Cu" "In16.Cu"
		)
		(hatch none 0.5)
		(connect_pads
			(clearance 0)
		)
		(min_thickness 0.25)
		(keepout
			(tracks not_allowed)
			(vias allowed)
			(pads allowed)
			(copperpour not_allowed)
			(footprints allowed)
		)
		(placement
			(enabled no)
			(sheetname "")
		)
		(fill yes
			(thermal_gap 0.5)
			(thermal_bridge_width 0.5)
			(island_removal_mode 0)
		)
		(polygon
			(pts
				(arc
					(start 82.831178 -338.176362)
					(mid 81.053178 -338.176362)
					(end 82.831178 -338.176362)
				)
			)
		)
	)
	(zone
		(layers "In1.Cu" "In3.Cu" "In5.Cu" "In7.Cu" "In8.Cu" "In9.Cu" "In10.Cu"
			"In12.Cu" "In14.Cu" "In16.Cu"
		)
		(hatch none 0.5)
		(connect_pads
			(clearance 0)
		)
		(min_thickness 0.25)
		(keepout
			(tracks not_allowed)
			(vias allowed)
			(pads allowed)
			(copperpour not_allowed)
			(footprints allowed)
		)
		(placement
			(enabled no)
			(sheetname "")
		)
		(fill yes
			(thermal_gap 0.5)
			(thermal_bridge_width 0.5)
			(island_removal_mode 0)
		)
		(polygon
			(pts
				(arc
					(start 50.29073 -356.822502)
					(mid 48.51273 -356.822502)
					(end 50.29073 -356.822502)
				)
			)
		)
	)
	(zone
		(layers "In1.Cu" "In3.Cu" "In5.Cu" "In7.Cu" "In8.Cu" "In9.Cu" "In10.Cu"
			"In12.Cu" "In14.Cu" "In16.Cu"
		)
		(hatch none 0.5)
		(connect_pads
			(clearance 0)
		)
		(min_thickness 0.25)
		(keepout
			(tracks not_allowed)
			(vias allowed)
			(pads allowed)
			(copperpour not_allowed)
			(footprints allowed)
		)
		(placement
			(enabled no)
			(sheetname "")
		)
		(fill yes
			(thermal_gap 0.5)
			(thermal_bridge_width 0.5)
			(island_removal_mode 0)
		)
		(polygon
			(pts
				(arc
					(start 288.302446 -348.782132)
					(mid 286.524446 -348.782132)
					(end 288.302446 -348.782132)
				)
			)
		)
	)
	(zone
		(layers "In1.Cu" "In3.Cu" "In5.Cu" "In7.Cu" "In8.Cu" "In9.Cu" "In10.Cu"
			"In12.Cu" "In14.Cu" "In16.Cu"
		)
		(hatch none 0.5)
		(connect_pads
			(clearance 0)
		)
		(min_thickness 0.25)
		(keepout
			(tracks not_allowed)
			(vias allowed)
			(pads allowed)
			(copperpour not_allowed)
			(footprints allowed)
		)
		(placement
			(enabled no)
			(sheetname "")
		)
		(fill yes
			(thermal_gap 0.5)
			(thermal_bridge_width 0.5)
			(island_removal_mode 0)
		)
		(polygon
			(pts
				(arc
					(start 354.879656 -168.245536)
					(mid 353.101656 -168.245536)
					(end 354.879656 -168.245536)
				)
			)
		)
	)
	(zone
		(layers "In1.Cu" "In3.Cu" "In5.Cu" "In7.Cu" "In8.Cu" "In9.Cu" "In10.Cu"
			"In12.Cu" "In14.Cu" "In16.Cu"
		)
		(hatch none 0.5)
		(connect_pads
			(clearance 0)
		)
		(min_thickness 0.25)
		(keepout
			(tracks not_allowed)
			(vias allowed)
			(pads allowed)
			(copperpour not_allowed)
			(footprints allowed)
		)
		(placement
			(enabled no)
			(sheetname "")
		)
		(fill yes
			(thermal_gap 0.5)
			(thermal_bridge_width 0.5)
			(island_removal_mode 0)
		)
		(polygon
			(pts
				(arc
					(start 73.533 -175.639222)
					(mid 71.77278 -175.639222)
					(end 73.533 -175.639222)
				)
			)
		)
	)
	(zone
		(layers "In1.Cu" "In3.Cu" "In5.Cu" "In7.Cu" "In8.Cu" "In9.Cu" "In10.Cu"
			"In12.Cu" "In14.Cu" "In16.Cu"
		)
		(hatch none 0.5)
		(connect_pads
			(clearance 0)
		)
		(min_thickness 0.25)
		(keepout
			(tracks not_allowed)
			(vias allowed)
			(pads allowed)
			(copperpour not_allowed)
			(footprints allowed)
		)
		(placement
			(enabled no)
			(sheetname "")
		)
		(fill yes
			(thermal_gap 0.5)
			(thermal_bridge_width 0.5)
			(island_removal_mode 0)
		)
		(polygon
			(pts
				(arc
					(start 82.281014 -338.590382)
					(mid 80.503014 -338.590382)
					(end 82.281014 -338.590382)
				)
			)
		)
	)
	(zone
		(layers "In1.Cu" "In3.Cu" "In5.Cu" "In7.Cu" "In8.Cu" "In9.Cu" "In10.Cu"
			"In12.Cu" "In14.Cu" "In16.Cu"
		)
		(hatch none 0.5)
		(connect_pads
			(clearance 0)
		)
		(min_thickness 0.25)
		(keepout
			(tracks not_allowed)
			(vias allowed)
			(pads allowed)
			(copperpour not_allowed)
			(footprints allowed)
		)
		(placement
			(enabled no)
			(sheetname "")
		)
		(fill yes
			(thermal_gap 0.5)
			(thermal_bridge_width 0.5)
			(island_removal_mode 0)
		)
		(polygon
			(pts
				(arc
					(start 346.512896 -335.580736)
					(mid 344.734896 -335.580736)
					(end 346.512896 -335.580736)
				)
			)
		)
	)
	(zone
		(layers "In1.Cu" "In3.Cu" "In5.Cu" "In7.Cu" "In8.Cu" "In9.Cu" "In10.Cu"
			"In12.Cu" "In14.Cu" "In16.Cu"
		)
		(hatch none 0.5)
		(connect_pads
			(clearance 0)
		)
		(min_thickness 0.25)
		(keepout
			(tracks not_allowed)
			(vias allowed)
			(pads allowed)
			(copperpour not_allowed)
			(footprints allowed)
		)
		(placement
			(enabled no)
			(sheetname "")
		)
		(fill yes
			(thermal_gap 0.5)
			(thermal_bridge_width 0.5)
			(island_removal_mode 0)
		)
		(polygon
			(pts
				(arc
					(start 63.445644 -348.709488)
					(mid 61.685424 -348.709488)
					(end 63.445644 -348.709488)
				)
			)
		)
	)
	(zone
		(layers "In1.Cu" "In3.Cu" "In5.Cu" "In7.Cu" "In8.Cu" "In9.Cu" "In10.Cu"
			"In12.Cu" "In14.Cu" "In16.Cu"
		)
		(hatch none 0.5)
		(connect_pads
			(clearance 0)
		)
		(min_thickness 0.25)
		(keepout
			(tracks not_allowed)
			(vias allowed)
			(pads allowed)
			(copperpour not_allowed)
			(footprints allowed)
		)
		(placement
			(enabled no)
			(sheetname "")
		)
		(fill yes
			(thermal_gap 0.5)
			(thermal_bridge_width 0.5)
			(island_removal_mode 0)
		)
		(polygon
			(pts
				(arc
					(start 439.60415 -13.061696)
					(mid 437.82615 -13.061696)
					(end 439.60415 -13.061696)
				)
			)
		)
	)
	(zone
		(layers "In1.Cu" "In3.Cu" "In5.Cu" "In7.Cu" "In8.Cu" "In9.Cu" "In10.Cu"
			"In12.Cu" "In14.Cu" "In16.Cu"
		)
		(hatch none 0.5)
		(connect_pads
			(clearance 0)
		)
		(min_thickness 0.25)
		(keepout
			(tracks not_allowed)
			(vias allowed)
			(pads allowed)
			(copperpour not_allowed)
			(footprints allowed)
		)
		(placement
			(enabled no)
			(sheetname "")
		)
		(fill yes
			(thermal_gap 0.5)
			(thermal_bridge_width 0.5)
			(island_removal_mode 0)
		)
		(polygon
			(pts
				(arc
					(start 195.846446 -354.859844)
					(mid 194.068446 -354.859844)
					(end 195.846446 -354.859844)
				)
			)
		)
	)
	(zone
		(layers "In1.Cu" "In3.Cu" "In5.Cu" "In7.Cu" "In8.Cu" "In9.Cu" "In10.Cu"
			"In12.Cu" "In14.Cu" "In16.Cu"
		)
		(hatch none 0.5)
		(connect_pads
			(clearance 0)
		)
		(min_thickness 0.25)
		(keepout
			(tracks not_allowed)
			(vias allowed)
			(pads allowed)
			(copperpour not_allowed)
			(footprints allowed)
		)
		(placement
			(enabled no)
			(sheetname "")
		)
		(fill yes
			(thermal_gap 0.5)
			(thermal_bridge_width 0.5)
			(island_removal_mode 0)
		)
		(polygon
			(pts
				(arc
					(start 287.90011 -355.949758)
					(mid 286.12211 -355.949758)
					(end 287.90011 -355.949758)
				)
			)
		)
	)
	(zone
		(layers "In1.Cu" "In3.Cu" "In5.Cu" "In7.Cu" "In8.Cu" "In9.Cu" "In10.Cu"
			"In12.Cu" "In14.Cu" "In16.Cu"
		)
		(hatch none 0.5)
		(connect_pads
			(clearance 0)
		)
		(min_thickness 0.25)
		(keepout
			(tracks not_allowed)
			(vias allowed)
			(pads allowed)
			(copperpour not_allowed)
			(footprints allowed)
		)
		(placement
			(enabled no)
			(sheetname "")
		)
		(fill yes
			(thermal_gap 0.5)
			(thermal_bridge_width 0.5)
			(island_removal_mode 0)
		)
		(polygon
			(pts
				(arc
					(start 370.936774 -179.883054)
					(mid 369.158774 -179.883054)
					(end 370.936774 -179.883054)
				)
			)
		)
	)
	(zone
		(layers "In1.Cu" "In3.Cu" "In5.Cu" "In7.Cu" "In8.Cu" "In9.Cu" "In10.Cu"
			"In12.Cu" "In14.Cu" "In16.Cu"
		)
		(hatch none 0.5)
		(connect_pads
			(clearance 0)
		)
		(min_thickness 0.25)
		(keepout
			(tracks not_allowed)
			(vias allowed)
			(pads allowed)
			(copperpour not_allowed)
			(footprints allowed)
		)
		(placement
			(enabled no)
			(sheetname "")
		)
		(fill yes
			(thermal_gap 0.5)
			(thermal_bridge_width 0.5)
			(island_removal_mode 0)
		)
		(polygon
			(pts
				(arc
					(start 64.941704 -347.302328)
					(mid 63.181484 -347.302328)
					(end 64.941704 -347.302328)
				)
			)
		)
	)
	(zone
		(layers "In1.Cu" "In3.Cu" "In5.Cu" "In7.Cu" "In8.Cu" "In9.Cu" "In10.Cu"
			"In12.Cu" "In14.Cu" "In16.Cu"
		)
		(hatch none 0.5)
		(connect_pads
			(clearance 0)
		)
		(min_thickness 0.25)
		(keepout
			(tracks not_allowed)
			(vias allowed)
			(pads allowed)
			(copperpour not_allowed)
			(footprints allowed)
		)
		(placement
			(enabled no)
			(sheetname "")
		)
		(fill yes
			(thermal_gap 0.5)
			(thermal_bridge_width 0.5)
			(island_removal_mode 0)
		)
		(polygon
			(pts
				(arc
					(start 32.11703 -350.318578)
					(mid 30.33903 -350.318578)
					(end 32.11703 -350.318578)
				)
			)
		)
	)
	(zone
		(layers "In1.Cu" "In3.Cu" "In5.Cu" "In7.Cu" "In8.Cu" "In9.Cu" "In10.Cu"
			"In12.Cu" "In14.Cu" "In16.Cu"
		)
		(hatch none 0.5)
		(connect_pads
			(clearance 0)
		)
		(min_thickness 0.25)
		(keepout
			(tracks not_allowed)
			(vias allowed)
			(pads allowed)
			(copperpour not_allowed)
			(footprints allowed)
		)
		(placement
			(enabled no)
			(sheetname "")
		)
		(fill yes
			(thermal_gap 0.5)
			(thermal_bridge_width 0.5)
			(island_removal_mode 0)
		)
		(polygon
			(pts
				(arc
					(start 88.56345 -162.812476)
					(mid 86.78545 -162.812476)
					(end 88.56345 -162.812476)
				)
			)
		)
	)
	(zone
		(layers "In1.Cu" "In3.Cu" "In5.Cu" "In7.Cu" "In8.Cu" "In9.Cu" "In10.Cu"
			"In12.Cu" "In14.Cu" "In16.Cu"
		)
		(hatch none 0.5)
		(connect_pads
			(clearance 0)
		)
		(min_thickness 0.25)
		(keepout
			(tracks not_allowed)
			(vias allowed)
			(pads allowed)
			(copperpour not_allowed)
			(footprints allowed)
		)
		(placement
			(enabled no)
			(sheetname "")
		)
		(fill yes
			(thermal_gap 0.5)
			(thermal_bridge_width 0.5)
			(island_removal_mode 0)
		)
		(polygon
			(pts
				(arc
					(start 294.196516 -348.704662)
					(mid 292.436296 -348.704662)
					(end 294.196516 -348.704662)
				)
			)
		)
	)
	(zone
		(layers "In1.Cu" "In3.Cu" "In5.Cu" "In7.Cu" "In8.Cu" "In9.Cu" "In10.Cu"
			"In12.Cu" "In14.Cu" "In16.Cu"
		)
		(hatch none 0.5)
		(connect_pads
			(clearance 0)
		)
		(min_thickness 0.25)
		(keepout
			(tracks not_allowed)
			(vias allowed)
			(pads allowed)
			(copperpour not_allowed)
			(footprints allowed)
		)
		(placement
			(enabled no)
			(sheetname "")
		)
		(fill yes
			(thermal_gap 0.5)
			(thermal_bridge_width 0.5)
			(island_removal_mode 0)
		)
		(polygon
			(pts
				(arc
					(start 388.182358 -155.089352)
					(mid 386.404358 -155.089352)
					(end 388.182358 -155.089352)
				)
			)
		)
	)
	(zone
		(layers "In1.Cu" "In3.Cu" "In5.Cu" "In7.Cu" "In8.Cu" "In9.Cu" "In10.Cu"
			"In12.Cu" "In14.Cu" "In16.Cu"
		)
		(hatch none 0.5)
		(connect_pads
			(clearance 0)
		)
		(min_thickness 0.25)
		(keepout
			(tracks not_allowed)
			(vias allowed)
			(pads allowed)
			(copperpour not_allowed)
			(footprints allowed)
		)
		(placement
			(enabled no)
			(sheetname "")
		)
		(fill yes
			(thermal_gap 0.5)
			(thermal_bridge_width 0.5)
			(island_removal_mode 0)
		)
		(polygon
			(pts
				(arc
					(start 353.211638 -167.430196)
					(mid 351.433638 -167.430196)
					(end 353.211638 -167.430196)
				)
			)
		)
	)
	(zone
		(layers "In1.Cu" "In3.Cu" "In5.Cu" "In7.Cu" "In8.Cu" "In9.Cu" "In10.Cu"
			"In12.Cu" "In14.Cu" "In16.Cu"
		)
		(hatch none 0.5)
		(connect_pads
			(clearance 0)
		)
		(min_thickness 0.25)
		(keepout
			(tracks not_allowed)
			(vias allowed)
			(pads allowed)
			(copperpour not_allowed)
			(footprints allowed)
		)
		(placement
			(enabled no)
			(sheetname "")
		)
		(fill yes
			(thermal_gap 0.5)
			(thermal_bridge_width 0.5)
			(island_removal_mode 0)
		)
		(polygon
			(pts
				(arc
					(start 331.301344 -338.527136)
					(mid 329.523344 -338.527136)
					(end 331.301344 -338.527136)
				)
			)
		)
	)
	(zone
		(layers "In1.Cu" "In3.Cu" "In5.Cu" "In7.Cu" "In8.Cu" "In9.Cu" "In10.Cu"
			"In12.Cu" "In14.Cu" "In16.Cu"
		)
		(hatch none 0.5)
		(connect_pads
			(clearance 0)
		)
		(min_thickness 0.25)
		(keepout
			(tracks not_allowed)
			(vias allowed)
			(pads allowed)
			(copperpour not_allowed)
			(footprints allowed)
		)
		(placement
			(enabled no)
			(sheetname "")
		)
		(fill yes
			(thermal_gap 0.5)
			(thermal_bridge_width 0.5)
			(island_removal_mode 0)
		)
		(polygon
			(pts
				(arc
					(start 87.90813 -164.097716)
					(mid 86.13013 -164.097716)
					(end 87.90813 -164.097716)
				)
			)
		)
	)
	(zone
		(layers "In1.Cu" "In3.Cu" "In5.Cu" "In7.Cu" "In8.Cu" "In9.Cu" "In10.Cu"
			"In12.Cu" "In14.Cu" "In16.Cu"
		)
		(hatch none 0.5)
		(connect_pads
			(clearance 0)
		)
		(min_thickness 0.25)
		(keepout
			(tracks not_allowed)
			(vias allowed)
			(pads allowed)
			(copperpour not_allowed)
			(footprints allowed)
		)
		(placement
			(enabled no)
			(sheetname "")
		)
		(fill yes
			(thermal_gap 0.5)
			(thermal_bridge_width 0.5)
			(island_removal_mode 0)
		)
		(polygon
			(pts
				(arc
					(start 331.301344 -337.790536)
					(mid 329.523344 -337.790536)
					(end 331.301344 -337.790536)
				)
			)
		)
	)
	(zone
		(layers "In1.Cu" "In3.Cu" "In5.Cu" "In7.Cu" "In8.Cu" "In9.Cu" "In10.Cu"
			"In12.Cu" "In14.Cu" "In16.Cu"
		)
		(hatch none 0.5)
		(connect_pads
			(clearance 0)
		)
		(min_thickness 0.25)
		(keepout
			(tracks not_allowed)
			(vias allowed)
			(pads allowed)
			(copperpour not_allowed)
			(footprints allowed)
		)
		(placement
			(enabled no)
			(sheetname "")
		)
		(fill yes
			(thermal_gap 0.5)
			(thermal_bridge_width 0.5)
			(island_removal_mode 0)
		)
		(polygon
			(pts
				(arc
					(start 90.199464 -336.255868)
					(mid 88.439244 -336.255868)
					(end 90.199464 -336.255868)
				)
			)
		)
	)
	(zone
		(layers "In1.Cu" "In3.Cu" "In5.Cu" "In7.Cu" "In8.Cu" "In9.Cu" "In10.Cu"
			"In12.Cu" "In14.Cu" "In16.Cu"
		)
		(hatch none 0.5)
		(connect_pads
			(clearance 0)
		)
		(min_thickness 0.25)
		(keepout
			(tracks not_allowed)
			(vias allowed)
			(pads allowed)
			(copperpour not_allowed)
			(footprints allowed)
		)
		(placement
			(enabled no)
			(sheetname "")
		)
		(fill yes
			(thermal_gap 0.5)
			(thermal_bridge_width 0.5)
			(island_removal_mode 0)
		)
		(polygon
			(pts
				(arc
					(start 99.636834 -338.974684)
					(mid 97.858834 -338.974684)
					(end 99.636834 -338.974684)
				)
			)
		)
	)
	(zone
		(layers "In1.Cu" "In3.Cu" "In5.Cu" "In7.Cu" "In8.Cu" "In9.Cu" "In10.Cu"
			"In12.Cu" "In14.Cu" "In16.Cu"
		)
		(hatch none 0.5)
		(connect_pads
			(clearance 0)
		)
		(min_thickness 0.25)
		(keepout
			(tracks not_allowed)
			(vias allowed)
			(pads allowed)
			(copperpour not_allowed)
			(footprints allowed)
		)
		(placement
			(enabled no)
			(sheetname "")
		)
		(fill yes
			(thermal_gap 0.5)
			(thermal_bridge_width 0.5)
			(island_removal_mode 0)
		)
		(polygon
			(pts
				(arc
					(start 372.23954 -180.803804)
					(mid 370.47932 -180.803804)
					(end 372.23954 -180.803804)
				)
			)
		)
	)
	(zone
		(layers "In1.Cu" "In3.Cu" "In5.Cu" "In7.Cu" "In8.Cu" "In9.Cu" "In10.Cu"
			"In12.Cu" "In14.Cu" "In16.Cu"
		)
		(hatch none 0.5)
		(connect_pads
			(clearance 0)
		)
		(min_thickness 0.25)
		(keepout
			(tracks not_allowed)
			(vias allowed)
			(pads allowed)
			(copperpour not_allowed)
			(footprints allowed)
		)
		(placement
			(enabled no)
			(sheetname "")
		)
		(fill yes
			(thermal_gap 0.5)
			(thermal_bridge_width 0.5)
			(island_removal_mode 0)
		)
		(polygon
			(pts
				(arc
					(start 113.947194 -169.062654)
					(mid 112.169194 -169.062654)
					(end 113.947194 -169.062654)
				)
			)
		)
	)
	(zone
		(layers "In1.Cu" "In3.Cu" "In5.Cu" "In7.Cu" "In8.Cu" "In9.Cu" "In10.Cu"
			"In12.Cu" "In14.Cu" "In16.Cu"
		)
		(hatch none 0.5)
		(connect_pads
			(clearance 0)
		)
		(min_thickness 0.25)
		(keepout
			(tracks not_allowed)
			(vias allowed)
			(pads allowed)
			(copperpour not_allowed)
			(footprints allowed)
		)
		(placement
			(enabled no)
			(sheetname "")
		)
		(fill yes
			(thermal_gap 0.5)
			(thermal_bridge_width 0.5)
			(island_removal_mode 0)
		)
		(polygon
			(pts
				(arc
					(start 105.300272 -341.927688)
					(mid 103.540052 -341.927688)
					(end 105.300272 -341.927688)
				)
			)
		)
	)
	(zone
		(layers "In1.Cu" "In3.Cu" "In5.Cu" "In7.Cu" "In8.Cu" "In9.Cu" "In10.Cu"
			"In12.Cu" "In14.Cu" "In16.Cu"
		)
		(hatch none 0.5)
		(connect_pads
			(clearance 0)
		)
		(min_thickness 0.25)
		(keepout
			(tracks not_allowed)
			(vias allowed)
			(pads allowed)
			(copperpour not_allowed)
			(footprints allowed)
		)
		(placement
			(enabled no)
			(sheetname "")
		)
		(fill yes
			(thermal_gap 0.5)
			(thermal_bridge_width 0.5)
			(island_removal_mode 0)
		)
		(polygon
			(pts
				(arc
					(start 89.81313 -164.097716)
					(mid 88.03513 -164.097716)
					(end 89.81313 -164.097716)
				)
			)
		)
	)
	(zone
		(layers "In1.Cu" "In3.Cu" "In5.Cu" "In7.Cu" "In8.Cu" "In9.Cu" "In10.Cu"
			"In12.Cu" "In14.Cu" "In16.Cu"
		)
		(hatch none 0.5)
		(connect_pads
			(clearance 0)
		)
		(min_thickness 0.25)
		(keepout
			(tracks not_allowed)
			(vias allowed)
			(pads allowed)
			(copperpour not_allowed)
			(footprints allowed)
		)
		(placement
			(enabled no)
			(sheetname "")
		)
		(fill yes
			(thermal_gap 0.5)
			(thermal_bridge_width 0.5)
			(island_removal_mode 0)
		)
		(polygon
			(pts
				(arc
					(start 114.480848 -171.33316)
					(mid 112.702848 -171.33316)
					(end 114.480848 -171.33316)
				)
			)
		)
	)
	(zone
		(layers "In1.Cu" "In3.Cu" "In5.Cu" "In7.Cu" "In8.Cu" "In9.Cu" "In10.Cu"
			"In12.Cu" "In14.Cu" "In16.Cu"
		)
		(hatch none 0.5)
		(connect_pads
			(clearance 0)
		)
		(min_thickness 0.25)
		(keepout
			(tracks not_allowed)
			(vias allowed)
			(pads allowed)
			(copperpour not_allowed)
			(footprints allowed)
		)
		(placement
			(enabled no)
			(sheetname "")
		)
		(fill yes
			(thermal_gap 0.5)
			(thermal_bridge_width 0.5)
			(island_removal_mode 0)
		)
		(polygon
			(pts
				(arc
					(start 66.474594 -348.786958)
					(mid 64.696594 -348.786958)
					(end 66.474594 -348.786958)
				)
			)
		)
	)
	(zone
		(layers "In1.Cu" "In3.Cu" "In5.Cu" "In7.Cu" "In8.Cu" "In9.Cu" "In10.Cu"
			"In12.Cu" "In14.Cu" "In16.Cu"
		)
		(hatch none 0.5)
		(connect_pads
			(clearance 0)
		)
		(min_thickness 0.25)
		(keepout
			(tracks not_allowed)
			(vias allowed)
			(pads allowed)
			(copperpour not_allowed)
			(footprints allowed)
		)
		(placement
			(enabled no)
			(sheetname "")
		)
		(fill yes
			(thermal_gap 0.5)
			(thermal_bridge_width 0.5)
			(island_removal_mode 0)
		)
		(polygon
			(pts
				(arc
					(start 193.07683 -362.430568)
					(mid 190.28283 -362.430568)
					(end 193.07683 -362.430568)
				)
			)
		)
	)
	(zone
		(layers "In1.Cu" "In3.Cu" "In5.Cu" "In7.Cu" "In8.Cu" "In9.Cu" "In10.Cu"
			"In12.Cu" "In14.Cu" "In16.Cu"
		)
		(hatch none 0.5)
		(connect_pads
			(clearance 0)
		)
		(min_thickness 0.25)
		(keepout
			(tracks not_allowed)
			(vias allowed)
			(pads allowed)
			(copperpour not_allowed)
			(footprints allowed)
		)
		(placement
			(enabled no)
			(sheetname "")
		)
		(fill yes
			(thermal_gap 0.5)
			(thermal_bridge_width 0.5)
			(island_removal_mode 0)
		)
		(polygon
			(pts
				(arc
					(start 353.211638 -165.956996)
					(mid 351.433638 -165.956996)
					(end 353.211638 -165.956996)
				)
			)
		)
	)
	(zone
		(layers "In1.Cu" "In3.Cu" "In5.Cu" "In7.Cu" "In10.Cu" "In12.Cu" "In14.Cu"
			"In16.Cu"
		)
		(hatch none 0.5)
		(connect_pads
			(clearance 0)
		)
		(min_thickness 0.25)
		(keepout
			(tracks not_allowed)
			(vias allowed)
			(pads allowed)
			(copperpour not_allowed)
			(footprints allowed)
		)
		(placement
			(enabled no)
			(sheetname "")
		)
		(fill yes
			(thermal_gap 0.5)
			(thermal_bridge_width 0.5)
			(island_removal_mode 0)
		)
		(polygon
			(pts
				(arc
					(start 102.099618 -414.277302)
					(mid 102.135539 -414.292181)
					(end 102.150418 -414.328102)
				)
				(arc
					(start 102.150418 -421.122094)
					(mid 102.135539 -421.158015)
					(end 102.099618 -421.172894)
				)
				(arc
					(start 97.200974 -421.172894)
					(mid 97.165053 -421.158015)
					(end 97.150174 -421.122094)
				)
				(arc
					(start 97.150174 -414.328102)
					(mid 97.165053 -414.292181)
					(end 97.200974 -414.277302)
				)
			)
		)
	)
	(zone
		(layers "In1.Cu" "In3.Cu" "In5.Cu" "In7.Cu" "In12.Cu" "In14.Cu")
		(hatch none 0.5)
		(connect_pads
			(clearance 0)
		)
		(min_thickness 0.25)
		(keepout
			(tracks not_allowed)
			(vias allowed)
			(pads allowed)
			(copperpour not_allowed)
			(footprints allowed)
		)
		(placement
			(enabled no)
			(sheetname "")
		)
		(fill yes
			(thermal_gap 0.5)
			(thermal_bridge_width 0.5)
			(island_removal_mode 0)
		)
		(polygon
			(pts
				(arc
					(start 314.73648 -394.552424)
					(mid 314.846451 -394.653478)
					(end 314.991242 -394.690092)
				)
				(arc
					(start 314.991242 -394.690092)
					(mid 315.206768 -394.600818)
					(end 315.296042 -394.385292)
				)
				(arc
					(start 315.296042 -394.385292)
					(mid 315.285705 -394.306553)
					(end 315.255402 -394.233146)
				)
				(arc
					(start 314.862972 -393.554204)
					(mid 314.750575 -393.432587)
					(end 314.591192 -393.38758)
				)
				(arc
					(start 314.591192 -393.38758)
					(mid 314.375666 -393.476854)
					(end 314.286392 -393.69238)
				)
				(arc
					(start 314.286392 -393.69238)
					(mid 314.29597 -393.768442)
					(end 314.324238 -393.8397)
				)
				(xy 314.721494 -394.527024) (xy 314.733686 -394.54836) (xy 314.736226 -394.552678)
			)
		)
	)
	(zone
		(layers "In1.Cu" "In3.Cu" "In5.Cu" "In7.Cu" "In12.Cu" "In14.Cu")
		(hatch none 0.5)
		(connect_pads
			(clearance 0)
		)
		(min_thickness 0.25)
		(keepout
			(tracks not_allowed)
			(vias allowed)
			(pads allowed)
			(copperpour not_allowed)
			(footprints allowed)
		)
		(placement
			(enabled no)
			(sheetname "")
		)
		(fill yes
			(thermal_gap 0.5)
			(thermal_bridge_width 0.5)
			(island_removal_mode 0)
		)
		(polygon
			(pts
				(arc
					(start 317.136526 -394.552424)
					(mid 317.246497 -394.653478)
					(end 317.391288 -394.690092)
				)
				(arc
					(start 317.391288 -394.690092)
					(mid 317.606814 -394.600818)
					(end 317.696088 -394.385292)
				)
				(arc
					(start 317.696088 -394.385292)
					(mid 317.685751 -394.306553)
					(end 317.655448 -394.233146)
				)
				(arc
					(start 317.263018 -393.554204)
					(mid 317.150621 -393.432587)
					(end 316.991238 -393.38758)
				)
				(arc
					(start 316.991238 -393.38758)
					(mid 316.775712 -393.476854)
					(end 316.686438 -393.69238)
				)
				(arc
					(start 316.686438 -393.69238)
					(mid 316.696016 -393.768442)
					(end 316.724284 -393.8397)
				)
				(xy 317.12154 -394.527024) (xy 317.133732 -394.54836) (xy 317.136272 -394.552678)
			)
		)
	)
	(zone
		(layers "In1.Cu" "In3.Cu" "In5.Cu" "In7.Cu" "In12.Cu" "In14.Cu" "In16.Cu")
		(hatch none 0.5)
		(connect_pads
			(clearance 0)
		)
		(min_thickness 0.25)
		(keepout
			(tracks not_allowed)
			(vias allowed)
			(pads allowed)
			(copperpour not_allowed)
			(footprints allowed)
		)
		(placement
			(enabled no)
			(sheetname "")
		)
		(fill yes
			(thermal_gap 0.5)
			(thermal_bridge_width 0.5)
			(island_removal_mode 0)
		)
		(polygon
			(pts
				(arc
					(start 319.536572 -394.552424)
					(mid 319.646543 -394.653478)
					(end 319.791334 -394.690092)
				)
				(arc
					(start 319.791334 -394.690092)
					(mid 320.00686 -394.600818)
					(end 320.096134 -394.385292)
				)
				(arc
					(start 320.096134 -394.385292)
					(mid 320.085797 -394.306553)
					(end 320.055494 -394.233146)
				)
				(arc
					(start 319.663064 -393.554204)
					(mid 319.550667 -393.432587)
					(end 319.391284 -393.38758)
				)
				(arc
					(start 319.391284 -393.38758)
					(mid 319.175758 -393.476854)
					(end 319.086484 -393.69238)
				)
				(arc
					(start 319.086484 -393.69238)
					(mid 319.096062 -393.768442)
					(end 319.12433 -393.8397)
				)
				(xy 319.521586 -394.527024) (xy 319.533778 -394.54836) (xy 319.536318 -394.552678)
			)
		)
	)
	(zone
		(layers "In1.Cu" "In5.Cu" "In7.Cu" "In10.Cu" "In12.Cu" "In14.Cu")
		(hatch none 0.5)
		(connect_pads
			(clearance 0)
		)
		(min_thickness 0.25)
		(keepout
			(tracks not_allowed)
			(vias allowed)
			(pads allowed)
			(copperpour not_allowed)
			(footprints allowed)
		)
		(placement
			(enabled no)
			(sheetname "")
		)
		(fill yes
			(thermal_gap 0.5)
			(thermal_bridge_width 0.5)
			(island_removal_mode 0)
		)
		(polygon
			(pts
				(arc
					(start 313.536584 -394.552424)
					(mid 313.646555 -394.653478)
					(end 313.791346 -394.690092)
				)
				(arc
					(start 313.791346 -394.690092)
					(mid 314.006872 -394.600818)
					(end 314.096146 -394.385292)
				)
				(arc
					(start 314.096146 -394.385292)
					(mid 314.085809 -394.306553)
					(end 314.055506 -394.233146)
				)
				(arc
					(start 313.663076 -393.554204)
					(mid 313.550679 -393.432587)
					(end 313.391296 -393.38758)
				)
				(arc
					(start 313.391296 -393.38758)
					(mid 313.17577 -393.476854)
					(end 313.086496 -393.69238)
				)
				(arc
					(start 313.086496 -393.69238)
					(mid 313.096074 -393.768442)
					(end 313.124342 -393.8397)
				)
				(xy 313.521598 -394.527024) (xy 313.53379 -394.54836) (xy 313.53633 -394.552678)
			)
		)
	)
	(zone
		(layers "In1.Cu" "In5.Cu" "In7.Cu" "In10.Cu" "In12.Cu" "In14.Cu" "In16.Cu")
		(hatch none 0.5)
		(connect_pads
			(clearance 0)
		)
		(min_thickness 0.25)
		(keepout
			(tracks not_allowed)
			(vias allowed)
			(pads allowed)
			(copperpour not_allowed)
			(footprints allowed)
		)
		(placement
			(enabled no)
			(sheetname "")
		)
		(fill yes
			(thermal_gap 0.5)
			(thermal_bridge_width 0.5)
			(island_removal_mode 0)
		)
		(polygon
			(pts
				(arc
					(start 61.136784 -386.170424)
					(mid 61.246755 -386.271478)
					(end 61.391546 -386.308092)
				)
				(arc
					(start 61.391546 -386.308092)
					(mid 61.607072 -386.218818)
					(end 61.696346 -386.003292)
				)
				(arc
					(start 61.696346 -386.003292)
					(mid 61.686009 -385.924553)
					(end 61.655706 -385.851146)
				)
				(arc
					(start 61.263276 -385.172204)
					(mid 61.150879 -385.050587)
					(end 60.991496 -385.00558)
				)
				(arc
					(start 60.991496 -385.00558)
					(mid 60.77597 -385.094854)
					(end 60.686696 -385.31038)
				)
				(arc
					(start 60.686696 -385.31038)
					(mid 60.696274 -385.386442)
					(end 60.724542 -385.4577)
				)
				(xy 61.121798 -386.145024) (xy 61.13399 -386.16636) (xy 61.13653 -386.170678)
			)
		)
	)
	(zone
		(layers "In1.Cu" "In5.Cu" "In7.Cu" "In10.Cu" "In12.Cu" "In14.Cu" "In16.Cu")
		(hatch none 0.5)
		(connect_pads
			(clearance 0)
		)
		(min_thickness 0.25)
		(keepout
			(tracks not_allowed)
			(vias allowed)
			(pads allowed)
			(copperpour not_allowed)
			(footprints allowed)
		)
		(placement
			(enabled no)
			(sheetname "")
		)
		(fill yes
			(thermal_gap 0.5)
			(thermal_bridge_width 0.5)
			(island_removal_mode 0)
		)
		(polygon
			(pts
				(arc
					(start 63.53683 -386.170424)
					(mid 63.646801 -386.271478)
					(end 63.791592 -386.308092)
				)
				(arc
					(start 63.791592 -386.308092)
					(mid 64.007118 -386.218818)
					(end 64.096392 -386.003292)
				)
				(arc
					(start 64.096392 -386.003292)
					(mid 64.086055 -385.924553)
					(end 64.055752 -385.851146)
				)
				(arc
					(start 63.663322 -385.172204)
					(mid 63.550925 -385.050587)
					(end 63.391542 -385.00558)
				)
				(arc
					(start 63.391542 -385.00558)
					(mid 63.176016 -385.094854)
					(end 63.086742 -385.31038)
				)
				(arc
					(start 63.086742 -385.31038)
					(mid 63.09632 -385.386442)
					(end 63.124588 -385.4577)
				)
				(xy 63.521844 -386.145024) (xy 63.534036 -386.16636) (xy 63.536576 -386.170678)
			)
		)
	)
	(zone
		(layers "In1.Cu" "In5.Cu" "In7.Cu" "In10.Cu" "In12.Cu" "In14.Cu" "In16.Cu")
		(hatch none 0.5)
		(connect_pads
			(clearance 0)
		)
		(min_thickness 0.25)
		(keepout
			(tracks not_allowed)
			(vias allowed)
			(pads allowed)
			(copperpour not_allowed)
			(footprints allowed)
		)
		(placement
			(enabled no)
			(sheetname "")
		)
		(fill yes
			(thermal_gap 0.5)
			(thermal_bridge_width 0.5)
			(island_removal_mode 0)
		)
		(polygon
			(pts
				(arc
					(start 64.736726 -386.170424)
					(mid 64.846697 -386.271478)
					(end 64.991488 -386.308092)
				)
				(arc
					(start 64.991488 -386.308092)
					(mid 65.207014 -386.218818)
					(end 65.296288 -386.003292)
				)
				(arc
					(start 65.296288 -386.003292)
					(mid 65.285951 -385.924553)
					(end 65.255648 -385.851146)
				)
				(arc
					(start 64.863218 -385.172204)
					(mid 64.750821 -385.050587)
					(end 64.591438 -385.00558)
				)
				(arc
					(start 64.591438 -385.00558)
					(mid 64.375912 -385.094854)
					(end 64.286638 -385.31038)
				)
				(arc
					(start 64.286638 -385.31038)
					(mid 64.296216 -385.386442)
					(end 64.324484 -385.4577)
				)
				(xy 64.72174 -386.145024) (xy 64.733932 -386.16636) (xy 64.736472 -386.170678)
			)
		)
	)
	(zone
		(layers "In1.Cu" "In5.Cu" "In7.Cu" "In10.Cu" "In12.Cu" "In14.Cu" "In16.Cu")
		(hatch none 0.5)
		(connect_pads
			(clearance 0)
		)
		(min_thickness 0.25)
		(keepout
			(tracks not_allowed)
			(vias allowed)
			(pads allowed)
			(copperpour not_allowed)
			(footprints allowed)
		)
		(placement
			(enabled no)
			(sheetname "")
		)
		(fill yes
			(thermal_gap 0.5)
			(thermal_bridge_width 0.5)
			(island_removal_mode 0)
		)
		(polygon
			(pts
				(arc
					(start 58.736738 -386.170424)
					(mid 58.846709 -386.271478)
					(end 58.9915 -386.308092)
				)
				(arc
					(start 58.9915 -386.308092)
					(mid 59.207026 -386.218818)
					(end 59.2963 -386.003292)
				)
				(arc
					(start 59.2963 -386.003292)
					(mid 59.285963 -385.924553)
					(end 59.25566 -385.851146)
				)
				(arc
					(start 58.86323 -385.172204)
					(mid 58.750833 -385.050587)
					(end 58.59145 -385.00558)
				)
				(arc
					(start 58.59145 -385.00558)
					(mid 58.375924 -385.094854)
					(end 58.28665 -385.31038)
				)
				(arc
					(start 58.28665 -385.31038)
					(mid 58.296228 -385.386442)
					(end 58.324496 -385.4577)
				)
				(xy 58.721752 -386.145024) (xy 58.733944 -386.16636) (xy 58.736484 -386.170678)
			)
		)
	)
	(zone
		(layers "In1.Cu" "In5.Cu" "In7.Cu" "In10.Cu" "In12.Cu" "In14.Cu" "In16.Cu")
		(hatch none 0.5)
		(connect_pads
			(clearance 0)
		)
		(min_thickness 0.25)
		(keepout
			(tracks not_allowed)
			(vias allowed)
			(pads allowed)
			(copperpour not_allowed)
			(footprints allowed)
		)
		(placement
			(enabled no)
			(sheetname "")
		)
		(fill yes
			(thermal_gap 0.5)
			(thermal_bridge_width 0.5)
			(island_removal_mode 0)
		)
		(polygon
			(pts
				(arc
					(start 57.536842 -386.170424)
					(mid 57.646813 -386.271478)
					(end 57.791604 -386.308092)
				)
				(arc
					(start 57.791604 -386.308092)
					(mid 58.00713 -386.218818)
					(end 58.096404 -386.003292)
				)
				(arc
					(start 58.096404 -386.003292)
					(mid 58.086067 -385.924553)
					(end 58.055764 -385.851146)
				)
				(arc
					(start 57.663334 -385.172204)
					(mid 57.550937 -385.050587)
					(end 57.391554 -385.00558)
				)
				(arc
					(start 57.391554 -385.00558)
					(mid 57.176028 -385.094854)
					(end 57.086754 -385.31038)
				)
				(arc
					(start 57.086754 -385.31038)
					(mid 57.096332 -385.386442)
					(end 57.1246 -385.4577)
				)
				(xy 57.521856 -386.145024) (xy 57.534048 -386.16636) (xy 57.536588 -386.170678)
			)
		)
	)
	(zone
		(layers "In1.Cu" "In5.Cu" "In7.Cu" "In10.Cu" "In12.Cu" "In14.Cu" "In16.Cu")
		(hatch none 0.5)
		(connect_pads
			(clearance 0)
		)
		(min_thickness 0.25)
		(keepout
			(tracks not_allowed)
			(vias allowed)
			(pads allowed)
			(copperpour not_allowed)
			(footprints allowed)
		)
		(placement
			(enabled no)
			(sheetname "")
		)
		(fill yes
			(thermal_gap 0.5)
			(thermal_bridge_width 0.5)
			(island_removal_mode 0)
		)
		(polygon
			(pts
				(arc
					(start 62.33668 -386.170424)
					(mid 62.446651 -386.271478)
					(end 62.591442 -386.308092)
				)
				(arc
					(start 62.591442 -386.308092)
					(mid 62.806968 -386.218818)
					(end 62.896242 -386.003292)
				)
				(arc
					(start 62.896242 -386.003292)
					(mid 62.885905 -385.924553)
					(end 62.855602 -385.851146)
				)
				(arc
					(start 62.463172 -385.172204)
					(mid 62.350775 -385.050587)
					(end 62.191392 -385.00558)
				)
				(arc
					(start 62.191392 -385.00558)
					(mid 61.975866 -385.094854)
					(end 61.886592 -385.31038)
				)
				(arc
					(start 61.886592 -385.31038)
					(mid 61.89617 -385.386442)
					(end 61.924438 -385.4577)
				)
				(xy 62.321694 -386.145024) (xy 62.333886 -386.16636) (xy 62.336426 -386.170678)
			)
		)
	)
	(zone
		(layers "In1.Cu" "In5.Cu" "In7.Cu" "In10.Cu" "In14.Cu" "In16.Cu")
		(hatch none 0.5)
		(connect_pads
			(clearance 0)
		)
		(min_thickness 0.25)
		(keepout
			(tracks not_allowed)
			(vias allowed)
			(pads allowed)
			(copperpour not_allowed)
			(footprints allowed)
		)
		(placement
			(enabled no)
			(sheetname "")
		)
		(fill yes
			(thermal_gap 0.5)
			(thermal_bridge_width 0.5)
			(island_removal_mode 0)
		)
		(polygon
			(pts
				(arc
					(start 59.936888 -386.170424)
					(mid 60.046859 -386.271478)
					(end 60.19165 -386.308092)
				)
				(arc
					(start 60.19165 -386.308092)
					(mid 60.407176 -386.218818)
					(end 60.49645 -386.003292)
				)
				(arc
					(start 60.49645 -386.003292)
					(mid 60.486113 -385.924553)
					(end 60.45581 -385.851146)
				)
				(arc
					(start 60.06338 -385.172204)
					(mid 59.950983 -385.050587)
					(end 59.7916 -385.00558)
				)
				(arc
					(start 59.7916 -385.00558)
					(mid 59.576074 -385.094854)
					(end 59.4868 -385.31038)
				)
				(arc
					(start 59.4868 -385.31038)
					(mid 59.496378 -385.386442)
					(end 59.524646 -385.4577)
				)
				(xy 59.921902 -386.145024) (xy 59.934094 -386.16636) (xy 59.936634 -386.170678)
			)
		)
	)
	(zone
		(layers "In1.Cu" "In5.Cu" "In7.Cu" "In10.Cu" "In14.Cu" "In16.Cu")
		(hatch none 0.5)
		(connect_pads
			(clearance 0)
		)
		(min_thickness 0.25)
		(keepout
			(tracks not_allowed)
			(vias allowed)
			(pads allowed)
			(copperpour not_allowed)
			(footprints allowed)
		)
		(placement
			(enabled no)
			(sheetname "")
		)
		(fill yes
			(thermal_gap 0.5)
			(thermal_bridge_width 0.5)
			(island_removal_mode 0)
		)
		(polygon
			(pts
				(arc
					(start 65.936876 -386.170424)
					(mid 66.046847 -386.271478)
					(end 66.191638 -386.308092)
				)
				(arc
					(start 66.191638 -386.308092)
					(mid 66.407164 -386.218818)
					(end 66.496438 -386.003292)
				)
				(arc
					(start 66.496438 -386.003292)
					(mid 66.486101 -385.924553)
					(end 66.455798 -385.851146)
				)
				(arc
					(start 66.063368 -385.172204)
					(mid 65.950971 -385.050587)
					(end 65.791588 -385.00558)
				)
				(arc
					(start 65.791588 -385.00558)
					(mid 65.576062 -385.094854)
					(end 65.486788 -385.31038)
				)
				(arc
					(start 65.486788 -385.31038)
					(mid 65.496366 -385.386442)
					(end 65.524634 -385.4577)
				)
				(xy 65.92189 -386.145024) (xy 65.934082 -386.16636) (xy 65.936622 -386.170678)
			)
		)
	)
	(zone
		(layer "In2.Cu")
		(hatch none 0.5)
		(connect_pads
			(clearance 0)
		)
		(min_thickness 0.25)
		(keepout
			(tracks not_allowed)
			(vias allowed)
			(pads allowed)
			(copperpour not_allowed)
			(footprints allowed)
		)
		(placement
			(enabled no)
			(sheetname "")
		)
		(fill
			(thermal_gap 0.5)
			(thermal_bridge_width 0.5)
			(island_removal_mode 0)
		)
		(polygon
			(pts
				(xy 411.618684 -254.025146) (xy 413.117284 -254.025146) (xy 413.117284 -254.545084) (xy 411.618684 -254.545084)
			)
		)
	)
	(zone
		(layer "In2.Cu")
		(hatch none 0.5)
		(connect_pads
			(clearance 0)
		)
		(min_thickness 0.25)
		(keepout
			(tracks not_allowed)
			(vias allowed)
			(pads allowed)
			(copperpour not_allowed)
			(footprints allowed)
		)
		(placement
			(enabled no)
			(sheetname "")
		)
		(fill
			(thermal_gap 0.5)
			(thermal_bridge_width 0.5)
			(island_removal_mode 0)
		)
		(polygon
			(pts
				(xy 171.22267 -239.57534) (xy 172.72127 -239.57534) (xy 172.72127 -240.095278) (xy 171.22267 -240.095278)
			)
		)
	)
	(zone
		(layer "In2.Cu")
		(hatch none 0.5)
		(connect_pads
			(clearance 0)
		)
		(min_thickness 0.25)
		(keepout
			(tracks not_allowed)
			(vias allowed)
			(pads allowed)
			(copperpour not_allowed)
			(footprints allowed)
		)
		(placement
			(enabled no)
			(sheetname "")
		)
		(fill
			(thermal_gap 0.5)
			(thermal_bridge_width 0.5)
			(island_removal_mode 0)
		)
		(polygon
			(pts
				(xy 449.3387 -285.475172) (xy 450.8373 -285.475172) (xy 450.8373 -285.99511) (xy 449.3387 -285.99511)
			)
		)
	)
	(zone
		(layer "In2.Cu")
		(hatch none 0.5)
		(connect_pads
			(clearance 0)
		)
		(min_thickness 0.25)
		(keepout
			(tracks not_allowed)
			(vias allowed)
			(pads allowed)
			(copperpour not_allowed)
			(footprints allowed)
		)
		(placement
			(enabled no)
			(sheetname "")
		)
		(fill
			(thermal_gap 0.5)
			(thermal_bridge_width 0.5)
			(island_removal_mode 0)
		)
		(polygon
			(pts
				(xy 445.894968 -264.225278) (xy 447.393568 -264.225278) (xy 447.393568 -264.745216) (xy 445.894968 -264.745216)
			)
		)
	)
	(zone
		(layer "In2.Cu")
		(hatch none 0.5)
		(connect_pads
			(clearance 0)
		)
		(min_thickness 0.25)
		(keepout
			(tracks not_allowed)
			(vias allowed)
			(pads allowed)
			(copperpour not_allowed)
			(footprints allowed)
		)
		(placement
			(enabled no)
			(sheetname "")
		)
		(fill
			(thermal_gap 0.5)
			(thermal_bridge_width 0.5)
			(island_removal_mode 0)
		)
		(polygon
			(pts
				(xy 449.3387 -302.475138) (xy 450.8373 -302.475138) (xy 450.8373 -302.995076) (xy 449.3387 -302.995076)
			)
		)
	)
	(zone
		(layer "In2.Cu")
		(hatch none 0.5)
		(connect_pads
			(clearance 0)
		)
		(min_thickness 0.25)
		(keepout
			(tracks not_allowed)
			(vias allowed)
			(pads allowed)
			(copperpour not_allowed)
			(footprints allowed)
		)
		(placement
			(enabled no)
			(sheetname "")
		)
		(fill
			(thermal_gap 0.5)
			(thermal_bridge_width 0.5)
			(island_removal_mode 0)
		)
		(polygon
			(pts
				(xy 193.854578 -225.975164) (xy 195.353178 -225.975164) (xy 195.353178 -226.495102) (xy 193.854578 -226.495102)
			)
		)
	)
	(zone
		(layer "In2.Cu")
		(hatch none 0.5)
		(connect_pads
			(clearance 0)
		)
		(min_thickness 0.25)
		(keepout
			(tracks not_allowed)
			(vias allowed)
			(pads allowed)
			(copperpour not_allowed)
			(footprints allowed)
		)
		(placement
			(enabled no)
			(sheetname "")
		)
		(fill
			(thermal_gap 0.5)
			(thermal_bridge_width 0.5)
			(island_removal_mode 0)
		)
		(polygon
			(pts
				(xy 28.50261 -197.075298) (xy 30.00121 -197.075298) (xy 30.00121 -197.595236) (xy 28.50261 -197.595236)
			)
		)
	)
	(zone
		(layer "In2.Cu")
		(hatch none 0.5)
		(connect_pads
			(clearance 0)
		)
		(min_thickness 0.25)
		(keepout
			(tracks not_allowed)
			(vias allowed)
			(pads allowed)
			(copperpour not_allowed)
			(footprints allowed)
		)
		(placement
			(enabled no)
			(sheetname "")
		)
		(fill
			(thermal_gap 0.5)
			(thermal_bridge_width 0.5)
			(island_removal_mode 0)
		)
		(polygon
			(pts
				(xy 201.398632 -229.375208) (xy 202.897232 -229.375208) (xy 202.897232 -229.895146) (xy 201.398632 -229.895146)
			)
		)
	)
	(zone
		(layer "In2.Cu")
		(hatch none 0.5)
		(connect_pads
			(clearance 0)
		)
		(min_thickness 0.25)
		(keepout
			(tracks not_allowed)
			(vias allowed)
			(pads allowed)
			(copperpour not_allowed)
			(footprints allowed)
		)
		(placement
			(enabled no)
			(sheetname "")
		)
		(fill
			(thermal_gap 0.5)
			(thermal_bridge_width 0.5)
			(island_removal_mode 0)
		)
		(polygon
			(pts
				(xy 287.430718 -207.275176) (xy 288.929318 -207.275176) (xy 288.929318 -207.795114) (xy 287.430718 -207.795114)
			)
		)
	)
	(zone
		(layer "In2.Cu")
		(hatch none 0.5)
		(connect_pads
			(clearance 0)
		)
		(min_thickness 0.25)
		(keepout
			(tracks not_allowed)
			(vias allowed)
			(pads allowed)
			(copperpour not_allowed)
			(footprints allowed)
		)
		(placement
			(enabled no)
			(sheetname "")
		)
		(fill
			(thermal_gap 0.5)
			(thermal_bridge_width 0.5)
			(island_removal_mode 0)
		)
		(polygon
			(pts
				(xy 186.310778 -280.375106) (xy 187.809378 -280.375106) (xy 187.809378 -280.895044) (xy 186.310778 -280.895044)
			)
		)
	)
	(zone
		(layer "In2.Cu")
		(hatch none 0.5)
		(connect_pads
			(clearance 0)
		)
		(min_thickness 0.25)
		(keepout
			(tracks not_allowed)
			(vias allowed)
			(pads allowed)
			(copperpour not_allowed)
			(footprints allowed)
		)
		(placement
			(enabled no)
			(sheetname "")
		)
		(fill
			(thermal_gap 0.5)
			(thermal_bridge_width 0.5)
			(island_removal_mode 0)
		)
		(polygon
			(pts
				(xy 51.134772 -294.825166) (xy 52.633372 -294.825166) (xy 52.633372 -295.345104) (xy 51.134772 -295.345104)
			)
		)
	)
	(zone
		(layer "In2.Cu")
		(hatch none 0.5)
		(connect_pads
			(clearance 0)
		)
		(min_thickness 0.25)
		(keepout
			(tracks not_allowed)
			(vias allowed)
			(pads allowed)
			(copperpour not_allowed)
			(footprints allowed)
		)
		(placement
			(enabled no)
			(sheetname "")
		)
		(fill
			(thermal_gap 0.5)
			(thermal_bridge_width 0.5)
			(island_removal_mode 0)
		)
		(polygon
			(pts
				(xy 419.162738 -304.17516) (xy 420.661338 -304.17516) (xy 420.661338 -304.695098) (xy 419.162738 -304.695098)
			)
		)
	)
	(zone
		(layer "In2.Cu")
		(hatch none 0.5)
		(connect_pads
			(clearance 0)
		)
		(min_thickness 0.25)
		(keepout
			(tracks not_allowed)
			(vias allowed)
			(pads allowed)
			(copperpour not_allowed)
			(footprints allowed)
		)
		(placement
			(enabled no)
			(sheetname "")
		)
		(fill
			(thermal_gap 0.5)
			(thermal_bridge_width 0.5)
			(island_removal_mode 0)
		)
		(polygon
			(pts
				(xy 287.430718 -282.075128) (xy 288.929318 -282.075128) (xy 288.929318 -282.595066) (xy 287.430718 -282.595066)
			)
		)
	)
	(zone
		(layer "In2.Cu")
		(hatch none 0.5)
		(connect_pads
			(clearance 0)
		)
		(min_thickness 0.25)
		(keepout
			(tracks not_allowed)
			(vias allowed)
			(pads allowed)
			(copperpour not_allowed)
			(footprints allowed)
		)
		(placement
			(enabled no)
			(sheetname "")
		)
		(fill
			(thermal_gap 0.5)
			(thermal_bridge_width 0.5)
			(island_removal_mode 0)
		)
		(polygon
			(pts
				(xy 426.706792 -205.575154) (xy 428.205392 -205.575154) (xy 428.205392 -206.095092) (xy 426.706792 -206.095092)
			)
		)
	)
	(zone
		(layer "In2.Cu")
		(hatch none 0.5)
		(connect_pads
			(clearance 0)
		)
		(min_thickness 0.25)
		(keepout
			(tracks not_allowed)
			(vias allowed)
			(pads allowed)
			(copperpour not_allowed)
			(footprints allowed)
		)
		(placement
			(enabled no)
			(sheetname "")
		)
		(fill
			(thermal_gap 0.5)
			(thermal_bridge_width 0.5)
			(island_removal_mode 0)
		)
		(polygon
			(pts
				(xy 306.618894 -262.525256) (xy 308.117494 -262.525256) (xy 308.117494 -263.045194) (xy 306.618894 -263.045194)
			)
		)
	)
	(zone
		(layer "In2.Cu")
		(hatch none 0.5)
		(connect_pads
			(clearance 0)
		)
		(min_thickness 0.25)
		(keepout
			(tracks not_allowed)
			(vias allowed)
			(pads allowed)
			(copperpour not_allowed)
			(footprints allowed)
		)
		(placement
			(enabled no)
			(sheetname "")
		)
		(fill
			(thermal_gap 0.5)
			(thermal_bridge_width 0.5)
			(island_removal_mode 0)
		)
		(polygon
			(pts
				(xy 163.678616 -265.075162) (xy 165.177216 -265.075162) (xy 165.177216 -265.5951) (xy 163.678616 -265.5951)
			)
		)
	)
	(zone
		(layer "In2.Cu")
		(hatch none 0.5)
		(connect_pads
			(clearance 0)
		)
		(min_thickness 0.25)
		(keepout
			(tracks not_allowed)
			(vias allowed)
			(pads allowed)
			(copperpour not_allowed)
			(footprints allowed)
		)
		(placement
			(enabled no)
			(sheetname "")
		)
		(fill
			(thermal_gap 0.5)
			(thermal_bridge_width 0.5)
			(island_removal_mode 0)
		)
		(polygon
			(pts
				(xy 171.22267 -197.925182) (xy 172.72127 -197.925182) (xy 172.72127 -198.44512) (xy 171.22267 -198.44512)
			)
		)
	)
	(zone
		(layer "In2.Cu")
		(hatch none 0.5)
		(connect_pads
			(clearance 0)
		)
		(min_thickness 0.25)
		(keepout
			(tracks not_allowed)
			(vias allowed)
			(pads allowed)
			(copperpour not_allowed)
			(footprints allowed)
		)
		(placement
			(enabled no)
			(sheetname "")
		)
		(fill
			(thermal_gap 0.5)
			(thermal_bridge_width 0.5)
			(island_removal_mode 0)
		)
		(polygon
			(pts
				(xy 445.894968 -298.22521) (xy 447.393568 -298.22521) (xy 447.393568 -298.745148) (xy 445.894968 -298.745148)
			)
		)
	)
	(zone
		(layer "In2.Cu")
		(hatch none 0.5)
		(connect_pads
			(clearance 0)
		)
		(min_thickness 0.25)
		(keepout
			(tracks not_allowed)
			(vias allowed)
			(pads allowed)
			(copperpour not_allowed)
			(footprints allowed)
		)
		(placement
			(enabled no)
			(sheetname "")
		)
		(fill
			(thermal_gap 0.5)
			(thermal_bridge_width 0.5)
			(island_removal_mode 0)
		)
		(polygon
			(pts
				(xy 279.886664 -220.025214) (xy 281.385264 -220.025214) (xy 281.385264 -220.545152) (xy 279.886664 -220.545152)
			)
		)
	)
	(zone
		(layer "In2.Cu")
		(hatch none 0.5)
		(connect_pads
			(clearance 0)
		)
		(min_thickness 0.25)
		(keepout
			(tracks not_allowed)
			(vias allowed)
			(pads allowed)
			(copperpour not_allowed)
			(footprints allowed)
		)
		(placement
			(enabled no)
			(sheetname "")
		)
		(fill
			(thermal_gap 0.5)
			(thermal_bridge_width 0.5)
			(island_removal_mode 0)
		)
		(polygon
			(pts
				(xy 186.310778 -308.425342) (xy 187.809378 -308.425342) (xy 187.809378 -308.94528) (xy 186.310778 -308.94528)
			)
		)
	)
	(zone
		(layer "In2.Cu")
		(hatch none 0.5)
		(connect_pads
			(clearance 0)
		)
		(min_thickness 0.25)
		(keepout
			(tracks not_allowed)
			(vias allowed)
			(pads allowed)
			(copperpour not_allowed)
			(footprints allowed)
		)
		(placement
			(enabled no)
			(sheetname "")
		)
		(fill
			(thermal_gap 0.5)
			(thermal_bridge_width 0.5)
			(island_removal_mode 0)
		)
		(polygon
			(pts
				(xy 453.438768 -252.325124) (xy 454.937368 -252.325124) (xy 454.937368 -252.845062) (xy 453.438768 -252.845062)
			)
		)
	)
	(zone
		(layer "In2.Cu")
		(hatch none 0.5)
		(connect_pads
			(clearance 0)
		)
		(min_thickness 0.25)
		(keepout
			(tracks not_allowed)
			(vias allowed)
			(pads allowed)
			(copperpour not_allowed)
			(footprints allowed)
		)
		(placement
			(enabled no)
			(sheetname "")
		)
		(fill
			(thermal_gap 0.5)
			(thermal_bridge_width 0.5)
			(island_removal_mode 0)
		)
		(polygon
			(pts
				(xy 47.034704 -294.825166) (xy 48.533304 -294.825166) (xy 48.533304 -295.345104) (xy 47.034704 -295.345104)
			)
		)
	)
	(zone
		(layer "In2.Cu")
		(hatch none 0.5)
		(connect_pads
			(clearance 0)
		)
		(min_thickness 0.25)
		(keepout
			(tracks not_allowed)
			(vias allowed)
			(pads allowed)
			(copperpour not_allowed)
			(footprints allowed)
		)
		(placement
			(enabled no)
			(sheetname "")
		)
		(fill
			(thermal_gap 0.5)
			(thermal_bridge_width 0.5)
			(island_removal_mode 0)
		)
		(polygon
			(pts
				(xy 306.618894 -238.725202) (xy 308.117494 -238.725202) (xy 308.117494 -239.24514) (xy 306.618894 -239.24514)
			)
		)
	)
	(zone
		(layer "In2.Cu")
		(hatch none 0.5)
		(connect_pads
			(clearance 0)
		)
		(min_thickness 0.25)
		(keepout
			(tracks not_allowed)
			(vias allowed)
			(pads allowed)
			(copperpour not_allowed)
			(footprints allowed)
		)
		(placement
			(enabled no)
			(sheetname "")
		)
		(fill
			(thermal_gap 0.5)
			(thermal_bridge_width 0.5)
			(island_removal_mode 0)
		)
		(polygon
			(pts
				(xy 441.7949 -244.675152) (xy 443.2935 -244.675152) (xy 443.2935 -245.19509) (xy 441.7949 -245.19509)
			)
		)
	)
	(zone
		(layer "In2.Cu")
		(hatch none 0.5)
		(connect_pads
			(clearance 0)
		)
		(min_thickness 0.25)
		(keepout
			(tracks not_allowed)
			(vias allowed)
			(pads allowed)
			(copperpour not_allowed)
			(footprints allowed)
		)
		(placement
			(enabled no)
			(sheetname "")
		)
		(fill
			(thermal_gap 0.5)
			(thermal_bridge_width 0.5)
			(island_removal_mode 0)
		)
		(polygon
			(pts
				(xy 287.430718 -265.075162) (xy 288.929318 -265.075162) (xy 288.929318 -265.5951) (xy 287.430718 -265.5951)
			)
		)
	)
	(zone
		(layer "In2.Cu")
		(hatch none 0.5)
		(connect_pads
			(clearance 0)
		)
		(min_thickness 0.25)
		(keepout
			(tracks not_allowed)
			(vias allowed)
			(pads allowed)
			(copperpour not_allowed)
			(footprints allowed)
		)
		(placement
			(enabled no)
			(sheetname "")
		)
		(fill
			(thermal_gap 0.5)
			(thermal_bridge_width 0.5)
			(island_removal_mode 0)
		)
		(polygon
			(pts
				(xy 302.518826 -251.47524) (xy 304.017426 -251.47524) (xy 304.017426 -251.995178) (xy 302.518826 -251.995178)
			)
		)
	)
	(zone
		(layer "In2.Cu")
		(hatch none 0.5)
		(connect_pads
			(clearance 0)
		)
		(min_thickness 0.25)
		(keepout
			(tracks not_allowed)
			(vias allowed)
			(pads allowed)
			(copperpour not_allowed)
			(footprints allowed)
		)
		(placement
			(enabled no)
			(sheetname "")
		)
		(fill
			(thermal_gap 0.5)
			(thermal_bridge_width 0.5)
			(island_removal_mode 0)
		)
		(polygon
			(pts
				(xy 58.678826 -264.225278) (xy 60.177426 -264.225278) (xy 60.177426 -264.745216) (xy 58.678826 -264.745216)
			)
		)
	)
	(zone
		(layer "In2.Cu")
		(hatch none 0.5)
		(connect_pads
			(clearance 0)
		)
		(min_thickness 0.25)
		(keepout
			(tracks not_allowed)
			(vias allowed)
			(pads allowed)
			(copperpour not_allowed)
			(footprints allowed)
		)
		(placement
			(enabled no)
			(sheetname "")
		)
		(fill
			(thermal_gap 0.5)
			(thermal_bridge_width 0.5)
			(island_removal_mode 0)
		)
		(polygon
			(pts
				(xy 171.22267 -297.375326) (xy 172.72127 -297.375326) (xy 172.72127 -297.895264) (xy 171.22267 -297.895264)
			)
		)
	)
	(zone
		(layer "In2.Cu")
		(hatch none 0.5)
		(connect_pads
			(clearance 0)
		)
		(min_thickness 0.25)
		(keepout
			(tracks not_allowed)
			(vias allowed)
			(pads allowed)
			(copperpour not_allowed)
			(footprints allowed)
		)
		(placement
			(enabled no)
			(sheetname "")
		)
		(fill
			(thermal_gap 0.5)
			(thermal_bridge_width 0.5)
			(island_removal_mode 0)
		)
		(polygon
			(pts
				(xy 190.410846 -260.825234) (xy 191.909446 -260.825234) (xy 191.909446 -261.345172) (xy 190.410846 -261.345172)
			)
		)
	)
	(zone
		(layer "In2.Cu")
		(hatch none 0.5)
		(connect_pads
			(clearance 0)
		)
		(min_thickness 0.25)
		(keepout
			(tracks not_allowed)
			(vias allowed)
			(pads allowed)
			(copperpour not_allowed)
			(footprints allowed)
		)
		(placement
			(enabled no)
			(sheetname "")
		)
		(fill
			(thermal_gap 0.5)
			(thermal_bridge_width 0.5)
			(island_removal_mode 0)
		)
		(polygon
			(pts
				(xy 167.778684 -238.725202) (xy 169.277284 -238.725202) (xy 169.277284 -239.24514) (xy 167.778684 -239.24514)
			)
		)
	)
	(zone
		(layer "In2.Cu")
		(hatch none 0.5)
		(connect_pads
			(clearance 0)
		)
		(min_thickness 0.25)
		(keepout
			(tracks not_allowed)
			(vias allowed)
			(pads allowed)
			(copperpour not_allowed)
			(footprints allowed)
		)
		(placement
			(enabled no)
			(sheetname "")
		)
		(fill
			(thermal_gap 0.5)
			(thermal_bridge_width 0.5)
			(island_removal_mode 0)
		)
		(polygon
			(pts
				(xy 306.618894 -305.875182) (xy 308.117494 -305.875182) (xy 308.117494 -306.39512) (xy 306.618894 -306.39512)
			)
		)
	)
	(zone
		(layer "In2.Cu")
		(hatch none 0.5)
		(connect_pads
			(clearance 0)
		)
		(min_thickness 0.25)
		(keepout
			(tracks not_allowed)
			(vias allowed)
			(pads allowed)
			(copperpour not_allowed)
			(footprints allowed)
		)
		(placement
			(enabled no)
			(sheetname "")
		)
		(fill
			(thermal_gap 0.5)
			(thermal_bridge_width 0.5)
			(island_removal_mode 0)
		)
		(polygon
			(pts
				(xy 276.442932 -204.72527) (xy 277.941532 -204.72527) (xy 277.941532 -205.245208) (xy 276.442932 -205.245208)
			)
		)
	)
	(zone
		(layer "In2.Cu")
		(hatch none 0.5)
		(connect_pads
			(clearance 0)
		)
		(min_thickness 0.25)
		(keepout
			(tracks not_allowed)
			(vias allowed)
			(pads allowed)
			(copperpour not_allowed)
			(footprints allowed)
		)
		(placement
			(enabled no)
			(sheetname "")
		)
		(fill
			(thermal_gap 0.5)
			(thermal_bridge_width 0.5)
			(island_removal_mode 0)
		)
		(polygon
			(pts
				(xy 175.322738 -226.825302) (xy 176.821338 -226.825302) (xy 176.821338 -227.34524) (xy 175.322738 -227.34524)
			)
		)
	)
	(zone
		(layer "In2.Cu")
		(hatch none 0.5)
		(connect_pads
			(clearance 0)
		)
		(min_thickness 0.25)
		(keepout
			(tracks not_allowed)
			(vias allowed)
			(pads allowed)
			(copperpour not_allowed)
			(footprints allowed)
		)
		(placement
			(enabled no)
			(sheetname "")
		)
		(fill
			(thermal_gap 0.5)
			(thermal_bridge_width 0.5)
			(island_removal_mode 0)
		)
		(polygon
			(pts
				(xy 449.3387 -293.125144) (xy 450.8373 -293.125144) (xy 450.8373 -293.645082) (xy 449.3387 -293.645082)
			)
		)
	)
	(zone
		(layer "In2.Cu")
		(hatch none 0.5)
		(connect_pads
			(clearance 0)
		)
		(min_thickness 0.25)
		(keepout
			(tracks not_allowed)
			(vias allowed)
			(pads allowed)
			(copperpour not_allowed)
			(footprints allowed)
		)
		(placement
			(enabled no)
			(sheetname "")
		)
		(fill
			(thermal_gap 0.5)
			(thermal_bridge_width 0.5)
			(island_removal_mode 0)
		)
		(polygon
			(pts
				(xy 276.442932 -198.77532) (xy 277.941532 -198.77532) (xy 277.941532 -199.295258) (xy 276.442932 -199.295258)
			)
		)
	)
	(zone
		(layer "In2.Cu")
		(hatch none 0.5)
		(connect_pads
			(clearance 0)
		)
		(min_thickness 0.25)
		(keepout
			(tracks not_allowed)
			(vias allowed)
			(pads allowed)
			(copperpour not_allowed)
			(footprints allowed)
		)
		(placement
			(enabled no)
			(sheetname "")
		)
		(fill
			(thermal_gap 0.5)
			(thermal_bridge_width 0.5)
			(island_removal_mode 0)
		)
		(polygon
			(pts
				(xy 24.402542 -210.67522) (xy 25.901142 -210.67522) (xy 25.901142 -211.195158) (xy 24.402542 -211.195158)
			)
		)
	)
	(zone
		(layer "In2.Cu")
		(hatch none 0.5)
		(connect_pads
			(clearance 0)
		)
		(min_thickness 0.25)
		(keepout
			(tracks not_allowed)
			(vias allowed)
			(pads allowed)
			(copperpour not_allowed)
			(footprints allowed)
		)
		(placement
			(enabled no)
			(sheetname "")
		)
		(fill
			(thermal_gap 0.5)
			(thermal_bridge_width 0.5)
			(island_removal_mode 0)
		)
		(polygon
			(pts
				(xy 276.442932 -290.575238) (xy 277.941532 -290.575238) (xy 277.941532 -291.095176) (xy 276.442932 -291.095176)
			)
		)
	)
	(zone
		(layer "In2.Cu")
		(hatch none 0.5)
		(connect_pads
			(clearance 0)
		)
		(min_thickness 0.25)
		(keepout
			(tracks not_allowed)
			(vias allowed)
			(pads allowed)
			(copperpour not_allowed)
			(footprints allowed)
		)
		(placement
			(enabled no)
			(sheetname "")
		)
		(fill
			(thermal_gap 0.5)
			(thermal_bridge_width 0.5)
			(island_removal_mode 0)
		)
		(polygon
			(pts
				(xy 31.946596 -311.825132) (xy 33.445196 -311.825132) (xy 33.445196 -312.34507) (xy 31.946596 -312.34507)
			)
		)
	)
	(zone
		(layer "In2.Cu")
		(hatch none 0.5)
		(connect_pads
			(clearance 0)
		)
		(min_thickness 0.25)
		(keepout
			(tracks not_allowed)
			(vias allowed)
			(pads allowed)
			(copperpour not_allowed)
			(footprints allowed)
		)
		(placement
			(enabled no)
			(sheetname "")
		)
		(fill
			(thermal_gap 0.5)
			(thermal_bridge_width 0.5)
			(island_removal_mode 0)
		)
		(polygon
			(pts
				(xy 47.034704 -229.375208) (xy 48.533304 -229.375208) (xy 48.533304 -229.895146) (xy 47.034704 -229.895146)
			)
		)
	)
	(zone
		(layer "In2.Cu")
		(hatch none 0.5)
		(connect_pads
			(clearance 0)
		)
		(min_thickness 0.25)
		(keepout
			(tracks not_allowed)
			(vias allowed)
			(pads allowed)
			(copperpour not_allowed)
			(footprints allowed)
		)
		(placement
			(enabled no)
			(sheetname "")
		)
		(fill
			(thermal_gap 0.5)
			(thermal_bridge_width 0.5)
			(island_removal_mode 0)
		)
		(polygon
			(pts
				(xy 163.678616 -268.475206) (xy 165.177216 -268.475206) (xy 165.177216 -268.995144) (xy 163.678616 -268.995144)
			)
		)
	)
	(zone
		(layer "In2.Cu")
		(hatch none 0.5)
		(connect_pads
			(clearance 0)
		)
		(min_thickness 0.25)
		(keepout
			(tracks not_allowed)
			(vias allowed)
			(pads allowed)
			(copperpour not_allowed)
			(footprints allowed)
		)
		(placement
			(enabled no)
			(sheetname "")
		)
		(fill
			(thermal_gap 0.5)
			(thermal_bridge_width 0.5)
			(island_removal_mode 0)
		)
		(polygon
			(pts
				(xy 190.410846 -223.425258) (xy 191.909446 -223.425258) (xy 191.909446 -223.945196) (xy 190.410846 -223.945196)
			)
		)
	)
	(zone
		(layer "In2.Cu")
		(hatch none 0.5)
		(connect_pads
			(clearance 0)
		)
		(min_thickness 0.25)
		(keepout
			(tracks not_allowed)
			(vias allowed)
			(pads allowed)
			(copperpour not_allowed)
			(footprints allowed)
		)
		(placement
			(enabled no)
			(sheetname "")
		)
		(fill
			(thermal_gap 0.5)
			(thermal_bridge_width 0.5)
			(island_removal_mode 0)
		)
		(polygon
			(pts
				(xy 167.778684 -245.52529) (xy 169.277284 -245.52529) (xy 169.277284 -246.045228) (xy 167.778684 -246.045228)
			)
		)
	)
	(zone
		(layer "In2.Cu")
		(hatch none 0.5)
		(connect_pads
			(clearance 0)
		)
		(min_thickness 0.25)
		(keepout
			(tracks not_allowed)
			(vias allowed)
			(pads allowed)
			(copperpour not_allowed)
			(footprints allowed)
		)
		(placement
			(enabled no)
			(sheetname "")
		)
		(fill
			(thermal_gap 0.5)
			(thermal_bridge_width 0.5)
			(island_removal_mode 0)
		)
		(polygon
			(pts
				(xy 268.898878 -270.175228) (xy 270.397478 -270.175228) (xy 270.397478 -270.695166) (xy 268.898878 -270.695166)
			)
		)
	)
	(zone
		(layer "In2.Cu")
		(hatch none 0.5)
		(connect_pads
			(clearance 0)
		)
		(min_thickness 0.25)
		(keepout
			(tracks not_allowed)
			(vias allowed)
			(pads allowed)
			(copperpour not_allowed)
			(footprints allowed)
		)
		(placement
			(enabled no)
			(sheetname "")
		)
		(fill
			(thermal_gap 0.5)
			(thermal_bridge_width 0.5)
			(island_removal_mode 0)
		)
		(polygon
			(pts
				(xy 190.410846 -247.225312) (xy 191.909446 -247.225312) (xy 191.909446 -247.74525) (xy 190.410846 -247.74525)
			)
		)
	)
	(zone
		(layer "In2.Cu")
		(hatch none 0.5)
		(connect_pads
			(clearance 0)
		)
		(min_thickness 0.25)
		(keepout
			(tracks not_allowed)
			(vias allowed)
			(pads allowed)
			(copperpour not_allowed)
			(footprints allowed)
		)
		(placement
			(enabled no)
			(sheetname "")
		)
		(fill
			(thermal_gap 0.5)
			(thermal_bridge_width 0.5)
			(island_removal_mode 0)
		)
		(polygon
			(pts
				(xy 441.7949 -272.725134) (xy 443.2935 -272.725134) (xy 443.2935 -273.245072) (xy 441.7949 -273.245072)
			)
		)
	)
	(zone
		(layer "In2.Cu")
		(hatch none 0.5)
		(connect_pads
			(clearance 0)
		)
		(min_thickness 0.25)
		(keepout
			(tracks not_allowed)
			(vias allowed)
			(pads allowed)
			(copperpour not_allowed)
			(footprints allowed)
		)
		(placement
			(enabled no)
			(sheetname "")
		)
		(fill
			(thermal_gap 0.5)
			(thermal_bridge_width 0.5)
			(island_removal_mode 0)
		)
		(polygon
			(pts
				(xy 453.438768 -264.225278) (xy 454.937368 -264.225278) (xy 454.937368 -264.745216) (xy 453.438768 -264.745216)
			)
		)
	)
	(zone
		(layer "In2.Cu")
		(hatch none 0.5)
		(connect_pads
			(clearance 0)
		)
		(min_thickness 0.25)
		(keepout
			(tracks not_allowed)
			(vias allowed)
			(pads allowed)
			(copperpour not_allowed)
			(footprints allowed)
		)
		(placement
			(enabled no)
			(sheetname "")
		)
		(fill
			(thermal_gap 0.5)
			(thermal_bridge_width 0.5)
			(island_removal_mode 0)
		)
		(polygon
			(pts
				(xy 434.250846 -276.975316) (xy 435.749446 -276.975316) (xy 435.749446 -277.495254) (xy 434.250846 -277.495254)
			)
		)
	)
	(zone
		(layer "In2.Cu")
		(hatch none 0.5)
		(connect_pads
			(clearance 0)
		)
		(min_thickness 0.25)
		(keepout
			(tracks not_allowed)
			(vias allowed)
			(pads allowed)
			(copperpour not_allowed)
			(footprints allowed)
		)
		(placement
			(enabled no)
			(sheetname "")
		)
		(fill
			(thermal_gap 0.5)
			(thermal_bridge_width 0.5)
			(island_removal_mode 0)
		)
		(polygon
			(pts
				(xy 276.442932 -212.375242) (xy 277.941532 -212.375242) (xy 277.941532 -212.89518) (xy 276.442932 -212.89518)
			)
		)
	)
	(zone
		(layer "In2.Cu")
		(hatch none 0.5)
		(connect_pads
			(clearance 0)
		)
		(min_thickness 0.25)
		(keepout
			(tracks not_allowed)
			(vias allowed)
			(pads allowed)
			(copperpour not_allowed)
			(footprints allowed)
		)
		(placement
			(enabled no)
			(sheetname "")
		)
		(fill
			(thermal_gap 0.5)
			(thermal_bridge_width 0.5)
			(island_removal_mode 0)
		)
		(polygon
			(pts
				(xy 426.706792 -288.025332) (xy 428.205392 -288.025332) (xy 428.205392 -288.54527) (xy 426.706792 -288.54527)
			)
		)
	)
	(zone
		(layer "In2.Cu")
		(hatch none 0.5)
		(connect_pads
			(clearance 0)
		)
		(min_thickness 0.25)
		(keepout
			(tracks not_allowed)
			(vias allowed)
			(pads allowed)
			(copperpour not_allowed)
			(footprints allowed)
		)
		(placement
			(enabled no)
			(sheetname "")
		)
		(fill
			(thermal_gap 0.5)
			(thermal_bridge_width 0.5)
			(island_removal_mode 0)
		)
		(polygon
			(pts
				(xy 201.398632 -242.97513) (xy 202.897232 -242.97513) (xy 202.897232 -243.495068) (xy 201.398632 -243.495068)
			)
		)
	)
	(zone
		(layer "In2.Cu")
		(hatch none 0.5)
		(connect_pads
			(clearance 0)
		)
		(min_thickness 0.25)
		(keepout
			(tracks not_allowed)
			(vias allowed)
			(pads allowed)
			(copperpour not_allowed)
			(footprints allowed)
		)
		(placement
			(enabled no)
			(sheetname "")
		)
		(fill
			(thermal_gap 0.5)
			(thermal_bridge_width 0.5)
			(island_removal_mode 0)
		)
		(polygon
			(pts
				(xy 175.322738 -287.175194) (xy 176.821338 -287.175194) (xy 176.821338 -287.695132) (xy 175.322738 -287.695132)
			)
		)
	)
	(zone
		(layer "In2.Cu")
		(hatch none 0.5)
		(connect_pads
			(clearance 0)
		)
		(min_thickness 0.25)
		(keepout
			(tracks not_allowed)
			(vias allowed)
			(pads allowed)
			(copperpour not_allowed)
			(footprints allowed)
		)
		(placement
			(enabled no)
			(sheetname "")
		)
		(fill
			(thermal_gap 0.5)
			(thermal_bridge_width 0.5)
			(island_removal_mode 0)
		)
		(polygon
			(pts
				(xy 51.134772 -232.775252) (xy 52.633372 -232.775252) (xy 52.633372 -233.29519) (xy 51.134772 -233.29519)
			)
		)
	)
	(zone
		(layer "In2.Cu")
		(hatch none 0.5)
		(connect_pads
			(clearance 0)
		)
		(min_thickness 0.25)
		(keepout
			(tracks not_allowed)
			(vias allowed)
			(pads allowed)
			(copperpour not_allowed)
			(footprints allowed)
		)
		(placement
			(enabled no)
			(sheetname "")
		)
		(fill
			(thermal_gap 0.5)
			(thermal_bridge_width 0.5)
			(island_removal_mode 0)
		)
		(polygon
			(pts
				(xy 449.3387 -299.075348) (xy 450.8373 -299.075348) (xy 450.8373 -299.595286) (xy 449.3387 -299.595286)
			)
		)
	)
	(zone
		(layer "In2.Cu")
		(hatch none 0.5)
		(connect_pads
			(clearance 0)
		)
		(min_thickness 0.25)
		(keepout
			(tracks not_allowed)
			(vias allowed)
			(pads allowed)
			(copperpour not_allowed)
			(footprints allowed)
		)
		(placement
			(enabled no)
			(sheetname "")
		)
		(fill
			(thermal_gap 0.5)
			(thermal_bridge_width 0.5)
			(island_removal_mode 0)
		)
		(polygon
			(pts
				(xy 272.342864 -305.025298) (xy 273.841464 -305.025298) (xy 273.841464 -305.545236) (xy 272.342864 -305.545236)
			)
		)
	)
	(zone
		(layer "In2.Cu")
		(hatch none 0.5)
		(connect_pads
			(clearance 0)
		)
		(min_thickness 0.25)
		(keepout
			(tracks not_allowed)
			(vias allowed)
			(pads allowed)
			(copperpour not_allowed)
			(footprints allowed)
		)
		(placement
			(enabled no)
			(sheetname "")
		)
		(fill
			(thermal_gap 0.5)
			(thermal_bridge_width 0.5)
			(island_removal_mode 0)
		)
		(polygon
			(pts
				(xy 16.858742 -289.725354) (xy 18.357342 -289.725354) (xy 18.357342 -290.245292) (xy 16.858742 -290.245292)
			)
		)
	)
	(zone
		(layer "In2.Cu")
		(hatch none 0.5)
		(connect_pads
			(clearance 0)
		)
		(min_thickness 0.25)
		(keepout
			(tracks not_allowed)
			(vias allowed)
			(pads allowed)
			(copperpour not_allowed)
			(footprints allowed)
		)
		(placement
			(enabled no)
			(sheetname "")
		)
		(fill
			(thermal_gap 0.5)
			(thermal_bridge_width 0.5)
			(island_removal_mode 0)
		)
		(polygon
			(pts
				(xy 190.410846 -276.125178) (xy 191.909446 -276.125178) (xy 191.909446 -276.645116) (xy 190.410846 -276.645116)
			)
		)
	)
	(zone
		(layer "In2.Cu")
		(hatch none 0.5)
		(connect_pads
			(clearance 0)
		)
		(min_thickness 0.25)
		(keepout
			(tracks not_allowed)
			(vias allowed)
			(pads allowed)
			(copperpour not_allowed)
			(footprints allowed)
		)
		(placement
			(enabled no)
			(sheetname "")
		)
		(fill
			(thermal_gap 0.5)
			(thermal_bridge_width 0.5)
			(island_removal_mode 0)
		)
		(polygon
			(pts
				(xy 306.618894 -240.425224) (xy 308.117494 -240.425224) (xy 308.117494 -240.945162) (xy 306.618894 -240.945162)
			)
		)
	)
	(zone
		(layer "In2.Cu")
		(hatch none 0.5)
		(connect_pads
			(clearance 0)
		)
		(min_thickness 0.25)
		(keepout
			(tracks not_allowed)
			(vias allowed)
			(pads allowed)
			(copperpour not_allowed)
			(footprints allowed)
		)
		(placement
			(enabled no)
			(sheetname "")
		)
		(fill
			(thermal_gap 0.5)
			(thermal_bridge_width 0.5)
			(island_removal_mode 0)
		)
		(polygon
			(pts
				(xy 16.858742 -229.375208) (xy 18.357342 -229.375208) (xy 18.357342 -229.895146) (xy 16.858742 -229.895146)
			)
		)
	)
	(zone
		(layer "In2.Cu")
		(hatch none 0.5)
		(connect_pads
			(clearance 0)
		)
		(min_thickness 0.25)
		(keepout
			(tracks not_allowed)
			(vias allowed)
			(pads allowed)
			(copperpour not_allowed)
			(footprints allowed)
		)
		(placement
			(enabled no)
			(sheetname "")
		)
		(fill
			(thermal_gap 0.5)
			(thermal_bridge_width 0.5)
			(island_removal_mode 0)
		)
		(polygon
			(pts
				(xy 415.718752 -292.27526) (xy 417.217352 -292.27526) (xy 417.217352 -292.795198) (xy 415.718752 -292.795198)
			)
		)
	)
	(zone
		(layer "In2.Cu")
		(hatch none 0.5)
		(connect_pads
			(clearance 0)
		)
		(min_thickness 0.25)
		(keepout
			(tracks not_allowed)
			(vias allowed)
			(pads allowed)
			(copperpour not_allowed)
			(footprints allowed)
		)
		(placement
			(enabled no)
			(sheetname "")
		)
		(fill
			(thermal_gap 0.5)
			(thermal_bridge_width 0.5)
			(island_removal_mode 0)
		)
		(polygon
			(pts
				(xy 16.858742 -203.875132) (xy 18.357342 -203.875132) (xy 18.357342 -204.39507) (xy 16.858742 -204.39507)
			)
		)
	)
	(zone
		(layer "In2.Cu")
		(hatch none 0.5)
		(connect_pads
			(clearance 0)
		)
		(min_thickness 0.25)
		(keepout
			(tracks not_allowed)
			(vias allowed)
			(pads allowed)
			(copperpour not_allowed)
			(footprints allowed)
		)
		(placement
			(enabled no)
			(sheetname "")
		)
		(fill
			(thermal_gap 0.5)
			(thermal_bridge_width 0.5)
			(island_removal_mode 0)
		)
		(polygon
			(pts
				(xy 419.162738 -313.525154) (xy 420.661338 -313.525154) (xy 420.661338 -314.045092) (xy 419.162738 -314.045092)
			)
		)
	)
	(zone
		(layer "In2.Cu")
		(hatch none 0.5)
		(connect_pads
			(clearance 0)
		)
		(min_thickness 0.25)
		(keepout
			(tracks not_allowed)
			(vias allowed)
			(pads allowed)
			(copperpour not_allowed)
			(footprints allowed)
		)
		(placement
			(enabled no)
			(sheetname "")
		)
		(fill
			(thermal_gap 0.5)
			(thermal_bridge_width 0.5)
			(island_removal_mode 0)
		)
		(polygon
			(pts
				(xy 449.3387 -237.02518) (xy 450.8373 -237.02518) (xy 450.8373 -237.545118) (xy 449.3387 -237.545118)
			)
		)
	)
	(zone
		(layer "In2.Cu")
		(hatch none 0.5)
		(connect_pads
			(clearance 0)
		)
		(min_thickness 0.25)
		(keepout
			(tracks not_allowed)
			(vias allowed)
			(pads allowed)
			(copperpour not_allowed)
			(footprints allowed)
		)
		(placement
			(enabled no)
			(sheetname "")
		)
		(fill
			(thermal_gap 0.5)
			(thermal_bridge_width 0.5)
			(island_removal_mode 0)
		)
		(polygon
			(pts
				(xy 276.442932 -234.475274) (xy 277.941532 -234.475274) (xy 277.941532 -234.995212) (xy 276.442932 -234.995212)
			)
		)
	)
	(zone
		(layer "In2.Cu")
		(hatch none 0.5)
		(connect_pads
			(clearance 0)
		)
		(min_thickness 0.25)
		(keepout
			(tracks not_allowed)
			(vias allowed)
			(pads allowed)
			(copperpour not_allowed)
			(footprints allowed)
		)
		(placement
			(enabled no)
			(sheetname "")
		)
		(fill
			(thermal_gap 0.5)
			(thermal_bridge_width 0.5)
			(island_removal_mode 0)
		)
		(polygon
			(pts
				(xy 272.342864 -302.475138) (xy 273.841464 -302.475138) (xy 273.841464 -302.995076) (xy 272.342864 -302.995076)
			)
		)
	)
	(zone
		(layer "In2.Cu")
		(hatch none 0.5)
		(connect_pads
			(clearance 0)
		)
		(min_thickness 0.25)
		(keepout
			(tracks not_allowed)
			(vias allowed)
			(pads allowed)
			(copperpour not_allowed)
			(footprints allowed)
		)
		(placement
			(enabled no)
			(sheetname "")
		)
		(fill
			(thermal_gap 0.5)
			(thermal_bridge_width 0.5)
			(island_removal_mode 0)
		)
		(polygon
			(pts
				(xy 419.162738 -276.975316) (xy 420.661338 -276.975316) (xy 420.661338 -277.495254) (xy 419.162738 -277.495254)
			)
		)
	)
	(zone
		(layer "In2.Cu")
		(hatch none 0.5)
		(connect_pads
			(clearance 0)
		)
		(min_thickness 0.25)
		(keepout
			(tracks not_allowed)
			(vias allowed)
			(pads allowed)
			(copperpour not_allowed)
			(footprints allowed)
		)
		(placement
			(enabled no)
			(sheetname "")
		)
		(fill
			(thermal_gap 0.5)
			(thermal_bridge_width 0.5)
			(island_removal_mode 0)
		)
		(polygon
			(pts
				(xy 299.07484 -288.875216) (xy 300.57344 -288.875216) (xy 300.57344 -289.395154) (xy 299.07484 -289.395154)
			)
		)
	)
	(zone
		(layer "In2.Cu")
		(hatch none 0.5)
		(connect_pads
			(clearance 0)
		)
		(min_thickness 0.25)
		(keepout
			(tracks not_allowed)
			(vias allowed)
			(pads allowed)
			(copperpour not_allowed)
			(footprints allowed)
		)
		(placement
			(enabled no)
			(sheetname "")
		)
		(fill
			(thermal_gap 0.5)
			(thermal_bridge_width 0.5)
			(island_removal_mode 0)
		)
		(polygon
			(pts
				(xy 193.854578 -276.975316) (xy 195.353178 -276.975316) (xy 195.353178 -277.495254) (xy 193.854578 -277.495254)
			)
		)
	)
	(zone
		(layer "In2.Cu")
		(hatch none 0.5)
		(connect_pads
			(clearance 0)
		)
		(min_thickness 0.25)
		(keepout
			(tracks not_allowed)
			(vias allowed)
			(pads allowed)
			(copperpour not_allowed)
			(footprints allowed)
		)
		(placement
			(enabled no)
			(sheetname "")
		)
		(fill
			(thermal_gap 0.5)
			(thermal_bridge_width 0.5)
			(island_removal_mode 0)
		)
		(polygon
			(pts
				(xy 276.442932 -296.525188) (xy 277.941532 -296.525188) (xy 277.941532 -297.045126) (xy 276.442932 -297.045126)
			)
		)
	)
	(zone
		(layer "In2.Cu")
		(hatch none 0.5)
		(connect_pads
			(clearance 0)
		)
		(min_thickness 0.25)
		(keepout
			(tracks not_allowed)
			(vias allowed)
			(pads allowed)
			(copperpour not_allowed)
			(footprints allowed)
		)
		(placement
			(enabled no)
			(sheetname "")
		)
		(fill
			(thermal_gap 0.5)
			(thermal_bridge_width 0.5)
			(island_removal_mode 0)
		)
		(polygon
			(pts
				(xy 415.718752 -225.12528) (xy 417.217352 -225.12528) (xy 417.217352 -225.645218) (xy 415.718752 -225.645218)
			)
		)
	)
	(zone
		(layer "In2.Cu")
		(hatch none 0.5)
		(connect_pads
			(clearance 0)
		)
		(min_thickness 0.25)
		(keepout
			(tracks not_allowed)
			(vias allowed)
			(pads allowed)
			(copperpour not_allowed)
			(footprints allowed)
		)
		(placement
			(enabled no)
			(sheetname "")
		)
		(fill
			(thermal_gap 0.5)
			(thermal_bridge_width 0.5)
			(island_removal_mode 0)
		)
		(polygon
			(pts
				(xy 276.442932 -203.025248) (xy 277.941532 -203.025248) (xy 277.941532 -203.545186) (xy 276.442932 -203.545186)
			)
		)
	)
	(zone
		(layer "In2.Cu")
		(hatch none 0.5)
		(connect_pads
			(clearance 0)
		)
		(min_thickness 0.25)
		(keepout
			(tracks not_allowed)
			(vias allowed)
			(pads allowed)
			(copperpour not_allowed)
			(footprints allowed)
		)
		(placement
			(enabled no)
			(sheetname "")
		)
		(fill
			(thermal_gap 0.5)
			(thermal_bridge_width 0.5)
			(island_removal_mode 0)
		)
		(polygon
			(pts
				(xy 36.046664 -226.825302) (xy 37.545264 -226.825302) (xy 37.545264 -227.34524) (xy 36.046664 -227.34524)
			)
		)
	)
	(zone
		(layer "In2.Cu")
		(hatch none 0.5)
		(connect_pads
			(clearance 0)
		)
		(min_thickness 0.25)
		(keepout
			(tracks not_allowed)
			(vias allowed)
			(pads allowed)
			(copperpour not_allowed)
			(footprints allowed)
		)
		(placement
			(enabled no)
			(sheetname "")
		)
		(fill
			(thermal_gap 0.5)
			(thermal_bridge_width 0.5)
			(island_removal_mode 0)
		)
		(polygon
			(pts
				(xy 268.898878 -212.375242) (xy 270.397478 -212.375242) (xy 270.397478 -212.89518) (xy 268.898878 -212.89518)
			)
		)
	)
	(zone
		(layer "In2.Cu")
		(hatch none 0.5)
		(connect_pads
			(clearance 0)
		)
		(min_thickness 0.25)
		(keepout
			(tracks not_allowed)
			(vias allowed)
			(pads allowed)
			(copperpour not_allowed)
			(footprints allowed)
		)
		(placement
			(enabled no)
			(sheetname "")
		)
		(fill
			(thermal_gap 0.5)
			(thermal_bridge_width 0.5)
			(island_removal_mode 0)
		)
		(polygon
			(pts
				(xy 20.95881 -254.025146) (xy 22.45741 -254.025146) (xy 22.45741 -254.545084) (xy 20.95881 -254.545084)
			)
		)
	)
	(zone
		(layer "In2.Cu")
		(hatch none 0.5)
		(connect_pads
			(clearance 0)
		)
		(min_thickness 0.25)
		(keepout
			(tracks not_allowed)
			(vias allowed)
			(pads allowed)
			(copperpour not_allowed)
			(footprints allowed)
		)
		(placement
			(enabled no)
			(sheetname "")
		)
		(fill
			(thermal_gap 0.5)
			(thermal_bridge_width 0.5)
			(island_removal_mode 0)
		)
		(polygon
			(pts
				(xy 294.974772 -242.97513) (xy 296.473372 -242.97513) (xy 296.473372 -243.495068) (xy 294.974772 -243.495068)
			)
		)
	)
	(zone
		(layer "In2.Cu")
		(hatch none 0.5)
		(connect_pads
			(clearance 0)
		)
		(min_thickness 0.25)
		(keepout
			(tracks not_allowed)
			(vias allowed)
			(pads allowed)
			(copperpour not_allowed)
			(footprints allowed)
		)
		(placement
			(enabled no)
			(sheetname "")
		)
		(fill
			(thermal_gap 0.5)
			(thermal_bridge_width 0.5)
			(island_removal_mode 0)
		)
		(polygon
			(pts
				(xy 186.310778 -283.77515) (xy 187.809378 -283.77515) (xy 187.809378 -284.295088) (xy 186.310778 -284.295088)
			)
		)
	)
	(zone
		(layer "In2.Cu")
		(hatch none 0.5)
		(connect_pads
			(clearance 0)
		)
		(min_thickness 0.25)
		(keepout
			(tracks not_allowed)
			(vias allowed)
			(pads allowed)
			(copperpour not_allowed)
			(footprints allowed)
		)
		(placement
			(enabled no)
			(sheetname "")
		)
		(fill
			(thermal_gap 0.5)
			(thermal_bridge_width 0.5)
			(island_removal_mode 0)
		)
		(polygon
			(pts
				(xy 453.438768 -198.77532) (xy 454.937368 -198.77532) (xy 454.937368 -199.295258) (xy 453.438768 -199.295258)
			)
		)
	)
	(zone
		(layer "In2.Cu")
		(hatch none 0.5)
		(connect_pads
			(clearance 0)
		)
		(min_thickness 0.25)
		(keepout
			(tracks not_allowed)
			(vias allowed)
			(pads allowed)
			(copperpour not_allowed)
			(footprints allowed)
		)
		(placement
			(enabled no)
			(sheetname "")
		)
		(fill
			(thermal_gap 0.5)
			(thermal_bridge_width 0.5)
			(island_removal_mode 0)
		)
		(polygon
			(pts
				(xy 287.430718 -218.325192) (xy 288.929318 -218.325192) (xy 288.929318 -218.84513) (xy 287.430718 -218.84513)
			)
		)
	)
	(zone
		(layer "In2.Cu")
		(hatch none 0.5)
		(connect_pads
			(clearance 0)
		)
		(min_thickness 0.25)
		(keepout
			(tracks not_allowed)
			(vias allowed)
			(pads allowed)
			(copperpour not_allowed)
			(footprints allowed)
		)
		(placement
			(enabled no)
			(sheetname "")
		)
		(fill
			(thermal_gap 0.5)
			(thermal_bridge_width 0.5)
			(island_removal_mode 0)
		)
		(polygon
			(pts
				(xy 299.07484 -217.475308) (xy 300.57344 -217.475308) (xy 300.57344 -217.995246) (xy 299.07484 -217.995246)
			)
		)
	)
	(zone
		(layer "In2.Cu")
		(hatch none 0.5)
		(connect_pads
			(clearance 0)
		)
		(min_thickness 0.25)
		(keepout
			(tracks not_allowed)
			(vias allowed)
			(pads allowed)
			(copperpour not_allowed)
			(footprints allowed)
		)
		(placement
			(enabled no)
			(sheetname "")
		)
		(fill
			(thermal_gap 0.5)
			(thermal_bridge_width 0.5)
			(island_removal_mode 0)
		)
		(polygon
			(pts
				(xy 445.894968 -269.325344) (xy 447.393568 -269.325344) (xy 447.393568 -269.845282) (xy 445.894968 -269.845282)
			)
		)
	)
	(zone
		(layer "In2.Cu")
		(hatch none 0.5)
		(connect_pads
			(clearance 0)
		)
		(min_thickness 0.25)
		(keepout
			(tracks not_allowed)
			(vias allowed)
			(pads allowed)
			(copperpour not_allowed)
			(footprints allowed)
		)
		(placement
			(enabled no)
			(sheetname "")
		)
		(fill
			(thermal_gap 0.5)
			(thermal_bridge_width 0.5)
			(island_removal_mode 0)
		)
		(polygon
			(pts
				(xy 302.518826 -285.475172) (xy 304.017426 -285.475172) (xy 304.017426 -285.99511) (xy 302.518826 -285.99511)
			)
		)
	)
	(zone
		(layer "In2.Cu")
		(hatch none 0.5)
		(connect_pads
			(clearance 0)
		)
		(min_thickness 0.25)
		(keepout
			(tracks not_allowed)
			(vias allowed)
			(pads allowed)
			(copperpour not_allowed)
			(footprints allowed)
		)
		(placement
			(enabled no)
			(sheetname "")
		)
		(fill
			(thermal_gap 0.5)
			(thermal_bridge_width 0.5)
			(island_removal_mode 0)
		)
		(polygon
			(pts
				(xy 426.706792 -202.17511) (xy 428.205392 -202.17511) (xy 428.205392 -202.695048) (xy 426.706792 -202.695048)
			)
		)
	)
	(zone
		(layer "In2.Cu")
		(hatch none 0.5)
		(connect_pads
			(clearance 0)
		)
		(min_thickness 0.25)
		(keepout
			(tracks allowed)
			(vias allowed)
			(pads allowed)
			(copperpour allowed)
			(footprints allowed)
		)
		(placement
			(enabled no)
			(sheetname "")
		)
		(fill
			(thermal_gap 0.5)
			(thermal_bridge_width 0.5)
			(island_removal_mode 0)
		)
		(polygon
			(pts
				(xy 76.88199 -338.688172) (xy 76.88199 -339.574632) (xy 76.71181 -339.574632) (xy 76.71181 -338.688172)
			)
		)
	)
	(zone
		(layer "In2.Cu")
		(hatch none 0.5)
		(connect_pads
			(clearance 0)
		)
		(min_thickness 0.25)
		(keepout
			(tracks not_allowed)
			(vias allowed)
			(pads allowed)
			(copperpour not_allowed)
			(footprints allowed)
		)
		(placement
			(enabled no)
			(sheetname "")
		)
		(fill
			(thermal_gap 0.5)
			(thermal_bridge_width 0.5)
			(island_removal_mode 0)
		)
		(polygon
			(pts
				(xy 28.50261 -243.825268) (xy 30.00121 -243.825268) (xy 30.00121 -244.345206) (xy 28.50261 -244.345206)
			)
		)
	)
	(zone
		(layer "In2.Cu")
		(hatch none 0.5)
		(connect_pads
			(clearance 0)
		)
		(min_thickness 0.25)
		(keepout
			(tracks not_allowed)
			(vias allowed)
			(pads allowed)
			(copperpour not_allowed)
			(footprints allowed)
		)
		(placement
			(enabled no)
			(sheetname "")
		)
		(fill
			(thermal_gap 0.5)
			(thermal_bridge_width 0.5)
			(island_removal_mode 0)
		)
		(polygon
			(pts
				(xy 186.310778 -291.425122) (xy 187.809378 -291.425122) (xy 187.809378 -291.94506) (xy 186.310778 -291.94506)
			)
		)
	)
	(zone
		(layer "In2.Cu")
		(hatch none 0.5)
		(connect_pads
			(clearance 0)
		)
		(min_thickness 0.25)
		(keepout
			(tracks not_allowed)
			(vias allowed)
			(pads allowed)
			(copperpour not_allowed)
			(footprints allowed)
		)
		(placement
			(enabled no)
			(sheetname "")
		)
		(fill
			(thermal_gap 0.5)
			(thermal_bridge_width 0.5)
			(island_removal_mode 0)
		)
		(polygon
			(pts
				(xy 193.854578 -207.275176) (xy 195.353178 -207.275176) (xy 195.353178 -207.795114) (xy 193.854578 -207.795114)
			)
		)
	)
	(zone
		(layer "In2.Cu")
		(hatch none 0.5)
		(connect_pads
			(clearance 0)
		)
		(min_thickness 0.25)
		(keepout
			(tracks not_allowed)
			(vias allowed)
			(pads allowed)
			(copperpour not_allowed)
			(footprints allowed)
		)
		(placement
			(enabled no)
			(sheetname "")
		)
		(fill
			(thermal_gap 0.5)
			(thermal_bridge_width 0.5)
			(island_removal_mode 0)
		)
		(polygon
			(pts
				(xy 58.678826 -307.575204) (xy 60.177426 -307.575204) (xy 60.177426 -308.095142) (xy 58.678826 -308.095142)
			)
		)
	)
	(zone
		(layer "In2.Cu")
		(hatch none 0.5)
		(connect_pads
			(clearance 0)
		)
		(min_thickness 0.25)
		(keepout
			(tracks not_allowed)
			(vias allowed)
			(pads allowed)
			(copperpour not_allowed)
			(footprints allowed)
		)
		(placement
			(enabled no)
			(sheetname "")
		)
		(fill
			(thermal_gap 0.5)
			(thermal_bridge_width 0.5)
			(island_removal_mode 0)
		)
		(polygon
			(pts
				(xy 449.3387 -311.825132) (xy 450.8373 -311.825132) (xy 450.8373 -312.34507) (xy 449.3387 -312.34507)
			)
		)
	)
	(zone
		(layer "In2.Cu")
		(hatch none 0.5)
		(connect_pads
			(clearance 0)
		)
		(min_thickness 0.25)
		(keepout
			(tracks not_allowed)
			(vias allowed)
			(pads allowed)
			(copperpour not_allowed)
			(footprints allowed)
		)
		(placement
			(enabled no)
			(sheetname "")
		)
		(fill
			(thermal_gap 0.5)
			(thermal_bridge_width 0.5)
			(island_removal_mode 0)
		)
		(polygon
			(pts
				(xy 291.530786 -245.52529) (xy 293.029386 -245.52529) (xy 293.029386 -246.045228) (xy 291.530786 -246.045228)
			)
		)
	)
	(zone
		(layer "In2.Cu")
		(hatch none 0.5)
		(connect_pads
			(clearance 0)
		)
		(min_thickness 0.25)
		(keepout
			(tracks not_allowed)
			(vias allowed)
			(pads allowed)
			(copperpour not_allowed)
			(footprints allowed)
		)
		(placement
			(enabled no)
			(sheetname "")
		)
		(fill
			(thermal_gap 0.5)
			(thermal_bridge_width 0.5)
			(island_removal_mode 0)
		)
		(polygon
			(pts
				(xy 163.678616 -280.375106) (xy 165.177216 -280.375106) (xy 165.177216 -280.895044) (xy 163.678616 -280.895044)
			)
		)
	)
	(zone
		(layer "In2.Cu")
		(hatch none 0.5)
		(connect_pads
			(clearance 0)
		)
		(min_thickness 0.25)
		(keepout
			(tracks not_allowed)
			(vias allowed)
			(pads allowed)
			(copperpour not_allowed)
			(footprints allowed)
		)
		(placement
			(enabled no)
			(sheetname "")
		)
		(fill
			(thermal_gap 0.5)
			(thermal_bridge_width 0.5)
			(island_removal_mode 0)
		)
		(polygon
			(pts
				(xy 47.034704 -235.325158) (xy 48.533304 -235.325158) (xy 48.533304 -235.845096) (xy 47.034704 -235.845096)
			)
		)
	)
	(zone
		(layer "In2.Cu")
		(hatch none 0.5)
		(connect_pads
			(clearance 0)
		)
		(min_thickness 0.25)
		(keepout
			(tracks not_allowed)
			(vias allowed)
			(pads allowed)
			(copperpour not_allowed)
			(footprints allowed)
		)
		(placement
			(enabled no)
			(sheetname "")
		)
		(fill
			(thermal_gap 0.5)
			(thermal_bridge_width 0.5)
			(island_removal_mode 0)
		)
		(polygon
			(pts
				(xy 415.718752 -282.925266) (xy 417.217352 -282.925266) (xy 417.217352 -283.445204) (xy 415.718752 -283.445204)
			)
		)
	)
	(zone
		(layer "In2.Cu")
		(hatch none 0.5)
		(connect_pads
			(clearance 0)
		)
		(min_thickness 0.25)
		(keepout
			(tracks not_allowed)
			(vias allowed)
			(pads allowed)
			(copperpour not_allowed)
			(footprints allowed)
		)
		(placement
			(enabled no)
			(sheetname "")
		)
		(fill
			(thermal_gap 0.5)
			(thermal_bridge_width 0.5)
			(island_removal_mode 0)
		)
		(polygon
			(pts
				(xy 58.678826 -271.87525) (xy 60.177426 -271.87525) (xy 60.177426 -272.395188) (xy 58.678826 -272.395188)
			)
		)
	)
	(zone
		(layer "In2.Cu")
		(hatch none 0.5)
		(connect_pads
			(clearance 0)
		)
		(min_thickness 0.25)
		(keepout
			(tracks not_allowed)
			(vias allowed)
			(pads allowed)
			(copperpour not_allowed)
			(footprints allowed)
		)
		(placement
			(enabled no)
			(sheetname "")
		)
		(fill
			(thermal_gap 0.5)
			(thermal_bridge_width 0.5)
			(island_removal_mode 0)
		)
		(polygon
			(pts
				(xy 426.706792 -216.62517) (xy 428.205392 -216.62517) (xy 428.205392 -217.145108) (xy 426.706792 -217.145108)
			)
		)
	)
	(zone
		(layer "In2.Cu")
		(hatch none 0.5)
		(connect_pads
			(clearance 0)
		)
		(min_thickness 0.25)
		(keepout
			(tracks not_allowed)
			(vias allowed)
			(pads allowed)
			(copperpour not_allowed)
			(footprints allowed)
		)
		(placement
			(enabled no)
			(sheetname "")
		)
		(fill
			(thermal_gap 0.5)
			(thermal_bridge_width 0.5)
			(island_removal_mode 0)
		)
		(polygon
			(pts
				(xy 283.986732 -275.275294) (xy 285.485332 -275.275294) (xy 285.485332 -275.795232) (xy 283.986732 -275.795232)
			)
		)
	)
	(zone
		(layer "In2.Cu")
		(hatch none 0.5)
		(connect_pads
			(clearance 0)
		)
		(min_thickness 0.25)
		(keepout
			(tracks not_allowed)
			(vias allowed)
			(pads allowed)
			(copperpour not_allowed)
			(footprints allowed)
		)
		(placement
			(enabled no)
			(sheetname "")
		)
		(fill
			(thermal_gap 0.5)
			(thermal_bridge_width 0.5)
			(island_removal_mode 0)
		)
		(polygon
			(pts
				(xy 426.706792 -242.97513) (xy 428.205392 -242.97513) (xy 428.205392 -243.495068) (xy 426.706792 -243.495068)
			)
		)
	)
	(zone
		(layer "In2.Cu")
		(hatch none 0.5)
		(connect_pads
			(clearance 0)
		)
		(min_thickness 0.25)
		(keepout
			(tracks not_allowed)
			(vias allowed)
			(pads allowed)
			(copperpour not_allowed)
			(footprints allowed)
		)
		(placement
			(enabled no)
			(sheetname "")
		)
		(fill
			(thermal_gap 0.5)
			(thermal_bridge_width 0.5)
			(island_removal_mode 0)
		)
		(polygon
			(pts
				(xy 453.438768 -262.525256) (xy 454.937368 -262.525256) (xy 454.937368 -263.045194) (xy 453.438768 -263.045194)
			)
		)
	)
	(zone
		(layer "In2.Cu")
		(hatch none 0.5)
		(connect_pads
			(clearance 0)
		)
		(min_thickness 0.25)
		(keepout
			(tracks not_allowed)
			(vias allowed)
			(pads allowed)
			(copperpour not_allowed)
			(footprints allowed)
		)
		(placement
			(enabled no)
			(sheetname "")
		)
		(fill
			(thermal_gap 0.5)
			(thermal_bridge_width 0.5)
			(island_removal_mode 0)
		)
		(polygon
			(pts
				(xy 47.034704 -286.32531) (xy 48.533304 -286.32531) (xy 48.533304 -286.845248) (xy 47.034704 -286.845248)
			)
		)
	)
	(zone
		(layer "In2.Cu")
		(hatch none 0.5)
		(connect_pads
			(clearance 0)
		)
		(min_thickness 0.25)
		(keepout
			(tracks not_allowed)
			(vias allowed)
			(pads allowed)
			(copperpour not_allowed)
			(footprints allowed)
		)
		(placement
			(enabled no)
			(sheetname "")
		)
		(fill
			(thermal_gap 0.5)
			(thermal_bridge_width 0.5)
			(island_removal_mode 0)
		)
		(polygon
			(pts
				(xy 279.886664 -216.62517) (xy 281.385264 -216.62517) (xy 281.385264 -217.145108) (xy 279.886664 -217.145108)
			)
		)
	)
	(zone
		(layer "In2.Cu")
		(hatch none 0.5)
		(connect_pads
			(clearance 0)
		)
		(min_thickness 0.25)
		(keepout
			(tracks not_allowed)
			(vias allowed)
			(pads allowed)
			(copperpour not_allowed)
			(footprints allowed)
		)
		(placement
			(enabled no)
			(sheetname "")
		)
		(fill
			(thermal_gap 0.5)
			(thermal_bridge_width 0.5)
			(island_removal_mode 0)
		)
		(polygon
			(pts
				(xy 272.342864 -266.775184) (xy 273.841464 -266.775184) (xy 273.841464 -267.295122) (xy 272.342864 -267.295122)
			)
		)
	)
	(zone
		(layer "In2.Cu")
		(hatch none 0.5)
		(connect_pads
			(clearance 0)
		)
		(min_thickness 0.25)
		(keepout
			(tracks not_allowed)
			(vias allowed)
			(pads allowed)
			(copperpour not_allowed)
			(footprints allowed)
		)
		(placement
			(enabled no)
			(sheetname "")
		)
		(fill
			(thermal_gap 0.5)
			(thermal_bridge_width 0.5)
			(island_removal_mode 0)
		)
		(polygon
			(pts
				(xy 16.858742 -239.57534) (xy 18.357342 -239.57534) (xy 18.357342 -240.095278) (xy 16.858742 -240.095278)
			)
		)
	)
	(zone
		(layer "In2.Cu")
		(hatch none 0.5)
		(connect_pads
			(clearance 0)
		)
		(min_thickness 0.25)
		(keepout
			(tracks not_allowed)
			(vias allowed)
			(pads allowed)
			(copperpour not_allowed)
			(footprints allowed)
		)
		(placement
			(enabled no)
			(sheetname "")
		)
		(fill
			(thermal_gap 0.5)
			(thermal_bridge_width 0.5)
			(island_removal_mode 0)
		)
		(polygon
			(pts
				(xy 54.578758 -280.375106) (xy 56.077358 -280.375106) (xy 56.077358 -280.895044) (xy 54.578758 -280.895044)
			)
		)
	)
	(zone
		(layer "In2.Cu")
		(hatch none 0.5)
		(connect_pads
			(clearance 0)
		)
		(min_thickness 0.25)
		(keepout
			(tracks allowed)
			(vias allowed)
			(pads allowed)
			(copperpour allowed)
			(footprints allowed)
		)
		(placement
			(enabled no)
			(sheetname "")
		)
		(fill
			(thermal_gap 0.5)
			(thermal_bridge_width 0.5)
			(island_removal_mode 0)
		)
		(polygon
			(pts
				(xy 90.55481 -338.853018) (xy 90.55481 -338.230718) (xy 91.10599 -338.230718) (xy 91.10599 -338.853018)
			)
		)
	)
	(zone
		(layer "In2.Cu")
		(hatch none 0.5)
		(connect_pads
			(clearance 0)
		)
		(min_thickness 0.25)
		(keepout
			(tracks not_allowed)
			(vias allowed)
			(pads allowed)
			(copperpour not_allowed)
			(footprints allowed)
		)
		(placement
			(enabled no)
			(sheetname "")
		)
		(fill
			(thermal_gap 0.5)
			(thermal_bridge_width 0.5)
			(island_removal_mode 0)
		)
		(polygon
			(pts
				(xy 430.80686 -201.325226) (xy 432.30546 -201.325226) (xy 432.30546 -201.845164) (xy 430.80686 -201.845164)
			)
		)
	)
	(zone
		(layer "In2.Cu")
		(hatch none 0.5)
		(connect_pads
			(clearance 0)
		)
		(min_thickness 0.25)
		(keepout
			(tracks not_allowed)
			(vias allowed)
			(pads allowed)
			(copperpour not_allowed)
			(footprints allowed)
		)
		(placement
			(enabled no)
			(sheetname "")
		)
		(fill
			(thermal_gap 0.5)
			(thermal_bridge_width 0.5)
			(island_removal_mode 0)
		)
		(polygon
			(pts
				(xy 24.402542 -293.125144) (xy 25.901142 -293.125144) (xy 25.901142 -293.645082) (xy 24.402542 -293.645082)
			)
		)
	)
	(zone
		(layer "In2.Cu")
		(hatch none 0.5)
		(connect_pads
			(clearance 0)
		)
		(min_thickness 0.25)
		(keepout
			(tracks not_allowed)
			(vias allowed)
			(pads allowed)
			(copperpour not_allowed)
			(footprints allowed)
		)
		(placement
			(enabled no)
			(sheetname "")
		)
		(fill
			(thermal_gap 0.5)
			(thermal_bridge_width 0.5)
			(island_removal_mode 0)
		)
		(polygon
			(pts
				(xy 163.678616 -304.17516) (xy 165.177216 -304.17516) (xy 165.177216 -304.695098) (xy 163.678616 -304.695098)
			)
		)
	)
	(zone
		(layer "In2.Cu")
		(hatch none 0.5)
		(connect_pads
			(clearance 0)
		)
		(min_thickness 0.25)
		(keepout
			(tracks not_allowed)
			(vias allowed)
			(pads allowed)
			(copperpour not_allowed)
			(footprints allowed)
		)
		(placement
			(enabled no)
			(sheetname "")
		)
		(fill
			(thermal_gap 0.5)
			(thermal_bridge_width 0.5)
			(island_removal_mode 0)
		)
		(polygon
			(pts
				(xy 434.250846 -310.12511) (xy 435.749446 -310.12511) (xy 435.749446 -310.645048) (xy 434.250846 -310.645048)
			)
		)
	)
	(zone
		(layer "In2.Cu")
		(hatch none 0.5)
		(connect_pads
			(clearance 0)
		)
		(min_thickness 0.25)
		(keepout
			(tracks not_allowed)
			(vias allowed)
			(pads allowed)
			(copperpour not_allowed)
			(footprints allowed)
		)
		(placement
			(enabled no)
			(sheetname "")
		)
		(fill
			(thermal_gap 0.5)
			(thermal_bridge_width 0.5)
			(island_removal_mode 0)
		)
		(polygon
			(pts
				(xy 434.250846 -251.47524) (xy 435.749446 -251.47524) (xy 435.749446 -251.995178) (xy 434.250846 -251.995178)
			)
		)
	)
	(zone
		(layer "In2.Cu")
		(hatch none 0.5)
		(connect_pads
			(clearance 0)
		)
		(min_thickness 0.25)
		(keepout
			(tracks not_allowed)
			(vias allowed)
			(pads allowed)
			(copperpour not_allowed)
			(footprints allowed)
		)
		(placement
			(enabled no)
			(sheetname "")
		)
		(fill
			(thermal_gap 0.5)
			(thermal_bridge_width 0.5)
			(island_removal_mode 0)
		)
		(polygon
			(pts
				(xy 268.898878 -309.275226) (xy 270.397478 -309.275226) (xy 270.397478 -309.795164) (xy 268.898878 -309.795164)
			)
		)
	)
	(zone
		(layer "In2.Cu")
		(hatch none 0.5)
		(connect_pads
			(clearance 0)
		)
		(min_thickness 0.25)
		(keepout
			(tracks not_allowed)
			(vias allowed)
			(pads allowed)
			(copperpour not_allowed)
			(footprints allowed)
		)
		(placement
			(enabled no)
			(sheetname "")
		)
		(fill
			(thermal_gap 0.5)
			(thermal_bridge_width 0.5)
			(island_removal_mode 0)
		)
		(polygon
			(pts
				(xy 438.350914 -220.025214) (xy 439.849514 -220.025214) (xy 439.849514 -220.545152) (xy 438.350914 -220.545152)
			)
		)
	)
	(zone
		(layer "In2.Cu")
		(hatch none 0.5)
		(connect_pads
			(clearance 0)
		)
		(min_thickness 0.25)
		(keepout
			(tracks not_allowed)
			(vias allowed)
			(pads allowed)
			(copperpour not_allowed)
			(footprints allowed)
		)
		(placement
			(enabled no)
			(sheetname "")
		)
		(fill
			(thermal_gap 0.5)
			(thermal_bridge_width 0.5)
			(island_removal_mode 0)
		)
		(polygon
			(pts
				(xy 28.50261 -200.475342) (xy 30.00121 -200.475342) (xy 30.00121 -200.99528) (xy 28.50261 -200.99528)
			)
		)
	)
	(zone
		(layer "In2.Cu")
		(hatch none 0.5)
		(connect_pads
			(clearance 0)
		)
		(min_thickness 0.25)
		(keepout
			(tracks not_allowed)
			(vias allowed)
			(pads allowed)
			(copperpour not_allowed)
			(footprints allowed)
		)
		(placement
			(enabled no)
			(sheetname "")
		)
		(fill
			(thermal_gap 0.5)
			(thermal_bridge_width 0.5)
			(island_removal_mode 0)
		)
		(polygon
			(pts
				(xy 287.430718 -225.975164) (xy 288.929318 -225.975164) (xy 288.929318 -226.495102) (xy 287.430718 -226.495102)
			)
		)
	)
	(zone
		(layer "In2.Cu")
		(hatch none 0.5)
		(connect_pads
			(clearance 0)
		)
		(min_thickness 0.25)
		(keepout
			(tracks not_allowed)
			(vias allowed)
			(pads allowed)
			(copperpour not_allowed)
			(footprints allowed)
		)
		(placement
			(enabled no)
			(sheetname "")
		)
		(fill
			(thermal_gap 0.5)
			(thermal_bridge_width 0.5)
			(island_removal_mode 0)
		)
		(polygon
			(pts
				(xy 31.946596 -283.77515) (xy 33.445196 -283.77515) (xy 33.445196 -284.295088) (xy 31.946596 -284.295088)
			)
		)
	)
	(zone
		(layer "In2.Cu")
		(hatch none 0.5)
		(connect_pads
			(clearance 0)
		)
		(min_thickness 0.25)
		(keepout
			(tracks allowed)
			(vias allowed)
			(pads allowed)
			(copperpour allowed)
			(footprints allowed)
		)
		(placement
			(enabled no)
			(sheetname "")
		)
		(fill
			(thermal_gap 0.5)
			(thermal_bridge_width 0.5)
			(island_removal_mode 0)
		)
		(polygon
			(pts
				(xy 385.41833 -179.494434) (xy 385.41833 -178.94808) (xy 385.97078 -178.94808) (xy 385.97078 -179.494434)
			)
		)
	)
	(zone
		(layer "In2.Cu")
		(hatch none 0.5)
		(connect_pads
			(clearance 0)
		)
		(min_thickness 0.25)
		(keepout
			(tracks not_allowed)
			(vias allowed)
			(pads allowed)
			(copperpour not_allowed)
			(footprints allowed)
		)
		(placement
			(enabled no)
			(sheetname "")
		)
		(fill
			(thermal_gap 0.5)
			(thermal_bridge_width 0.5)
			(island_removal_mode 0)
		)
		(polygon
			(pts
				(xy 415.718752 -276.125178) (xy 417.217352 -276.125178) (xy 417.217352 -276.645116) (xy 415.718752 -276.645116)
			)
		)
	)
	(zone
		(layer "In2.Cu")
		(hatch none 0.5)
		(connect_pads
			(clearance 0)
		)
		(min_thickness 0.25)
		(keepout
			(tracks not_allowed)
			(vias allowed)
			(pads allowed)
			(copperpour not_allowed)
			(footprints allowed)
		)
		(placement
			(enabled no)
			(sheetname "")
		)
		(fill
			(thermal_gap 0.5)
			(thermal_bridge_width 0.5)
			(island_removal_mode 0)
		)
		(polygon
			(pts
				(xy 449.3387 -214.925148) (xy 450.8373 -214.925148) (xy 450.8373 -215.445086) (xy 449.3387 -215.445086)
			)
		)
	)
	(zone
		(layer "In2.Cu")
		(hatch none 0.5)
		(connect_pads
			(clearance 0)
		)
		(min_thickness 0.25)
		(keepout
			(tracks not_allowed)
			(vias allowed)
			(pads allowed)
			(copperpour not_allowed)
			(footprints allowed)
		)
		(placement
			(enabled no)
			(sheetname "")
		)
		(fill
			(thermal_gap 0.5)
			(thermal_bridge_width 0.5)
			(island_removal_mode 0)
		)
		(polygon
			(pts
				(xy 279.886664 -305.025298) (xy 281.385264 -305.025298) (xy 281.385264 -305.545236) (xy 279.886664 -305.545236)
			)
		)
	)
	(zone
		(layer "In2.Cu")
		(hatch none 0.5)
		(connect_pads
			(clearance 0)
		)
		(min_thickness 0.25)
		(keepout
			(tracks not_allowed)
			(vias allowed)
			(pads allowed)
			(copperpour not_allowed)
			(footprints allowed)
		)
		(placement
			(enabled no)
			(sheetname "")
		)
		(fill
			(thermal_gap 0.5)
			(thermal_bridge_width 0.5)
			(island_removal_mode 0)
		)
		(polygon
			(pts
				(xy 449.3387 -261.675118) (xy 450.8373 -261.675118) (xy 450.8373 -262.195056) (xy 449.3387 -262.195056)
			)
		)
	)
	(zone
		(layer "In2.Cu")
		(hatch none 0.5)
		(connect_pads
			(clearance 0)
		)
		(min_thickness 0.25)
		(keepout
			(tracks not_allowed)
			(vias allowed)
			(pads allowed)
			(copperpour not_allowed)
			(footprints allowed)
		)
		(placement
			(enabled no)
			(sheetname "")
		)
		(fill
			(thermal_gap 0.5)
			(thermal_bridge_width 0.5)
			(island_removal_mode 0)
		)
		(polygon
			(pts
				(xy 47.034704 -317.775336) (xy 48.533304 -317.775336) (xy 48.533304 -318.295274) (xy 47.034704 -318.295274)
			)
		)
	)
	(zone
		(layer "In2.Cu")
		(hatch none 0.5)
		(connect_pads
			(clearance 0)
		)
		(min_thickness 0.25)
		(keepout
			(tracks not_allowed)
			(vias allowed)
			(pads allowed)
			(copperpour not_allowed)
			(footprints allowed)
		)
		(placement
			(enabled no)
			(sheetname "")
		)
		(fill
			(thermal_gap 0.5)
			(thermal_bridge_width 0.5)
			(island_removal_mode 0)
		)
		(polygon
			(pts
				(xy 16.858742 -214.925148) (xy 18.357342 -214.925148) (xy 18.357342 -215.445086) (xy 16.858742 -215.445086)
			)
		)
	)
	(zone
		(layer "In2.Cu")
		(hatch none 0.5)
		(connect_pads
			(clearance 0)
		)
		(min_thickness 0.25)
		(keepout
			(tracks not_allowed)
			(vias allowed)
			(pads allowed)
			(copperpour not_allowed)
			(footprints allowed)
		)
		(placement
			(enabled no)
			(sheetname "")
		)
		(fill
			(thermal_gap 0.5)
			(thermal_bridge_width 0.5)
			(island_removal_mode 0)
		)
		(polygon
			(pts
				(xy 167.778684 -200.475342) (xy 169.277284 -200.475342) (xy 169.277284 -200.99528) (xy 167.778684 -200.99528)
			)
		)
	)
	(zone
		(layer "In2.Cu")
		(hatch none 0.5)
		(connect_pads
			(clearance 0)
		)
		(min_thickness 0.25)
		(keepout
			(tracks not_allowed)
			(vias allowed)
			(pads allowed)
			(copperpour not_allowed)
			(footprints allowed)
		)
		(placement
			(enabled no)
			(sheetname "")
		)
		(fill
			(thermal_gap 0.5)
			(thermal_bridge_width 0.5)
			(island_removal_mode 0)
		)
		(polygon
			(pts
				(xy 190.410846 -240.425224) (xy 191.909446 -240.425224) (xy 191.909446 -240.945162) (xy 190.410846 -240.945162)
			)
		)
	)
	(zone
		(layer "In2.Cu")
		(hatch none 0.5)
		(connect_pads
			(clearance 0)
		)
		(min_thickness 0.25)
		(keepout
			(tracks not_allowed)
			(vias allowed)
			(pads allowed)
			(copperpour not_allowed)
			(footprints allowed)
		)
		(placement
			(enabled no)
			(sheetname "")
		)
		(fill
			(thermal_gap 0.5)
			(thermal_bridge_width 0.5)
			(island_removal_mode 0)
		)
		(polygon
			(pts
				(xy 28.50261 -301.625254) (xy 30.00121 -301.625254) (xy 30.00121 -302.145192) (xy 28.50261 -302.145192)
			)
		)
	)
	(zone
		(layer "In2.Cu")
		(hatch none 0.5)
		(connect_pads
			(clearance 0)
		)
		(min_thickness 0.25)
		(keepout
			(tracks not_allowed)
			(vias allowed)
			(pads allowed)
			(copperpour not_allowed)
			(footprints allowed)
		)
		(placement
			(enabled no)
			(sheetname "")
		)
		(fill
			(thermal_gap 0.5)
			(thermal_bridge_width 0.5)
			(island_removal_mode 0)
		)
		(polygon
			(pts
				(xy 430.80686 -279.525222) (xy 432.30546 -279.525222) (xy 432.30546 -280.04516) (xy 430.80686 -280.04516)
			)
		)
	)
	(zone
		(layer "In2.Cu")
		(hatch none 0.5)
		(connect_pads
			(clearance 0)
		)
		(min_thickness 0.25)
		(keepout
			(tracks not_allowed)
			(vias allowed)
			(pads allowed)
			(copperpour not_allowed)
			(footprints allowed)
		)
		(placement
			(enabled no)
			(sheetname "")
		)
		(fill
			(thermal_gap 0.5)
			(thermal_bridge_width 0.5)
			(island_removal_mode 0)
		)
		(polygon
			(pts
				(xy 276.442932 -238.725202) (xy 277.941532 -238.725202) (xy 277.941532 -239.24514) (xy 276.442932 -239.24514)
			)
		)
	)
	(zone
		(layer "In2.Cu")
		(hatch none 0.5)
		(connect_pads
			(clearance 0)
		)
		(min_thickness 0.25)
		(keepout
			(tracks not_allowed)
			(vias allowed)
			(pads allowed)
			(copperpour not_allowed)
			(footprints allowed)
		)
		(placement
			(enabled no)
			(sheetname "")
		)
		(fill
			(thermal_gap 0.5)
			(thermal_bridge_width 0.5)
			(island_removal_mode 0)
		)
		(polygon
			(pts
				(xy 423.262806 -209.825336) (xy 424.761406 -209.825336) (xy 424.761406 -210.345274) (xy 423.262806 -210.345274)
			)
		)
	)
	(zone
		(layer "In2.Cu")
		(hatch none 0.5)
		(connect_pads
			(clearance 0)
		)
		(min_thickness 0.25)
		(keepout
			(tracks not_allowed)
			(vias allowed)
			(pads allowed)
			(copperpour not_allowed)
			(footprints allowed)
		)
		(placement
			(enabled no)
			(sheetname "")
		)
		(fill
			(thermal_gap 0.5)
			(thermal_bridge_width 0.5)
			(island_removal_mode 0)
		)
		(polygon
			(pts
				(xy 31.946596 -203.875132) (xy 33.445196 -203.875132) (xy 33.445196 -204.39507) (xy 31.946596 -204.39507)
			)
		)
	)
	(zone
		(layer "In2.Cu")
		(hatch none 0.5)
		(connect_pads
			(clearance 0)
		)
		(min_thickness 0.25)
		(keepout
			(tracks not_allowed)
			(vias allowed)
			(pads allowed)
			(copperpour not_allowed)
			(footprints allowed)
		)
		(placement
			(enabled no)
			(sheetname "")
		)
		(fill
			(thermal_gap 0.5)
			(thermal_bridge_width 0.5)
			(island_removal_mode 0)
		)
		(polygon
			(pts
				(xy 279.886664 -291.425122) (xy 281.385264 -291.425122) (xy 281.385264 -291.94506) (xy 279.886664 -291.94506)
			)
		)
	)
	(zone
		(layer "In2.Cu")
		(hatch none 0.5)
		(connect_pads
			(clearance 0)
		)
		(min_thickness 0.25)
		(keepout
			(tracks not_allowed)
			(vias allowed)
			(pads allowed)
			(copperpour not_allowed)
			(footprints allowed)
		)
		(placement
			(enabled no)
			(sheetname "")
		)
		(fill
			(thermal_gap 0.5)
			(thermal_bridge_width 0.5)
			(island_removal_mode 0)
		)
		(polygon
			(pts
				(xy 453.438768 -290.575238) (xy 454.937368 -290.575238) (xy 454.937368 -291.095176) (xy 453.438768 -291.095176)
			)
		)
	)
	(zone
		(layer "In2.Cu")
		(hatch none 0.5)
		(connect_pads
			(clearance 0)
		)
		(min_thickness 0.25)
		(keepout
			(tracks not_allowed)
			(vias allowed)
			(pads allowed)
			(copperpour not_allowed)
			(footprints allowed)
		)
		(placement
			(enabled no)
			(sheetname "")
		)
		(fill
			(thermal_gap 0.5)
			(thermal_bridge_width 0.5)
			(island_removal_mode 0)
		)
		(polygon
			(pts
				(xy 294.974772 -300.775116) (xy 296.473372 -300.775116) (xy 296.473372 -301.295054) (xy 294.974772 -301.295054)
			)
		)
	)
	(zone
		(layer "In2.Cu")
		(hatch none 0.5)
		(connect_pads
			(clearance 0)
		)
		(min_thickness 0.25)
		(keepout
			(tracks not_allowed)
			(vias allowed)
			(pads allowed)
			(copperpour not_allowed)
			(footprints allowed)
		)
		(placement
			(enabled no)
			(sheetname "")
		)
		(fill
			(thermal_gap 0.5)
			(thermal_bridge_width 0.5)
			(island_removal_mode 0)
		)
		(polygon
			(pts
				(xy 16.858742 -213.225126) (xy 18.357342 -213.225126) (xy 18.357342 -213.745064) (xy 16.858742 -213.745064)
			)
		)
	)
	(zone
		(layer "In2.Cu")
		(hatch none 0.5)
		(connect_pads
			(clearance 0)
		)
		(min_thickness 0.25)
		(keepout
			(tracks not_allowed)
			(vias allowed)
			(pads allowed)
			(copperpour not_allowed)
			(footprints allowed)
		)
		(placement
			(enabled no)
			(sheetname "")
		)
		(fill
			(thermal_gap 0.5)
			(thermal_bridge_width 0.5)
			(island_removal_mode 0)
		)
		(polygon
			(pts
				(xy 47.034704 -231.925114) (xy 48.533304 -231.925114) (xy 48.533304 -232.445052) (xy 47.034704 -232.445052)
			)
		)
	)
	(zone
		(layer "In2.Cu")
		(hatch none 0.5)
		(connect_pads
			(clearance 0)
		)
		(min_thickness 0.25)
		(keepout
			(tracks not_allowed)
			(vias allowed)
			(pads allowed)
			(copperpour not_allowed)
			(footprints allowed)
		)
		(placement
			(enabled no)
			(sheetname "")
		)
		(fill
			(thermal_gap 0.5)
			(thermal_bridge_width 0.5)
			(island_removal_mode 0)
		)
		(polygon
			(pts
				(xy 283.986732 -269.325344) (xy 285.485332 -269.325344) (xy 285.485332 -269.845282) (xy 283.986732 -269.845282)
			)
		)
	)
	(zone
		(layer "In2.Cu")
		(hatch none 0.5)
		(connect_pads
			(clearance 0)
		)
		(min_thickness 0.25)
		(keepout
			(tracks not_allowed)
			(vias allowed)
			(pads allowed)
			(copperpour not_allowed)
			(footprints allowed)
		)
		(placement
			(enabled no)
			(sheetname "")
		)
		(fill
			(thermal_gap 0.5)
			(thermal_bridge_width 0.5)
			(island_removal_mode 0)
		)
		(polygon
			(pts
				(xy 453.438768 -245.52529) (xy 454.937368 -245.52529) (xy 454.937368 -246.045228) (xy 453.438768 -246.045228)
			)
		)
	)
	(zone
		(layer "In2.Cu")
		(hatch none 0.5)
		(connect_pads
			(clearance 0)
		)
		(min_thickness 0.25)
		(keepout
			(tracks not_allowed)
			(vias allowed)
			(pads allowed)
			(copperpour not_allowed)
			(footprints allowed)
		)
		(placement
			(enabled no)
			(sheetname "")
		)
		(fill
			(thermal_gap 0.5)
			(thermal_bridge_width 0.5)
			(island_removal_mode 0)
		)
		(polygon
			(pts
				(xy 190.410846 -197.075298) (xy 191.909446 -197.075298) (xy 191.909446 -197.595236) (xy 190.410846 -197.595236)
			)
		)
	)
	(zone
		(layer "In2.Cu")
		(hatch none 0.5)
		(connect_pads
			(clearance 0)
		)
		(min_thickness 0.25)
		(keepout
			(tracks not_allowed)
			(vias allowed)
			(pads allowed)
			(copperpour not_allowed)
			(footprints allowed)
		)
		(placement
			(enabled no)
			(sheetname "")
		)
		(fill
			(thermal_gap 0.5)
			(thermal_bridge_width 0.5)
			(island_removal_mode 0)
		)
		(polygon
			(pts
				(xy 201.398632 -244.675152) (xy 202.897232 -244.675152) (xy 202.897232 -245.19509) (xy 201.398632 -245.19509)
			)
		)
	)
	(zone
		(layer "In2.Cu")
		(hatch none 0.5)
		(connect_pads
			(clearance 0)
		)
		(min_thickness 0.25)
		(keepout
			(tracks not_allowed)
			(vias allowed)
			(pads allowed)
			(copperpour not_allowed)
			(footprints allowed)
		)
		(placement
			(enabled no)
			(sheetname "")
		)
		(fill
			(thermal_gap 0.5)
			(thermal_bridge_width 0.5)
			(island_removal_mode 0)
		)
		(polygon
			(pts
				(xy 423.262806 -304.17516) (xy 424.761406 -304.17516) (xy 424.761406 -304.695098) (xy 423.262806 -304.695098)
			)
		)
	)
	(zone
		(layer "In2.Cu")
		(hatch none 0.5)
		(connect_pads
			(clearance 0)
		)
		(min_thickness 0.25)
		(keepout
			(tracks not_allowed)
			(vias allowed)
			(pads allowed)
			(copperpour not_allowed)
			(footprints allowed)
		)
		(placement
			(enabled no)
			(sheetname "")
		)
		(fill
			(thermal_gap 0.5)
			(thermal_bridge_width 0.5)
			(island_removal_mode 0)
		)
		(polygon
			(pts
				(xy 283.986732 -282.925266) (xy 285.485332 -282.925266) (xy 285.485332 -283.445204) (xy 283.986732 -283.445204)
			)
		)
	)
	(zone
		(layer "In2.Cu")
		(hatch none 0.5)
		(connect_pads
			(clearance 0)
		)
		(min_thickness 0.25)
		(keepout
			(tracks not_allowed)
			(vias allowed)
			(pads allowed)
			(copperpour not_allowed)
			(footprints allowed)
		)
		(placement
			(enabled no)
			(sheetname "")
		)
		(fill
			(thermal_gap 0.5)
			(thermal_bridge_width 0.5)
			(island_removal_mode 0)
		)
		(polygon
			(pts
				(arc
					(start 48.562514 -408.923998)
					(mid 48.582438 -408.933234)
					(end 48.60417 -408.936444)
				)
				(arc
					(start 48.798734 -408.936444)
					(mid 48.852616 -408.914126)
					(end 48.874934 -408.860244)
				)
				(arc
					(start 48.874934 -408.174444)
					(mid 48.852616 -408.120562)
					(end 48.798734 -408.098244)
				)
				(arc
					(start 48.60417 -408.098244)
					(mid 48.582426 -408.101412)
					(end 48.562514 -408.11069)
				)
				(arc
					(start 48.26635 -408.303476)
					(mid 48.224666 -408.315698)
					(end 48.183038 -408.303222)
				)
				(arc
					(start 47.889414 -408.11069)
					(mid 47.86949 -408.101454)
					(end 47.847758 -408.098244)
				)
				(arc
					(start 47.653194 -408.098244)
					(mid 47.599312 -408.120562)
					(end 47.576994 -408.174444)
				)
				(arc
					(start 47.576994 -408.860244)
					(mid 47.599312 -408.914126)
					(end 47.653194 -408.936444)
				)
				(arc
					(start 47.849028 -408.936444)
					(mid 47.870772 -408.933276)
					(end 47.890684 -408.923998)
				)
				(arc
					(start 48.184308 -408.731466)
					(mid 48.225964 -408.719064)
					(end 48.26762 -408.731466)
				)
			)
		)
	)
	(zone
		(layer "In2.Cu")
		(hatch none 0.5)
		(connect_pads
			(clearance 0)
		)
		(min_thickness 0.25)
		(keepout
			(tracks allowed)
			(vias allowed)
			(pads allowed)
			(copperpour allowed)
			(footprints allowed)
		)
		(placement
			(enabled no)
			(sheetname "")
		)
		(fill
			(thermal_gap 0.5)
			(thermal_bridge_width 0.5)
			(island_removal_mode 0)
		)
		(polygon
			(pts
				(xy 383.163318 -178.284632) (xy 383.163318 -179.023772) (xy 382.927098 -179.023772) (xy 382.927098 -178.284632)
			)
		)
	)
	(zone
		(layer "In2.Cu")
		(hatch none 0.5)
		(connect_pads
			(clearance 0)
		)
		(min_thickness 0.25)
		(keepout
			(tracks not_allowed)
			(vias allowed)
			(pads allowed)
			(copperpour not_allowed)
			(footprints allowed)
		)
		(placement
			(enabled no)
			(sheetname "")
		)
		(fill
			(thermal_gap 0.5)
			(thermal_bridge_width 0.5)
			(island_removal_mode 0)
		)
		(polygon
			(pts
				(xy 426.706792 -285.475172) (xy 428.205392 -285.475172) (xy 428.205392 -285.99511) (xy 426.706792 -285.99511)
			)
		)
	)
	(zone
		(layer "In2.Cu")
		(hatch none 0.5)
		(connect_pads
			(clearance 0)
		)
		(min_thickness 0.25)
		(keepout
			(tracks not_allowed)
			(vias allowed)
			(pads allowed)
			(copperpour not_allowed)
			(footprints allowed)
		)
		(placement
			(enabled no)
			(sheetname "")
		)
		(fill
			(thermal_gap 0.5)
			(thermal_bridge_width 0.5)
			(island_removal_mode 0)
		)
		(polygon
			(pts
				(xy 299.07484 -298.22521) (xy 300.57344 -298.22521) (xy 300.57344 -298.745148) (xy 299.07484 -298.745148)
			)
		)
	)
	(zone
		(layer "In2.Cu")
		(hatch none 0.5)
		(connect_pads
			(clearance 0)
		)
		(min_thickness 0.25)
		(keepout
			(tracks not_allowed)
			(vias allowed)
			(pads allowed)
			(copperpour not_allowed)
			(footprints allowed)
		)
		(placement
			(enabled no)
			(sheetname "")
		)
		(fill
			(thermal_gap 0.5)
			(thermal_bridge_width 0.5)
			(island_removal_mode 0)
		)
		(polygon
			(pts
				(xy 276.442932 -208.125314) (xy 277.941532 -208.125314) (xy 277.941532 -208.645252) (xy 276.442932 -208.645252)
			)
		)
	)
	(zone
		(layer "In2.Cu")
		(hatch none 0.5)
		(connect_pads
			(clearance 0)
		)
		(min_thickness 0.25)
		(keepout
			(tracks not_allowed)
			(vias allowed)
			(pads allowed)
			(copperpour not_allowed)
			(footprints allowed)
		)
		(placement
			(enabled no)
			(sheetname "")
		)
		(fill
			(thermal_gap 0.5)
			(thermal_bridge_width 0.5)
			(island_removal_mode 0)
		)
		(polygon
			(pts
				(xy 411.618684 -289.725354) (xy 413.117284 -289.725354) (xy 413.117284 -290.245292) (xy 411.618684 -290.245292)
			)
		)
	)
	(zone
		(layer "In2.Cu")
		(hatch none 0.5)
		(connect_pads
			(clearance 0)
		)
		(min_thickness 0.25)
		(keepout
			(tracks not_allowed)
			(vias allowed)
			(pads allowed)
			(copperpour not_allowed)
			(footprints allowed)
		)
		(placement
			(enabled no)
			(sheetname "")
		)
		(fill
			(thermal_gap 0.5)
			(thermal_bridge_width 0.5)
			(island_removal_mode 0)
		)
		(polygon
			(pts
				(xy 411.618684 -253.175262) (xy 413.117284 -253.175262) (xy 413.117284 -253.6952) (xy 411.618684 -253.6952)
			)
		)
	)
	(zone
		(layer "In2.Cu")
		(hatch none 0.5)
		(connect_pads
			(clearance 0)
		)
		(min_thickness 0.25)
		(keepout
			(tracks not_allowed)
			(vias allowed)
			(pads allowed)
			(copperpour not_allowed)
			(footprints allowed)
		)
		(placement
			(enabled no)
			(sheetname "")
		)
		(fill
			(thermal_gap 0.5)
			(thermal_bridge_width 0.5)
			(island_removal_mode 0)
		)
		(polygon
			(pts
				(xy 419.162738 -285.475172) (xy 420.661338 -285.475172) (xy 420.661338 -285.99511) (xy 419.162738 -285.99511)
			)
		)
	)
	(zone
		(layer "In2.Cu")
		(hatch none 0.5)
		(connect_pads
			(clearance 0)
		)
		(min_thickness 0.25)
		(keepout
			(tracks not_allowed)
			(vias allowed)
			(pads allowed)
			(copperpour not_allowed)
			(footprints allowed)
		)
		(placement
			(enabled no)
			(sheetname "")
		)
		(fill
			(thermal_gap 0.5)
			(thermal_bridge_width 0.5)
			(island_removal_mode 0)
		)
		(polygon
			(pts
				(xy 16.858742 -251.47524) (xy 18.357342 -251.47524) (xy 18.357342 -251.995178) (xy 16.858742 -251.995178)
			)
		)
	)
	(zone
		(layer "In2.Cu")
		(hatch none 0.5)
		(connect_pads
			(clearance 0)
		)
		(min_thickness 0.25)
		(keepout
			(tracks not_allowed)
			(vias allowed)
			(pads allowed)
			(copperpour not_allowed)
			(footprints allowed)
		)
		(placement
			(enabled no)
			(sheetname "")
		)
		(fill
			(thermal_gap 0.5)
			(thermal_bridge_width 0.5)
			(island_removal_mode 0)
		)
		(polygon
			(pts
				(xy 306.618894 -200.475342) (xy 308.117494 -200.475342) (xy 308.117494 -200.99528) (xy 306.618894 -200.99528)
			)
		)
	)
	(zone
		(layer "In2.Cu")
		(hatch none 0.5)
		(connect_pads
			(clearance 0)
		)
		(min_thickness 0.25)
		(keepout
			(tracks not_allowed)
			(vias allowed)
			(pads allowed)
			(copperpour not_allowed)
			(footprints allowed)
		)
		(placement
			(enabled no)
			(sheetname "")
		)
		(fill
			(thermal_gap 0.5)
			(thermal_bridge_width 0.5)
			(island_removal_mode 0)
		)
		(polygon
			(pts
				(xy 190.410846 -217.475308) (xy 191.909446 -217.475308) (xy 191.909446 -217.995246) (xy 190.410846 -217.995246)
			)
		)
	)
	(zone
		(layer "In2.Cu")
		(hatch none 0.5)
		(connect_pads
			(clearance 0)
		)
		(min_thickness 0.25)
		(keepout
			(tracks not_allowed)
			(vias allowed)
			(pads allowed)
			(copperpour not_allowed)
			(footprints allowed)
		)
		(placement
			(enabled no)
			(sheetname "")
		)
		(fill
			(thermal_gap 0.5)
			(thermal_bridge_width 0.5)
			(island_removal_mode 0)
		)
		(polygon
			(pts
				(xy 411.618684 -308.425342) (xy 413.117284 -308.425342) (xy 413.117284 -308.94528) (xy 411.618684 -308.94528)
			)
		)
	)
	(zone
		(layer "In2.Cu")
		(hatch none 0.5)
		(connect_pads
			(clearance 0)
		)
		(min_thickness 0.25)
		(keepout
			(tracks not_allowed)
			(vias allowed)
			(pads allowed)
			(copperpour not_allowed)
			(footprints allowed)
		)
		(placement
			(enabled no)
			(sheetname "")
		)
		(fill
			(thermal_gap 0.5)
			(thermal_bridge_width 0.5)
			(island_removal_mode 0)
		)
		(polygon
			(pts
				(xy 426.706792 -313.525154) (xy 428.205392 -313.525154) (xy 428.205392 -314.045092) (xy 426.706792 -314.045092)
			)
		)
	)
	(zone
		(layer "In2.Cu")
		(hatch none 0.5)
		(connect_pads
			(clearance 0)
		)
		(min_thickness 0.25)
		(keepout
			(tracks not_allowed)
			(vias allowed)
			(pads allowed)
			(copperpour not_allowed)
			(footprints allowed)
		)
		(placement
			(enabled no)
			(sheetname "")
		)
		(fill
			(thermal_gap 0.5)
			(thermal_bridge_width 0.5)
			(island_removal_mode 0)
		)
		(polygon
			(pts
				(xy 24.402542 -213.225126) (xy 25.901142 -213.225126) (xy 25.901142 -213.745064) (xy 24.402542 -213.745064)
			)
		)
	)
	(zone
		(layer "In2.Cu")
		(hatch none 0.5)
		(connect_pads
			(clearance 0)
		)
		(min_thickness 0.25)
		(keepout
			(tracks not_allowed)
			(vias allowed)
			(pads allowed)
			(copperpour not_allowed)
			(footprints allowed)
		)
		(placement
			(enabled no)
			(sheetname "")
		)
		(fill
			(thermal_gap 0.5)
			(thermal_bridge_width 0.5)
			(island_removal_mode 0)
		)
		(polygon
			(pts
				(xy 201.398632 -306.72532) (xy 202.897232 -306.72532) (xy 202.897232 -307.245258) (xy 201.398632 -307.245258)
			)
		)
	)
	(zone
		(layer "In2.Cu")
		(hatch none 0.5)
		(connect_pads
			(clearance 0)
		)
		(min_thickness 0.25)
		(keepout
			(tracks not_allowed)
			(vias allowed)
			(pads allowed)
			(copperpour not_allowed)
			(footprints allowed)
		)
		(placement
			(enabled no)
			(sheetname "")
		)
		(fill
			(thermal_gap 0.5)
			(thermal_bridge_width 0.5)
			(island_removal_mode 0)
		)
		(polygon
			(pts
				(xy 31.946596 -302.475138) (xy 33.445196 -302.475138) (xy 33.445196 -302.995076) (xy 31.946596 -302.995076)
			)
		)
	)
	(zone
		(layer "In2.Cu")
		(hatch none 0.5)
		(connect_pads
			(clearance 0)
		)
		(min_thickness 0.25)
		(keepout
			(tracks not_allowed)
			(vias allowed)
			(pads allowed)
			(copperpour not_allowed)
			(footprints allowed)
		)
		(placement
			(enabled no)
			(sheetname "")
		)
		(fill
			(thermal_gap 0.5)
			(thermal_bridge_width 0.5)
			(island_removal_mode 0)
		)
		(polygon
			(pts
				(xy 287.430718 -227.675186) (xy 288.929318 -227.675186) (xy 288.929318 -228.195124) (xy 287.430718 -228.195124)
			)
		)
	)
	(zone
		(layer "In2.Cu")
		(hatch none 0.5)
		(connect_pads
			(clearance 0)
		)
		(min_thickness 0.25)
		(keepout
			(tracks not_allowed)
			(vias allowed)
			(pads allowed)
			(copperpour not_allowed)
			(footprints allowed)
		)
		(placement
			(enabled no)
			(sheetname "")
		)
		(fill
			(thermal_gap 0.5)
			(thermal_bridge_width 0.5)
			(island_removal_mode 0)
		)
		(polygon
			(pts
				(xy 193.854578 -248.075196) (xy 195.353178 -248.075196) (xy 195.353178 -248.595134) (xy 193.854578 -248.595134)
			)
		)
	)
	(zone
		(layer "In2.Cu")
		(hatch none 0.5)
		(connect_pads
			(clearance 0)
		)
		(min_thickness 0.25)
		(keepout
			(tracks not_allowed)
			(vias allowed)
			(pads allowed)
			(copperpour not_allowed)
			(footprints allowed)
		)
		(placement
			(enabled no)
			(sheetname "")
		)
		(fill
			(thermal_gap 0.5)
			(thermal_bridge_width 0.5)
			(island_removal_mode 0)
		)
		(polygon
			(pts
				(xy 47.034704 -295.675304) (xy 48.533304 -295.675304) (xy 48.533304 -296.195242) (xy 47.034704 -296.195242)
			)
		)
	)
	(zone
		(layer "In2.Cu")
		(hatch none 0.5)
		(connect_pads
			(clearance 0)
		)
		(min_thickness 0.25)
		(keepout
			(tracks not_allowed)
			(vias allowed)
			(pads allowed)
			(copperpour not_allowed)
			(footprints allowed)
		)
		(placement
			(enabled no)
			(sheetname "")
		)
		(fill
			(thermal_gap 0.5)
			(thermal_bridge_width 0.5)
			(island_removal_mode 0)
		)
		(polygon
			(pts
				(xy 449.3387 -251.47524) (xy 450.8373 -251.47524) (xy 450.8373 -251.995178) (xy 449.3387 -251.995178)
			)
		)
	)
	(zone
		(layer "In2.Cu")
		(hatch none 0.5)
		(connect_pads
			(clearance 0)
		)
		(min_thickness 0.25)
		(keepout
			(tracks not_allowed)
			(vias allowed)
			(pads allowed)
			(copperpour not_allowed)
			(footprints allowed)
		)
		(placement
			(enabled no)
			(sheetname "")
		)
		(fill
			(thermal_gap 0.5)
			(thermal_bridge_width 0.5)
			(island_removal_mode 0)
		)
		(polygon
			(pts
				(xy 438.350914 -197.075298) (xy 439.849514 -197.075298) (xy 439.849514 -197.595236) (xy 438.350914 -197.595236)
			)
		)
	)
	(zone
		(layer "In2.Cu")
		(hatch none 0.5)
		(connect_pads
			(clearance 0)
		)
		(min_thickness 0.25)
		(keepout
			(tracks not_allowed)
			(vias allowed)
			(pads allowed)
			(copperpour not_allowed)
			(footprints allowed)
		)
		(placement
			(enabled no)
			(sheetname "")
		)
		(fill
			(thermal_gap 0.5)
			(thermal_bridge_width 0.5)
			(island_removal_mode 0)
		)
		(polygon
			(pts
				(xy 453.438768 -282.925266) (xy 454.937368 -282.925266) (xy 454.937368 -283.445204) (xy 453.438768 -283.445204)
			)
		)
	)
	(zone
		(layer "In2.Cu")
		(hatch none 0.5)
		(connect_pads
			(clearance 0)
		)
		(min_thickness 0.25)
		(keepout
			(tracks not_allowed)
			(vias allowed)
			(pads allowed)
			(copperpour not_allowed)
			(footprints allowed)
		)
		(placement
			(enabled no)
			(sheetname "")
		)
		(fill
			(thermal_gap 0.5)
			(thermal_bridge_width 0.5)
			(island_removal_mode 0)
		)
		(polygon
			(pts
				(xy 20.95881 -238.725202) (xy 22.45741 -238.725202) (xy 22.45741 -239.24514) (xy 20.95881 -239.24514)
			)
		)
	)
	(zone
		(layer "In2.Cu")
		(hatch none 0.5)
		(connect_pads
			(clearance 0)
		)
		(min_thickness 0.25)
		(keepout
			(tracks not_allowed)
			(vias allowed)
			(pads allowed)
			(copperpour not_allowed)
			(footprints allowed)
		)
		(placement
			(enabled no)
			(sheetname "")
		)
		(fill
			(thermal_gap 0.5)
			(thermal_bridge_width 0.5)
			(island_removal_mode 0)
		)
		(polygon
			(pts
				(xy 20.95881 -299.925232) (xy 22.45741 -299.925232) (xy 22.45741 -300.44517) (xy 20.95881 -300.44517)
			)
		)
	)
	(zone
		(layer "In2.Cu")
		(hatch none 0.5)
		(connect_pads
			(clearance 0)
		)
		(min_thickness 0.25)
		(keepout
			(tracks not_allowed)
			(vias allowed)
			(pads allowed)
			(copperpour not_allowed)
			(footprints allowed)
		)
		(placement
			(enabled no)
			(sheetname "")
		)
		(fill
			(thermal_gap 0.5)
			(thermal_bridge_width 0.5)
			(island_removal_mode 0)
		)
		(polygon
			(pts
				(xy 299.07484 -315.225176) (xy 300.57344 -315.225176) (xy 300.57344 -315.745114) (xy 299.07484 -315.745114)
			)
		)
	)
	(zone
		(layer "In2.Cu")
		(hatch none 0.5)
		(connect_pads
			(clearance 0)
		)
		(min_thickness 0.25)
		(keepout
			(tracks not_allowed)
			(vias allowed)
			(pads allowed)
			(copperpour not_allowed)
			(footprints allowed)
		)
		(placement
			(enabled no)
			(sheetname "")
		)
		(fill
			(thermal_gap 0.5)
			(thermal_bridge_width 0.5)
			(island_removal_mode 0)
		)
		(polygon
			(pts
				(xy 430.80686 -238.725202) (xy 432.30546 -238.725202) (xy 432.30546 -239.24514) (xy 430.80686 -239.24514)
			)
		)
	)
	(zone
		(layer "In2.Cu")
		(hatch none 0.5)
		(connect_pads
			(clearance 0)
		)
		(min_thickness 0.25)
		(keepout
			(tracks not_allowed)
			(vias allowed)
			(pads allowed)
			(copperpour not_allowed)
			(footprints allowed)
		)
		(placement
			(enabled no)
			(sheetname "")
		)
		(fill
			(thermal_gap 0.5)
			(thermal_bridge_width 0.5)
			(island_removal_mode 0)
		)
		(polygon
			(pts
				(xy 272.342864 -293.125144) (xy 273.841464 -293.125144) (xy 273.841464 -293.645082) (xy 272.342864 -293.645082)
			)
		)
	)
	(zone
		(layer "In2.Cu")
		(hatch none 0.5)
		(connect_pads
			(clearance 0)
		)
		(min_thickness 0.25)
		(keepout
			(tracks not_allowed)
			(vias allowed)
			(pads allowed)
			(copperpour not_allowed)
			(footprints allowed)
		)
		(placement
			(enabled no)
			(sheetname "")
		)
		(fill
			(thermal_gap 0.5)
			(thermal_bridge_width 0.5)
			(island_removal_mode 0)
		)
		(polygon
			(pts
				(xy 175.322738 -208.125314) (xy 176.821338 -208.125314) (xy 176.821338 -208.645252) (xy 175.322738 -208.645252)
			)
		)
	)
	(zone
		(layer "In2.Cu")
		(hatch none 0.5)
		(connect_pads
			(clearance 0)
		)
		(min_thickness 0.25)
		(keepout
			(tracks not_allowed)
			(vias allowed)
			(pads allowed)
			(copperpour not_allowed)
			(footprints allowed)
		)
		(placement
			(enabled no)
			(sheetname "")
		)
		(fill
			(thermal_gap 0.5)
			(thermal_bridge_width 0.5)
			(island_removal_mode 0)
		)
		(polygon
			(pts
				(xy 438.350914 -313.525154) (xy 439.849514 -313.525154) (xy 439.849514 -314.045092) (xy 438.350914 -314.045092)
			)
		)
	)
	(zone
		(layer "In2.Cu")
		(hatch none 0.5)
		(connect_pads
			(clearance 0)
		)
		(min_thickness 0.25)
		(keepout
			(tracks not_allowed)
			(vias allowed)
			(pads allowed)
			(copperpour not_allowed)
			(footprints allowed)
		)
		(placement
			(enabled no)
			(sheetname "")
		)
		(fill
			(thermal_gap 0.5)
			(thermal_bridge_width 0.5)
			(island_removal_mode 0)
		)
		(polygon
			(pts
				(xy 36.046664 -243.825268) (xy 37.545264 -243.825268) (xy 37.545264 -244.345206) (xy 36.046664 -244.345206)
			)
		)
	)
	(zone
		(layer "In2.Cu")
		(hatch none 0.5)
		(connect_pads
			(clearance 0)
		)
		(min_thickness 0.25)
		(keepout
			(tracks not_allowed)
			(vias allowed)
			(pads allowed)
			(copperpour not_allowed)
			(footprints allowed)
		)
		(placement
			(enabled no)
			(sheetname "")
		)
		(fill
			(thermal_gap 0.5)
			(thermal_bridge_width 0.5)
			(island_removal_mode 0)
		)
		(polygon
			(pts
				(xy 54.578758 -317.775336) (xy 56.077358 -317.775336) (xy 56.077358 -318.295274) (xy 54.578758 -318.295274)
			)
		)
	)
	(zone
		(layer "In2.Cu")
		(hatch none 0.5)
		(connect_pads
			(clearance 0)
		)
		(min_thickness 0.25)
		(keepout
			(tracks not_allowed)
			(vias allowed)
			(pads allowed)
			(copperpour not_allowed)
			(footprints allowed)
		)
		(placement
			(enabled no)
			(sheetname "")
		)
		(fill
			(thermal_gap 0.5)
			(thermal_bridge_width 0.5)
			(island_removal_mode 0)
		)
		(polygon
			(pts
				(xy 299.07484 -267.625322) (xy 300.57344 -267.625322) (xy 300.57344 -268.14526) (xy 299.07484 -268.14526)
			)
		)
	)
	(zone
		(layer "In2.Cu")
		(hatch none 0.5)
		(connect_pads
			(clearance 0)
		)
		(min_thickness 0.25)
		(keepout
			(tracks not_allowed)
			(vias allowed)
			(pads allowed)
			(copperpour not_allowed)
			(footprints allowed)
		)
		(placement
			(enabled no)
			(sheetname "")
		)
		(fill
			(thermal_gap 0.5)
			(thermal_bridge_width 0.5)
			(island_removal_mode 0)
		)
		(polygon
			(pts
				(xy 54.578758 -285.475172) (xy 56.077358 -285.475172) (xy 56.077358 -285.99511) (xy 54.578758 -285.99511)
			)
		)
	)
	(zone
		(layer "In2.Cu")
		(hatch none 0.5)
		(connect_pads
			(clearance 0)
		)
		(min_thickness 0.25)
		(keepout
			(tracks not_allowed)
			(vias allowed)
			(pads allowed)
			(copperpour not_allowed)
			(footprints allowed)
		)
		(placement
			(enabled no)
			(sheetname "")
		)
		(fill
			(thermal_gap 0.5)
			(thermal_bridge_width 0.5)
			(island_removal_mode 0)
		)
		(polygon
			(pts
				(xy 54.578758 -222.57512) (xy 56.077358 -222.57512) (xy 56.077358 -223.095058) (xy 54.578758 -223.095058)
			)
		)
	)
	(zone
		(layer "In2.Cu")
		(hatch none 0.5)
		(connect_pads
			(clearance 0)
		)
		(min_thickness 0.25)
		(keepout
			(tracks not_allowed)
			(vias allowed)
			(pads allowed)
			(copperpour not_allowed)
			(footprints allowed)
		)
		(placement
			(enabled no)
			(sheetname "")
		)
		(fill
			(thermal_gap 0.5)
			(thermal_bridge_width 0.5)
			(island_removal_mode 0)
		)
		(polygon
			(pts
				(xy 31.946596 -288.025332) (xy 33.445196 -288.025332) (xy 33.445196 -288.54527) (xy 31.946596 -288.54527)
			)
		)
	)
	(zone
		(layer "In2.Cu")
		(hatch none 0.5)
		(connect_pads
			(clearance 0)
		)
		(min_thickness 0.25)
		(keepout
			(tracks not_allowed)
			(vias allowed)
			(pads allowed)
			(copperpour not_allowed)
			(footprints allowed)
		)
		(placement
			(enabled no)
			(sheetname "")
		)
		(fill
			(thermal_gap 0.5)
			(thermal_bridge_width 0.5)
			(island_removal_mode 0)
		)
		(polygon
			(pts
				(xy 419.162738 -286.32531) (xy 420.661338 -286.32531) (xy 420.661338 -286.845248) (xy 419.162738 -286.845248)
			)
		)
	)
	(zone
		(layer "In2.Cu")
		(hatch none 0.5)
		(connect_pads
			(clearance 0)
		)
		(min_thickness 0.25)
		(keepout
			(tracks not_allowed)
			(vias allowed)
			(pads allowed)
			(copperpour not_allowed)
			(footprints allowed)
		)
		(placement
			(enabled no)
			(sheetname "")
		)
		(fill
			(thermal_gap 0.5)
			(thermal_bridge_width 0.5)
			(island_removal_mode 0)
		)
		(polygon
			(pts
				(xy 411.618684 -249.775218) (xy 413.117284 -249.775218) (xy 413.117284 -250.295156) (xy 411.618684 -250.295156)
			)
		)
	)
	(zone
		(layer "In2.Cu")
		(hatch none 0.5)
		(connect_pads
			(clearance 0)
		)
		(min_thickness 0.25)
		(keepout
			(tracks not_allowed)
			(vias allowed)
			(pads allowed)
			(copperpour not_allowed)
			(footprints allowed)
		)
		(placement
			(enabled no)
			(sheetname "")
		)
		(fill
			(thermal_gap 0.5)
			(thermal_bridge_width 0.5)
			(island_removal_mode 0)
		)
		(polygon
			(pts
				(xy 201.398632 -249.775218) (xy 202.897232 -249.775218) (xy 202.897232 -250.295156) (xy 201.398632 -250.295156)
			)
		)
	)
	(zone
		(layer "In2.Cu")
		(hatch none 0.5)
		(connect_pads
			(clearance 0)
		)
		(min_thickness 0.25)
		(keepout
			(tracks not_allowed)
			(vias allowed)
			(pads allowed)
			(copperpour not_allowed)
			(footprints allowed)
		)
		(placement
			(enabled no)
			(sheetname "")
		)
		(fill
			(thermal_gap 0.5)
			(thermal_bridge_width 0.5)
			(island_removal_mode 0)
		)
		(polygon
			(pts
				(xy 411.618684 -276.975316) (xy 413.117284 -276.975316) (xy 413.117284 -277.495254) (xy 411.618684 -277.495254)
			)
		)
	)
	(zone
		(layer "In2.Cu")
		(hatch none 0.5)
		(connect_pads
			(clearance 0)
		)
		(min_thickness 0.25)
		(keepout
			(tracks not_allowed)
			(vias allowed)
			(pads allowed)
			(copperpour not_allowed)
			(footprints allowed)
		)
		(placement
			(enabled no)
			(sheetname "")
		)
		(fill
			(thermal_gap 0.5)
			(thermal_bridge_width 0.5)
			(island_removal_mode 0)
		)
		(polygon
			(pts
				(xy 299.07484 -254.025146) (xy 300.57344 -254.025146) (xy 300.57344 -254.545084) (xy 299.07484 -254.545084)
			)
		)
	)
	(zone
		(layer "In2.Cu")
		(hatch none 0.5)
		(connect_pads
			(clearance 0)
		)
		(min_thickness 0.25)
		(keepout
			(tracks not_allowed)
			(vias allowed)
			(pads allowed)
			(copperpour not_allowed)
			(footprints allowed)
		)
		(placement
			(enabled no)
			(sheetname "")
		)
		(fill
			(thermal_gap 0.5)
			(thermal_bridge_width 0.5)
			(island_removal_mode 0)
		)
		(polygon
			(pts
				(xy 58.678826 -309.275226) (xy 60.177426 -309.275226) (xy 60.177426 -309.795164) (xy 58.678826 -309.795164)
			)
		)
	)
	(zone
		(layer "In2.Cu")
		(hatch none 0.5)
		(connect_pads
			(clearance 0)
		)
		(min_thickness 0.25)
		(keepout
			(tracks not_allowed)
			(vias allowed)
			(pads allowed)
			(copperpour not_allowed)
			(footprints allowed)
		)
		(placement
			(enabled no)
			(sheetname "")
		)
		(fill
			(thermal_gap 0.5)
			(thermal_bridge_width 0.5)
			(island_removal_mode 0)
		)
		(polygon
			(pts
				(xy 20.95881 -305.875182) (xy 22.45741 -305.875182) (xy 22.45741 -306.39512) (xy 20.95881 -306.39512)
			)
		)
	)
	(zone
		(layer "In2.Cu")
		(hatch none 0.5)
		(connect_pads
			(clearance 0)
		)
		(min_thickness 0.25)
		(keepout
			(tracks not_allowed)
			(vias allowed)
			(pads allowed)
			(copperpour not_allowed)
			(footprints allowed)
		)
		(placement
			(enabled no)
			(sheetname "")
		)
		(fill
			(thermal_gap 0.5)
			(thermal_bridge_width 0.5)
			(island_removal_mode 0)
		)
		(polygon
			(pts
				(xy 415.718752 -203.025248) (xy 417.217352 -203.025248) (xy 417.217352 -203.545186) (xy 415.718752 -203.545186)
			)
		)
	)
	(zone
		(layer "In2.Cu")
		(hatch none 0.5)
		(connect_pads
			(clearance 0)
		)
		(min_thickness 0.25)
		(keepout
			(tracks not_allowed)
			(vias allowed)
			(pads allowed)
			(copperpour not_allowed)
			(footprints allowed)
		)
		(placement
			(enabled no)
			(sheetname "")
		)
		(fill
			(thermal_gap 0.5)
			(thermal_bridge_width 0.5)
			(island_removal_mode 0)
		)
		(polygon
			(pts
				(xy 299.07484 -206.425292) (xy 300.57344 -206.425292) (xy 300.57344 -206.94523) (xy 299.07484 -206.94523)
			)
		)
	)
	(zone
		(layer "In2.Cu")
		(hatch none 0.5)
		(connect_pads
			(clearance 0)
		)
		(min_thickness 0.25)
		(keepout
			(tracks not_allowed)
			(vias allowed)
			(pads allowed)
			(copperpour not_allowed)
			(footprints allowed)
		)
		(placement
			(enabled no)
			(sheetname "")
		)
		(fill
			(thermal_gap 0.5)
			(thermal_bridge_width 0.5)
			(island_removal_mode 0)
		)
		(polygon
			(pts
				(xy 31.946596 -235.325158) (xy 33.445196 -235.325158) (xy 33.445196 -235.845096) (xy 31.946596 -235.845096)
			)
		)
	)
	(zone
		(layer "In2.Cu")
		(hatch none 0.5)
		(connect_pads
			(clearance 0)
		)
		(min_thickness 0.25)
		(keepout
			(tracks not_allowed)
			(vias allowed)
			(pads allowed)
			(copperpour not_allowed)
			(footprints allowed)
		)
		(placement
			(enabled no)
			(sheetname "")
		)
		(fill
			(thermal_gap 0.5)
			(thermal_bridge_width 0.5)
			(island_removal_mode 0)
		)
		(polygon
			(pts
				(xy 272.342864 -220.875098) (xy 273.841464 -220.875098) (xy 273.841464 -221.395036) (xy 272.342864 -221.395036)
			)
		)
	)
	(zone
		(layer "In2.Cu")
		(hatch none 0.5)
		(connect_pads
			(clearance 0)
		)
		(min_thickness 0.25)
		(keepout
			(tracks not_allowed)
			(vias allowed)
			(pads allowed)
			(copperpour not_allowed)
			(footprints allowed)
		)
		(placement
			(enabled no)
			(sheetname "")
		)
		(fill
			(thermal_gap 0.5)
			(thermal_bridge_width 0.5)
			(island_removal_mode 0)
		)
		(polygon
			(pts
				(xy 434.250846 -266.775184) (xy 435.749446 -266.775184) (xy 435.749446 -267.295122) (xy 434.250846 -267.295122)
			)
		)
	)
	(zone
		(layer "In2.Cu")
		(hatch none 0.5)
		(connect_pads
			(clearance 0)
		)
		(min_thickness 0.25)
		(keepout
			(tracks not_allowed)
			(vias allowed)
			(pads allowed)
			(copperpour not_allowed)
			(footprints allowed)
		)
		(placement
			(enabled no)
			(sheetname "")
		)
		(fill
			(thermal_gap 0.5)
			(thermal_bridge_width 0.5)
			(island_removal_mode 0)
		)
		(polygon
			(pts
				(xy 287.430718 -246.375174) (xy 288.929318 -246.375174) (xy 288.929318 -246.895112) (xy 287.430718 -246.895112)
			)
		)
	)
	(zone
		(layer "In2.Cu")
		(hatch none 0.5)
		(connect_pads
			(clearance 0)
		)
		(min_thickness 0.25)
		(keepout
			(tracks not_allowed)
			(vias allowed)
			(pads allowed)
			(copperpour not_allowed)
			(footprints allowed)
		)
		(placement
			(enabled no)
			(sheetname "")
		)
		(fill
			(thermal_gap 0.5)
			(thermal_bridge_width 0.5)
			(island_removal_mode 0)
		)
		(polygon
			(pts
				(xy 445.894968 -260.825234) (xy 447.393568 -260.825234) (xy 447.393568 -261.345172) (xy 445.894968 -261.345172)
			)
		)
	)
	(zone
		(layer "In2.Cu")
		(hatch none 0.5)
		(connect_pads
			(clearance 0)
		)
		(min_thickness 0.25)
		(keepout
			(tracks not_allowed)
			(vias allowed)
			(pads allowed)
			(copperpour not_allowed)
			(footprints allowed)
		)
		(placement
			(enabled no)
			(sheetname "")
		)
		(fill
			(thermal_gap 0.5)
			(thermal_bridge_width 0.5)
			(island_removal_mode 0)
		)
		(polygon
			(pts
				(xy 430.80686 -252.325124) (xy 432.30546 -252.325124) (xy 432.30546 -252.845062) (xy 430.80686 -252.845062)
			)
		)
	)
	(zone
		(layer "In2.Cu")
		(hatch none 0.5)
		(connect_pads
			(clearance 0)
		)
		(min_thickness 0.25)
		(keepout
			(tracks not_allowed)
			(vias allowed)
			(pads allowed)
			(copperpour not_allowed)
			(footprints allowed)
		)
		(placement
			(enabled no)
			(sheetname "")
		)
		(fill
			(thermal_gap 0.5)
			(thermal_bridge_width 0.5)
			(island_removal_mode 0)
		)
		(polygon
			(pts
				(xy 306.618894 -299.925232) (xy 308.117494 -299.925232) (xy 308.117494 -300.44517) (xy 306.618894 -300.44517)
			)
		)
	)
	(zone
		(layer "In2.Cu")
		(hatch none 0.5)
		(connect_pads
			(clearance 0)
		)
		(min_thickness 0.25)
		(keepout
			(tracks not_allowed)
			(vias allowed)
			(pads allowed)
			(copperpour not_allowed)
			(footprints allowed)
		)
		(placement
			(enabled no)
			(sheetname "")
		)
		(fill
			(thermal_gap 0.5)
			(thermal_bridge_width 0.5)
			(island_removal_mode 0)
		)
		(polygon
			(pts
				(xy 24.402542 -216.62517) (xy 25.901142 -216.62517) (xy 25.901142 -217.145108) (xy 24.402542 -217.145108)
			)
		)
	)
	(zone
		(layer "In2.Cu")
		(hatch none 0.5)
		(connect_pads
			(clearance 0)
		)
		(min_thickness 0.25)
		(keepout
			(tracks not_allowed)
			(vias allowed)
			(pads allowed)
			(copperpour not_allowed)
			(footprints allowed)
		)
		(placement
			(enabled no)
			(sheetname "")
		)
		(fill
			(thermal_gap 0.5)
			(thermal_bridge_width 0.5)
			(island_removal_mode 0)
		)
		(polygon
			(pts
				(xy 190.410846 -226.825302) (xy 191.909446 -226.825302) (xy 191.909446 -227.34524) (xy 190.410846 -227.34524)
			)
		)
	)
	(zone
		(layer "In2.Cu")
		(hatch none 0.5)
		(connect_pads
			(clearance 0)
		)
		(min_thickness 0.25)
		(keepout
			(tracks not_allowed)
			(vias allowed)
			(pads allowed)
			(copperpour not_allowed)
			(footprints allowed)
		)
		(placement
			(enabled no)
			(sheetname "")
		)
		(fill
			(thermal_gap 0.5)
			(thermal_bridge_width 0.5)
			(island_removal_mode 0)
		)
		(polygon
			(pts
				(xy 279.886664 -239.57534) (xy 281.385264 -239.57534) (xy 281.385264 -240.095278) (xy 279.886664 -240.095278)
			)
		)
	)
	(zone
		(layer "In2.Cu")
		(hatch none 0.5)
		(connect_pads
			(clearance 0)
		)
		(min_thickness 0.25)
		(keepout
			(tracks not_allowed)
			(vias allowed)
			(pads allowed)
			(copperpour not_allowed)
			(footprints allowed)
		)
		(placement
			(enabled no)
			(sheetname "")
		)
		(fill
			(thermal_gap 0.5)
			(thermal_bridge_width 0.5)
			(island_removal_mode 0)
		)
		(polygon
			(pts
				(xy 36.046664 -200.475342) (xy 37.545264 -200.475342) (xy 37.545264 -200.99528) (xy 36.046664 -200.99528)
			)
		)
	)
	(zone
		(layer "In2.Cu")
		(hatch none 0.5)
		(connect_pads
			(clearance 0)
		)
		(min_thickness 0.25)
		(keepout
			(tracks not_allowed)
			(vias allowed)
			(pads allowed)
			(copperpour not_allowed)
			(footprints allowed)
		)
		(placement
			(enabled no)
			(sheetname "")
		)
		(fill
			(thermal_gap 0.5)
			(thermal_bridge_width 0.5)
			(island_removal_mode 0)
		)
		(polygon
			(pts
				(xy 438.350914 -287.175194) (xy 439.849514 -287.175194) (xy 439.849514 -287.695132) (xy 438.350914 -287.695132)
			)
		)
	)
	(zone
		(layer "In2.Cu")
		(hatch none 0.5)
		(connect_pads
			(clearance 0)
		)
		(min_thickness 0.25)
		(keepout
			(tracks not_allowed)
			(vias allowed)
			(pads allowed)
			(copperpour not_allowed)
			(footprints allowed)
		)
		(placement
			(enabled no)
			(sheetname "")
		)
		(fill
			(thermal_gap 0.5)
			(thermal_bridge_width 0.5)
			(island_removal_mode 0)
		)
		(polygon
			(pts
				(xy 430.80686 -240.425224) (xy 432.30546 -240.425224) (xy 432.30546 -240.945162) (xy 430.80686 -240.945162)
			)
		)
	)
	(zone
		(layer "In2.Cu")
		(hatch none 0.5)
		(connect_pads
			(clearance 0)
		)
		(min_thickness 0.25)
		(keepout
			(tracks not_allowed)
			(vias allowed)
			(pads allowed)
			(copperpour not_allowed)
			(footprints allowed)
		)
		(placement
			(enabled no)
			(sheetname "")
		)
		(fill
			(thermal_gap 0.5)
			(thermal_bridge_width 0.5)
			(island_removal_mode 0)
		)
		(polygon
			(pts
				(xy 167.778684 -214.075264) (xy 169.277284 -214.075264) (xy 169.277284 -214.595202) (xy 167.778684 -214.595202)
			)
		)
	)
	(zone
		(layer "In2.Cu")
		(hatch none 0.5)
		(connect_pads
			(clearance 0)
		)
		(min_thickness 0.25)
		(keepout
			(tracks not_allowed)
			(vias allowed)
			(pads allowed)
			(copperpour not_allowed)
			(footprints allowed)
		)
		(placement
			(enabled no)
			(sheetname "")
		)
		(fill
			(thermal_gap 0.5)
			(thermal_bridge_width 0.5)
			(island_removal_mode 0)
		)
		(polygon
			(pts
				(xy 190.410846 -294.825166) (xy 191.909446 -294.825166) (xy 191.909446 -295.345104) (xy 190.410846 -295.345104)
			)
		)
	)
	(zone
		(layer "In2.Cu")
		(hatch none 0.5)
		(connect_pads
			(clearance 0)
		)
		(min_thickness 0.25)
		(keepout
			(tracks not_allowed)
			(vias allowed)
			(pads allowed)
			(copperpour not_allowed)
			(footprints allowed)
		)
		(placement
			(enabled no)
			(sheetname "")
		)
		(fill
			(thermal_gap 0.5)
			(thermal_bridge_width 0.5)
			(island_removal_mode 0)
		)
		(polygon
			(pts
				(xy 279.886664 -299.075348) (xy 281.385264 -299.075348) (xy 281.385264 -299.595286) (xy 279.886664 -299.595286)
			)
		)
	)
	(zone
		(layer "In2.Cu")
		(hatch none 0.5)
		(connect_pads
			(clearance 0)
		)
		(min_thickness 0.25)
		(keepout
			(tracks not_allowed)
			(vias allowed)
			(pads allowed)
			(copperpour not_allowed)
			(footprints allowed)
		)
		(placement
			(enabled no)
			(sheetname "")
		)
		(fill
			(thermal_gap 0.5)
			(thermal_bridge_width 0.5)
			(island_removal_mode 0)
		)
		(polygon
			(pts
				(xy 411.618684 -210.67522) (xy 413.117284 -210.67522) (xy 413.117284 -211.195158) (xy 411.618684 -211.195158)
			)
		)
	)
	(zone
		(layer "In2.Cu")
		(hatch none 0.5)
		(connect_pads
			(clearance 0)
		)
		(min_thickness 0.25)
		(keepout
			(tracks not_allowed)
			(vias allowed)
			(pads allowed)
			(copperpour not_allowed)
			(footprints allowed)
		)
		(placement
			(enabled no)
			(sheetname "")
		)
		(fill
			(thermal_gap 0.5)
			(thermal_bridge_width 0.5)
			(island_removal_mode 0)
		)
		(polygon
			(pts
				(xy 453.438768 -276.125178) (xy 454.937368 -276.125178) (xy 454.937368 -276.645116) (xy 453.438768 -276.645116)
			)
		)
	)
	(zone
		(layer "In2.Cu")
		(hatch none 0.5)
		(connect_pads
			(clearance 0)
		)
		(min_thickness 0.25)
		(keepout
			(tracks not_allowed)
			(vias allowed)
			(pads allowed)
			(copperpour not_allowed)
			(footprints allowed)
		)
		(placement
			(enabled no)
			(sheetname "")
		)
		(fill
			(thermal_gap 0.5)
			(thermal_bridge_width 0.5)
			(island_removal_mode 0)
		)
		(polygon
			(pts
				(xy 279.886664 -272.725134) (xy 281.385264 -272.725134) (xy 281.385264 -273.245072) (xy 279.886664 -273.245072)
			)
		)
	)
	(zone
		(layer "In2.Cu")
		(hatch none 0.5)
		(connect_pads
			(clearance 0)
		)
		(min_thickness 0.25)
		(keepout
			(tracks not_allowed)
			(vias allowed)
			(pads allowed)
			(copperpour not_allowed)
			(footprints allowed)
		)
		(placement
			(enabled no)
			(sheetname "")
		)
		(fill
			(thermal_gap 0.5)
			(thermal_bridge_width 0.5)
			(island_removal_mode 0)
		)
		(polygon
			(pts
				(xy 415.718752 -260.825234) (xy 417.217352 -260.825234) (xy 417.217352 -261.345172) (xy 415.718752 -261.345172)
			)
		)
	)
	(zone
		(layer "In2.Cu")
		(hatch none 0.5)
		(connect_pads
			(clearance 0)
		)
		(min_thickness 0.25)
		(keepout
			(tracks not_allowed)
			(vias allowed)
			(pads allowed)
			(copperpour not_allowed)
			(footprints allowed)
		)
		(placement
			(enabled no)
			(sheetname "")
		)
		(fill
			(thermal_gap 0.5)
			(thermal_bridge_width 0.5)
			(island_removal_mode 0)
		)
		(polygon
			(pts
				(xy 36.046664 -212.375242) (xy 37.545264 -212.375242) (xy 37.545264 -212.89518) (xy 36.046664 -212.89518)
			)
		)
	)
	(zone
		(layer "In2.Cu")
		(hatch none 0.5)
		(connect_pads
			(clearance 0)
		)
		(min_thickness 0.25)
		(keepout
			(tracks not_allowed)
			(vias allowed)
			(pads allowed)
			(copperpour not_allowed)
			(footprints allowed)
		)
		(placement
			(enabled no)
			(sheetname "")
		)
		(fill
			(thermal_gap 0.5)
			(thermal_bridge_width 0.5)
			(island_removal_mode 0)
		)
		(polygon
			(pts
				(xy 438.350914 -231.07523) (xy 439.849514 -231.07523) (xy 439.849514 -231.595168) (xy 438.350914 -231.595168)
			)
		)
	)
	(zone
		(layer "In2.Cu")
		(hatch none 0.5)
		(connect_pads
			(clearance 0)
		)
		(min_thickness 0.25)
		(keepout
			(tracks allowed)
			(vias allowed)
			(pads allowed)
			(copperpour allowed)
			(footprints allowed)
		)
		(placement
			(enabled no)
			(sheetname "")
		)
		(fill
			(thermal_gap 0.5)
			(thermal_bridge_width 0.5)
			(island_removal_mode 0)
		)
		(polygon
			(pts
				(xy 294.55237 -349.117666) (xy 294.55237 -348.495366) (xy 295.10355 -348.495366) (xy 295.10355 -349.117666)
			)
		)
	)
	(zone
		(layer "In2.Cu")
		(hatch none 0.5)
		(connect_pads
			(clearance 0)
		)
		(min_thickness 0.25)
		(keepout
			(tracks not_allowed)
			(vias allowed)
			(pads allowed)
			(copperpour not_allowed)
			(footprints allowed)
		)
		(placement
			(enabled no)
			(sheetname "")
		)
		(fill
			(thermal_gap 0.5)
			(thermal_bridge_width 0.5)
			(island_removal_mode 0)
		)
		(polygon
			(pts
				(xy 419.162738 -291.425122) (xy 420.661338 -291.425122) (xy 420.661338 -291.94506) (xy 419.162738 -291.94506)
			)
		)
	)
	(zone
		(layer "In2.Cu")
		(hatch none 0.5)
		(connect_pads
			(clearance 0)
		)
		(min_thickness 0.25)
		(keepout
			(tracks not_allowed)
			(vias allowed)
			(pads allowed)
			(copperpour not_allowed)
			(footprints allowed)
		)
		(placement
			(enabled no)
			(sheetname "")
		)
		(fill
			(thermal_gap 0.5)
			(thermal_bridge_width 0.5)
			(island_removal_mode 0)
		)
		(polygon
			(pts
				(xy 287.430718 -261.675118) (xy 288.929318 -261.675118) (xy 288.929318 -262.195056) (xy 287.430718 -262.195056)
			)
		)
	)
	(zone
		(layer "In2.Cu")
		(hatch none 0.5)
		(connect_pads
			(clearance 0)
		)
		(min_thickness 0.25)
		(keepout
			(tracks not_allowed)
			(vias allowed)
			(pads allowed)
			(copperpour not_allowed)
			(footprints allowed)
		)
		(placement
			(enabled no)
			(sheetname "")
		)
		(fill
			(thermal_gap 0.5)
			(thermal_bridge_width 0.5)
			(island_removal_mode 0)
		)
		(polygon
			(pts
				(xy 294.974772 -305.025298) (xy 296.473372 -305.025298) (xy 296.473372 -305.545236) (xy 294.974772 -305.545236)
			)
		)
	)
	(zone
		(layer "In2.Cu")
		(hatch none 0.5)
		(connect_pads
			(clearance 0)
		)
		(min_thickness 0.25)
		(keepout
			(tracks not_allowed)
			(vias allowed)
			(pads allowed)
			(copperpour not_allowed)
			(footprints allowed)
		)
		(placement
			(enabled no)
			(sheetname "")
		)
		(fill
			(thermal_gap 0.5)
			(thermal_bridge_width 0.5)
			(island_removal_mode 0)
		)
		(polygon
			(pts
				(xy 171.22267 -276.975316) (xy 172.72127 -276.975316) (xy 172.72127 -277.495254) (xy 171.22267 -277.495254)
			)
		)
	)
	(zone
		(layer "In2.Cu")
		(hatch none 0.5)
		(connect_pads
			(clearance 0)
		)
		(min_thickness 0.25)
		(keepout
			(tracks not_allowed)
			(vias allowed)
			(pads allowed)
			(copperpour not_allowed)
			(footprints allowed)
		)
		(placement
			(enabled no)
			(sheetname "")
		)
		(fill
			(thermal_gap 0.5)
			(thermal_bridge_width 0.5)
			(island_removal_mode 0)
		)
		(polygon
			(pts
				(xy 453.438768 -296.525188) (xy 454.937368 -296.525188) (xy 454.937368 -297.045126) (xy 453.438768 -297.045126)
			)
		)
	)
	(zone
		(layer "In2.Cu")
		(hatch none 0.5)
		(connect_pads
			(clearance 0)
		)
		(min_thickness 0.25)
		(keepout
			(tracks not_allowed)
			(vias allowed)
			(pads allowed)
			(copperpour not_allowed)
			(footprints allowed)
		)
		(placement
			(enabled no)
			(sheetname "")
		)
		(fill
			(thermal_gap 0.5)
			(thermal_bridge_width 0.5)
			(island_removal_mode 0)
		)
		(polygon
			(pts
				(xy 276.442932 -209.825336) (xy 277.941532 -209.825336) (xy 277.941532 -210.345274) (xy 276.442932 -210.345274)
			)
		)
	)
	(zone
		(layer "In2.Cu")
		(hatch none 0.5)
		(connect_pads
			(clearance 0)
		)
		(min_thickness 0.25)
		(keepout
			(tracks not_allowed)
			(vias allowed)
			(pads allowed)
			(copperpour not_allowed)
			(footprints allowed)
		)
		(placement
			(enabled no)
			(sheetname "")
		)
		(fill
			(thermal_gap 0.5)
			(thermal_bridge_width 0.5)
			(island_removal_mode 0)
		)
		(polygon
			(pts
				(xy 430.80686 -281.225244) (xy 432.30546 -281.225244) (xy 432.30546 -281.745182) (xy 430.80686 -281.745182)
			)
		)
	)
	(zone
		(layer "In2.Cu")
		(hatch none 0.5)
		(connect_pads
			(clearance 0)
		)
		(min_thickness 0.25)
		(keepout
			(tracks not_allowed)
			(vias allowed)
			(pads allowed)
			(copperpour not_allowed)
			(footprints allowed)
		)
		(placement
			(enabled no)
			(sheetname "")
		)
		(fill
			(thermal_gap 0.5)
			(thermal_bridge_width 0.5)
			(island_removal_mode 0)
		)
		(polygon
			(pts
				(xy 302.518826 -230.225346) (xy 304.017426 -230.225346) (xy 304.017426 -230.745284) (xy 302.518826 -230.745284)
			)
		)
	)
	(zone
		(layer "In2.Cu")
		(hatch none 0.5)
		(connect_pads
			(clearance 0)
		)
		(min_thickness 0.25)
		(keepout
			(tracks not_allowed)
			(vias allowed)
			(pads allowed)
			(copperpour not_allowed)
			(footprints allowed)
		)
		(placement
			(enabled no)
			(sheetname "")
		)
		(fill
			(thermal_gap 0.5)
			(thermal_bridge_width 0.5)
			(island_removal_mode 0)
		)
		(polygon
			(pts
				(xy 190.410846 -281.225244) (xy 191.909446 -281.225244) (xy 191.909446 -281.745182) (xy 190.410846 -281.745182)
			)
		)
	)
	(zone
		(layer "In2.Cu")
		(hatch none 0.5)
		(connect_pads
			(clearance 0)
		)
		(min_thickness 0.25)
		(keepout
			(tracks not_allowed)
			(vias allowed)
			(pads allowed)
			(copperpour not_allowed)
			(footprints allowed)
		)
		(placement
			(enabled no)
			(sheetname "")
		)
		(fill
			(thermal_gap 0.5)
			(thermal_bridge_width 0.5)
			(island_removal_mode 0)
		)
		(polygon
			(pts
				(xy 449.3387 -203.875132) (xy 450.8373 -203.875132) (xy 450.8373 -204.39507) (xy 449.3387 -204.39507)
			)
		)
	)
	(zone
		(layer "In2.Cu")
		(hatch none 0.5)
		(connect_pads
			(clearance 0)
		)
		(min_thickness 0.25)
		(keepout
			(tracks not_allowed)
			(vias allowed)
			(pads allowed)
			(copperpour not_allowed)
			(footprints allowed)
		)
		(placement
			(enabled no)
			(sheetname "")
		)
		(fill
			(thermal_gap 0.5)
			(thermal_bridge_width 0.5)
			(island_removal_mode 0)
		)
		(polygon
			(pts
				(arc
					(start 18.110708 -17.966436)
					(mid 18.133026 -18.020318)
					(end 18.186908 -18.042636)
				)
				(arc
					(start 18.382488 -18.042636)
					(mid 18.404364 -18.039504)
					(end 18.424398 -18.03019)
				)
				(arc
					(start 18.718022 -17.837658)
					(mid 18.759678 -17.825256)
					(end 18.801334 -17.837658)
				)
				(arc
					(start 19.096228 -18.03019)
					(mid 19.116152 -18.039426)
					(end 19.137884 -18.042636)
				)
				(arc
					(start 19.332448 -18.042636)
					(mid 19.38633 -18.020318)
					(end 19.408648 -17.966436)
				)
				(arc
					(start 19.408648 -17.280636)
					(mid 19.38633 -17.226754)
					(end 19.332448 -17.204436)
				)
				(arc
					(start 19.137884 -17.204436)
					(mid 19.11614 -17.207604)
					(end 19.096228 -17.216882)
				)
				(arc
					(start 18.800064 -17.409668)
					(mid 18.75838 -17.42189)
					(end 18.716752 -17.409414)
				)
				(arc
					(start 18.423128 -17.216882)
					(mid 18.403204 -17.207646)
					(end 18.381472 -17.204436)
				)
				(arc
					(start 18.186908 -17.204436)
					(mid 18.133026 -17.226754)
					(end 18.110708 -17.280636)
				)
			)
		)
	)
	(zone
		(layer "In2.Cu")
		(hatch none 0.5)
		(connect_pads
			(clearance 0)
		)
		(min_thickness 0.25)
		(keepout
			(tracks not_allowed)
			(vias allowed)
			(pads allowed)
			(copperpour not_allowed)
			(footprints allowed)
		)
		(placement
			(enabled no)
			(sheetname "")
		)
		(fill
			(thermal_gap 0.5)
			(thermal_bridge_width 0.5)
			(island_removal_mode 0)
		)
		(polygon
			(pts
				(arc
					(start 332.310994 -381.824484)
					(mid 332.330918 -381.83372)
					(end 332.35265 -381.83693)
				)
				(arc
					(start 332.547214 -381.83693)
					(mid 332.601096 -381.814612)
					(end 332.623414 -381.76073)
				)
				(arc
					(start 332.623414 -381.07493)
					(mid 332.601096 -381.021048)
					(end 332.547214 -380.99873)
				)
				(arc
					(start 332.35265 -380.99873)
					(mid 332.330906 -381.001898)
					(end 332.310994 -381.011176)
				)
				(arc
					(start 332.01483 -381.203962)
					(mid 331.973146 -381.216184)
					(end 331.931518 -381.203708)
				)
				(arc
					(start 331.637894 -381.011176)
					(mid 331.61797 -381.00194)
					(end 331.596238 -380.99873)
				)
				(arc
					(start 331.401674 -380.99873)
					(mid 331.347792 -381.021048)
					(end 331.325474 -381.07493)
				)
				(arc
					(start 331.325474 -381.76073)
					(mid 331.347792 -381.814612)
					(end 331.401674 -381.83693)
				)
				(arc
					(start 331.597508 -381.83693)
					(mid 331.619252 -381.833762)
					(end 331.639164 -381.824484)
				)
				(arc
					(start 331.932788 -381.631952)
					(mid 331.974444 -381.61955)
					(end 332.0161 -381.631952)
				)
			)
		)
	)
	(zone
		(layer "In2.Cu")
		(hatch none 0.5)
		(connect_pads
			(clearance 0)
		)
		(min_thickness 0.25)
		(keepout
			(tracks not_allowed)
			(vias allowed)
			(pads allowed)
			(copperpour not_allowed)
			(footprints allowed)
		)
		(placement
			(enabled no)
			(sheetname "")
		)
		(fill
			(thermal_gap 0.5)
			(thermal_bridge_width 0.5)
			(island_removal_mode 0)
		)
		(polygon
			(pts
				(xy 411.618684 -237.02518) (xy 413.117284 -237.02518) (xy 413.117284 -237.545118) (xy 411.618684 -237.545118)
			)
		)
	)
	(zone
		(layer "In2.Cu")
		(hatch none 0.5)
		(connect_pads
			(clearance 0)
		)
		(min_thickness 0.25)
		(keepout
			(tracks not_allowed)
			(vias allowed)
			(pads allowed)
			(copperpour not_allowed)
			(footprints allowed)
		)
		(placement
			(enabled no)
			(sheetname "")
		)
		(fill
			(thermal_gap 0.5)
			(thermal_bridge_width 0.5)
			(island_removal_mode 0)
		)
		(polygon
			(pts
				(xy 167.778684 -271.87525) (xy 169.277284 -271.87525) (xy 169.277284 -272.395188) (xy 167.778684 -272.395188)
			)
		)
	)
	(zone
		(layer "In2.Cu")
		(hatch none 0.5)
		(connect_pads
			(clearance 0)
		)
		(min_thickness 0.25)
		(keepout
			(tracks not_allowed)
			(vias allowed)
			(pads allowed)
			(copperpour not_allowed)
			(footprints allowed)
		)
		(placement
			(enabled no)
			(sheetname "")
		)
		(fill
			(thermal_gap 0.5)
			(thermal_bridge_width 0.5)
			(island_removal_mode 0)
		)
		(polygon
			(pts
				(xy 272.342864 -310.12511) (xy 273.841464 -310.12511) (xy 273.841464 -310.645048) (xy 272.342864 -310.645048)
			)
		)
	)
	(zone
		(layer "In2.Cu")
		(hatch none 0.5)
		(connect_pads
			(clearance 0)
		)
		(min_thickness 0.25)
		(keepout
			(tracks not_allowed)
			(vias allowed)
			(pads allowed)
			(copperpour not_allowed)
			(footprints allowed)
		)
		(placement
			(enabled no)
			(sheetname "")
		)
		(fill
			(thermal_gap 0.5)
			(thermal_bridge_width 0.5)
			(island_removal_mode 0)
		)
		(polygon
			(pts
				(xy 294.974772 -244.675152) (xy 296.473372 -244.675152) (xy 296.473372 -245.19509) (xy 294.974772 -245.19509)
			)
		)
	)
	(zone
		(layer "In2.Cu")
		(hatch none 0.5)
		(connect_pads
			(clearance 0)
		)
		(min_thickness 0.25)
		(keepout
			(tracks not_allowed)
			(vias allowed)
			(pads allowed)
			(copperpour not_allowed)
			(footprints allowed)
		)
		(placement
			(enabled no)
			(sheetname "")
		)
		(fill
			(thermal_gap 0.5)
			(thermal_bridge_width 0.5)
			(island_removal_mode 0)
		)
		(polygon
			(pts
				(xy 419.162738 -299.075348) (xy 420.661338 -299.075348) (xy 420.661338 -299.595286) (xy 419.162738 -299.595286)
			)
		)
	)
	(zone
		(layer "In2.Cu")
		(hatch none 0.5)
		(connect_pads
			(clearance 0)
		)
		(min_thickness 0.25)
		(keepout
			(tracks not_allowed)
			(vias allowed)
			(pads allowed)
			(copperpour not_allowed)
			(footprints allowed)
		)
		(placement
			(enabled no)
			(sheetname "")
		)
		(fill
			(thermal_gap 0.5)
			(thermal_bridge_width 0.5)
			(island_removal_mode 0)
		)
		(polygon
			(pts
				(xy 441.7949 -254.025146) (xy 443.2935 -254.025146) (xy 443.2935 -254.545084) (xy 441.7949 -254.545084)
			)
		)
	)
	(zone
		(layer "In2.Cu")
		(hatch none 0.5)
		(connect_pads
			(clearance 0)
		)
		(min_thickness 0.25)
		(keepout
			(tracks not_allowed)
			(vias allowed)
			(pads allowed)
			(copperpour not_allowed)
			(footprints allowed)
		)
		(placement
			(enabled no)
			(sheetname "")
		)
		(fill
			(thermal_gap 0.5)
			(thermal_bridge_width 0.5)
			(island_removal_mode 0)
		)
		(polygon
			(pts
				(xy 415.718752 -298.22521) (xy 417.217352 -298.22521) (xy 417.217352 -298.745148) (xy 415.718752 -298.745148)
			)
		)
	)
	(zone
		(layer "In2.Cu")
		(hatch none 0.5)
		(connect_pads
			(clearance 0)
		)
		(min_thickness 0.25)
		(keepout
			(tracks not_allowed)
			(vias allowed)
			(pads allowed)
			(copperpour not_allowed)
			(footprints allowed)
		)
		(placement
			(enabled no)
			(sheetname "")
		)
		(fill
			(thermal_gap 0.5)
			(thermal_bridge_width 0.5)
			(island_removal_mode 0)
		)
		(polygon
			(pts
				(xy 36.046664 -220.025214) (xy 37.545264 -220.025214) (xy 37.545264 -220.545152) (xy 36.046664 -220.545152)
			)
		)
	)
	(zone
		(layer "In2.Cu")
		(hatch none 0.5)
		(connect_pads
			(clearance 0)
		)
		(min_thickness 0.25)
		(keepout
			(tracks not_allowed)
			(vias allowed)
			(pads allowed)
			(copperpour not_allowed)
			(footprints allowed)
		)
		(placement
			(enabled no)
			(sheetname "")
		)
		(fill
			(thermal_gap 0.5)
			(thermal_bridge_width 0.5)
			(island_removal_mode 0)
		)
		(polygon
			(pts
				(xy 58.678826 -277.8252) (xy 60.177426 -277.8252) (xy 60.177426 -278.345138) (xy 58.678826 -278.345138)
			)
		)
	)
	(zone
		(layer "In2.Cu")
		(hatch none 0.5)
		(connect_pads
			(clearance 0)
		)
		(min_thickness 0.25)
		(keepout
			(tracks not_allowed)
			(vias allowed)
			(pads allowed)
			(copperpour not_allowed)
			(footprints allowed)
		)
		(placement
			(enabled no)
			(sheetname "")
		)
		(fill
			(thermal_gap 0.5)
			(thermal_bridge_width 0.5)
			(island_removal_mode 0)
		)
		(polygon
			(pts
				(arc
					(start 325.310246 -379.360684)
					(mid 325.33017 -379.36992)
					(end 325.351902 -379.37313)
				)
				(arc
					(start 325.546466 -379.37313)
					(mid 325.600348 -379.350812)
					(end 325.622666 -379.29693)
				)
				(arc
					(start 325.622666 -378.61113)
					(mid 325.600348 -378.557248)
					(end 325.546466 -378.53493)
				)
				(arc
					(start 325.351902 -378.53493)
					(mid 325.330158 -378.538098)
					(end 325.310246 -378.547376)
				)
				(arc
					(start 325.014082 -378.740162)
					(mid 324.972398 -378.752384)
					(end 324.93077 -378.739908)
				)
				(arc
					(start 324.637146 -378.547376)
					(mid 324.617222 -378.53814)
					(end 324.59549 -378.53493)
				)
				(arc
					(start 324.400926 -378.53493)
					(mid 324.347044 -378.557248)
					(end 324.324726 -378.61113)
				)
				(arc
					(start 324.324726 -379.29693)
					(mid 324.347044 -379.350812)
					(end 324.400926 -379.37313)
				)
				(arc
					(start 324.59676 -379.37313)
					(mid 324.618504 -379.369962)
					(end 324.638416 -379.360684)
				)
				(arc
					(start 324.93204 -379.168152)
					(mid 324.973696 -379.15575)
					(end 325.015352 -379.168152)
				)
			)
		)
	)
	(zone
		(layer "In2.Cu")
		(hatch none 0.5)
		(connect_pads
			(clearance 0)
		)
		(min_thickness 0.25)
		(keepout
			(tracks not_allowed)
			(vias allowed)
			(pads allowed)
			(copperpour not_allowed)
			(footprints allowed)
		)
		(placement
			(enabled no)
			(sheetname "")
		)
		(fill
			(thermal_gap 0.5)
			(thermal_bridge_width 0.5)
			(island_removal_mode 0)
		)
		(polygon
			(pts
				(xy 438.350914 -282.925266) (xy 439.849514 -282.925266) (xy 439.849514 -283.445204) (xy 438.350914 -283.445204)
			)
		)
	)
	(zone
		(layer "In2.Cu")
		(hatch none 0.5)
		(connect_pads
			(clearance 0)
		)
		(min_thickness 0.25)
		(keepout
			(tracks not_allowed)
			(vias allowed)
			(pads allowed)
			(copperpour not_allowed)
			(footprints allowed)
		)
		(placement
			(enabled no)
			(sheetname "")
		)
		(fill
			(thermal_gap 0.5)
			(thermal_bridge_width 0.5)
			(island_removal_mode 0)
		)
		(polygon
			(pts
				(xy 51.134772 -242.125246) (xy 52.633372 -242.125246) (xy 52.633372 -242.645184) (xy 51.134772 -242.645184)
			)
		)
	)
	(zone
		(layer "In2.Cu")
		(hatch none 0.5)
		(connect_pads
			(clearance 0)
		)
		(min_thickness 0.25)
		(keepout
			(tracks not_allowed)
			(vias allowed)
			(pads allowed)
			(copperpour not_allowed)
			(footprints allowed)
		)
		(placement
			(enabled no)
			(sheetname "")
		)
		(fill
			(thermal_gap 0.5)
			(thermal_bridge_width 0.5)
			(island_removal_mode 0)
		)
		(polygon
			(pts
				(xy 415.718752 -247.225312) (xy 417.217352 -247.225312) (xy 417.217352 -247.74525) (xy 415.718752 -247.74525)
			)
		)
	)
	(zone
		(layer "In2.Cu")
		(hatch none 0.5)
		(connect_pads
			(clearance 0)
		)
		(min_thickness 0.25)
		(keepout
			(tracks not_allowed)
			(vias allowed)
			(pads allowed)
			(copperpour not_allowed)
			(footprints allowed)
		)
		(placement
			(enabled no)
			(sheetname "")
		)
		(fill
			(thermal_gap 0.5)
			(thermal_bridge_width 0.5)
			(island_removal_mode 0)
		)
		(polygon
			(pts
				(xy 47.034704 -302.475138) (xy 48.533304 -302.475138) (xy 48.533304 -302.995076) (xy 47.034704 -302.995076)
			)
		)
	)
	(zone
		(layer "In2.Cu")
		(hatch none 0.5)
		(connect_pads
			(clearance 0)
		)
		(min_thickness 0.25)
		(keepout
			(tracks not_allowed)
			(vias allowed)
			(pads allowed)
			(copperpour not_allowed)
			(footprints allowed)
		)
		(placement
			(enabled no)
			(sheetname "")
		)
		(fill
			(thermal_gap 0.5)
			(thermal_bridge_width 0.5)
			(island_removal_mode 0)
		)
		(polygon
			(pts
				(xy 16.858742 -314.375292) (xy 18.357342 -314.375292) (xy 18.357342 -314.89523) (xy 16.858742 -314.89523)
			)
		)
	)
	(zone
		(layer "In2.Cu")
		(hatch none 0.5)
		(connect_pads
			(clearance 0)
		)
		(min_thickness 0.25)
		(keepout
			(tracks not_allowed)
			(vias allowed)
			(pads allowed)
			(copperpour not_allowed)
			(footprints allowed)
		)
		(placement
			(enabled no)
			(sheetname "")
		)
		(fill
			(thermal_gap 0.5)
			(thermal_bridge_width 0.5)
			(island_removal_mode 0)
		)
		(polygon
			(pts
				(xy 426.706792 -214.925148) (xy 428.205392 -214.925148) (xy 428.205392 -215.445086) (xy 426.706792 -215.445086)
			)
		)
	)
	(zone
		(layer "In2.Cu")
		(hatch none 0.5)
		(connect_pads
			(clearance 0)
		)
		(min_thickness 0.25)
		(keepout
			(tracks not_allowed)
			(vias allowed)
			(pads allowed)
			(copperpour not_allowed)
			(footprints allowed)
		)
		(placement
			(enabled no)
			(sheetname "")
		)
		(fill
			(thermal_gap 0.5)
			(thermal_bridge_width 0.5)
			(island_removal_mode 0)
		)
		(polygon
			(pts
				(xy 36.046664 -296.525188) (xy 37.545264 -296.525188) (xy 37.545264 -297.045126) (xy 36.046664 -297.045126)
			)
		)
	)
	(zone
		(layer "In2.Cu")
		(hatch none 0.5)
		(connect_pads
			(clearance 0)
		)
		(min_thickness 0.25)
		(keepout
			(tracks not_allowed)
			(vias allowed)
			(pads allowed)
			(copperpour not_allowed)
			(footprints allowed)
		)
		(placement
			(enabled no)
			(sheetname "")
		)
		(fill
			(thermal_gap 0.5)
			(thermal_bridge_width 0.5)
			(island_removal_mode 0)
		)
		(polygon
			(pts
				(xy 175.322738 -298.22521) (xy 176.821338 -298.22521) (xy 176.821338 -298.745148) (xy 175.322738 -298.745148)
			)
		)
	)
	(zone
		(layer "In2.Cu")
		(hatch none 0.5)
		(connect_pads
			(clearance 0)
		)
		(min_thickness 0.25)
		(keepout
			(tracks not_allowed)
			(vias allowed)
			(pads allowed)
			(copperpour not_allowed)
			(footprints allowed)
		)
		(placement
			(enabled no)
			(sheetname "")
		)
		(fill
			(thermal_gap 0.5)
			(thermal_bridge_width 0.5)
			(island_removal_mode 0)
		)
		(polygon
			(pts
				(xy 287.430718 -299.075348) (xy 288.929318 -299.075348) (xy 288.929318 -299.595286) (xy 287.430718 -299.595286)
			)
		)
	)
	(zone
		(layer "In2.Cu")
		(hatch none 0.5)
		(connect_pads
			(clearance 0)
		)
		(min_thickness 0.25)
		(keepout
			(tracks not_allowed)
			(vias allowed)
			(pads allowed)
			(copperpour not_allowed)
			(footprints allowed)
		)
		(placement
			(enabled no)
			(sheetname "")
		)
		(fill
			(thermal_gap 0.5)
			(thermal_bridge_width 0.5)
			(island_removal_mode 0)
		)
		(polygon
			(pts
				(xy 47.034704 -291.425122) (xy 48.533304 -291.425122) (xy 48.533304 -291.94506) (xy 47.034704 -291.94506)
			)
		)
	)
	(zone
		(layer "In2.Cu")
		(hatch none 0.5)
		(connect_pads
			(clearance 0)
		)
		(min_thickness 0.25)
		(keepout
			(tracks not_allowed)
			(vias allowed)
			(pads allowed)
			(copperpour not_allowed)
			(footprints allowed)
		)
		(placement
			(enabled no)
			(sheetname "")
		)
		(fill
			(thermal_gap 0.5)
			(thermal_bridge_width 0.5)
			(island_removal_mode 0)
		)
		(polygon
			(pts
				(xy 201.398632 -231.925114) (xy 202.897232 -231.925114) (xy 202.897232 -232.445052) (xy 201.398632 -232.445052)
			)
		)
	)
	(zone
		(layer "In2.Cu")
		(hatch none 0.5)
		(connect_pads
			(clearance 0)
		)
		(min_thickness 0.25)
		(keepout
			(tracks not_allowed)
			(vias allowed)
			(pads allowed)
			(copperpour not_allowed)
			(footprints allowed)
		)
		(placement
			(enabled no)
			(sheetname "")
		)
		(fill
			(thermal_gap 0.5)
			(thermal_bridge_width 0.5)
			(island_removal_mode 0)
		)
		(polygon
			(pts
				(xy 453.438768 -275.275294) (xy 454.937368 -275.275294) (xy 454.937368 -275.795232) (xy 453.438768 -275.795232)
			)
		)
	)
	(zone
		(layer "In2.Cu")
		(hatch none 0.5)
		(connect_pads
			(clearance 0)
		)
		(min_thickness 0.25)
		(keepout
			(tracks not_allowed)
			(vias allowed)
			(pads allowed)
			(copperpour not_allowed)
			(footprints allowed)
		)
		(placement
			(enabled no)
			(sheetname "")
		)
		(fill
			(thermal_gap 0.5)
			(thermal_bridge_width 0.5)
			(island_removal_mode 0)
		)
		(polygon
			(pts
				(xy 186.310778 -208.975198) (xy 187.809378 -208.975198) (xy 187.809378 -209.495136) (xy 186.310778 -209.495136)
			)
		)
	)
	(zone
		(layer "In2.Cu")
		(hatch none 0.5)
		(connect_pads
			(clearance 0)
		)
		(min_thickness 0.25)
		(keepout
			(tracks not_allowed)
			(vias allowed)
			(pads allowed)
			(copperpour not_allowed)
			(footprints allowed)
		)
		(placement
			(enabled no)
			(sheetname "")
		)
		(fill
			(thermal_gap 0.5)
			(thermal_bridge_width 0.5)
			(island_removal_mode 0)
		)
		(polygon
			(pts
				(xy 272.342864 -276.975316) (xy 273.841464 -276.975316) (xy 273.841464 -277.495254) (xy 272.342864 -277.495254)
			)
		)
	)
	(zone
		(layer "In2.Cu")
		(hatch none 0.5)
		(connect_pads
			(clearance 0)
		)
		(min_thickness 0.25)
		(keepout
			(tracks not_allowed)
			(vias allowed)
			(pads allowed)
			(copperpour not_allowed)
			(footprints allowed)
		)
		(placement
			(enabled no)
			(sheetname "")
		)
		(fill
			(thermal_gap 0.5)
			(thermal_bridge_width 0.5)
			(island_removal_mode 0)
		)
		(polygon
			(pts
				(xy 175.322738 -267.625322) (xy 176.821338 -267.625322) (xy 176.821338 -268.14526) (xy 175.322738 -268.14526)
			)
		)
	)
	(zone
		(layer "In2.Cu")
		(hatch none 0.5)
		(connect_pads
			(clearance 0)
		)
		(min_thickness 0.25)
		(keepout
			(tracks not_allowed)
			(vias allowed)
			(pads allowed)
			(copperpour not_allowed)
			(footprints allowed)
		)
		(placement
			(enabled no)
			(sheetname "")
		)
		(fill
			(thermal_gap 0.5)
			(thermal_bridge_width 0.5)
			(island_removal_mode 0)
		)
		(polygon
			(pts
				(xy 411.618684 -233.625136) (xy 413.117284 -233.625136) (xy 413.117284 -234.145074) (xy 411.618684 -234.145074)
			)
		)
	)
	(zone
		(layer "In2.Cu")
		(hatch none 0.5)
		(connect_pads
			(clearance 0)
		)
		(min_thickness 0.25)
		(keepout
			(tracks not_allowed)
			(vias allowed)
			(pads allowed)
			(copperpour not_allowed)
			(footprints allowed)
		)
		(placement
			(enabled no)
			(sheetname "")
		)
		(fill
			(thermal_gap 0.5)
			(thermal_bridge_width 0.5)
			(island_removal_mode 0)
		)
		(polygon
			(pts
				(xy 54.578758 -211.525104) (xy 56.077358 -211.525104) (xy 56.077358 -212.045042) (xy 54.578758 -212.045042)
			)
		)
	)
	(zone
		(layer "In2.Cu")
		(hatch none 0.5)
		(connect_pads
			(clearance 0)
		)
		(min_thickness 0.25)
		(keepout
			(tracks not_allowed)
			(vias allowed)
			(pads allowed)
			(copperpour not_allowed)
			(footprints allowed)
		)
		(placement
			(enabled no)
			(sheetname "")
		)
		(fill
			(thermal_gap 0.5)
			(thermal_bridge_width 0.5)
			(island_removal_mode 0)
		)
		(polygon
			(pts
				(xy 171.22267 -310.12511) (xy 172.72127 -310.12511) (xy 172.72127 -310.645048) (xy 171.22267 -310.645048)
			)
		)
	)
	(zone
		(layer "In2.Cu")
		(hatch none 0.5)
		(connect_pads
			(clearance 0)
		)
		(min_thickness 0.25)
		(keepout
			(tracks not_allowed)
			(vias allowed)
			(pads allowed)
			(copperpour not_allowed)
			(footprints allowed)
		)
		(placement
			(enabled no)
			(sheetname "")
		)
		(fill
			(thermal_gap 0.5)
			(thermal_bridge_width 0.5)
			(island_removal_mode 0)
		)
		(polygon
			(pts
				(xy 36.046664 -260.825234) (xy 37.545264 -260.825234) (xy 37.545264 -261.345172) (xy 36.046664 -261.345172)
			)
		)
	)
	(zone
		(layer "In2.Cu")
		(hatch none 0.5)
		(connect_pads
			(clearance 0)
		)
		(min_thickness 0.25)
		(keepout
			(tracks not_allowed)
			(vias allowed)
			(pads allowed)
			(copperpour not_allowed)
			(footprints allowed)
		)
		(placement
			(enabled no)
			(sheetname "")
		)
		(fill
			(thermal_gap 0.5)
			(thermal_bridge_width 0.5)
			(island_removal_mode 0)
		)
		(polygon
			(pts
				(xy 453.438768 -294.825166) (xy 454.937368 -294.825166) (xy 454.937368 -295.345104) (xy 453.438768 -295.345104)
			)
		)
	)
	(zone
		(layer "In2.Cu")
		(hatch none 0.5)
		(connect_pads
			(clearance 0)
		)
		(min_thickness 0.25)
		(keepout
			(tracks not_allowed)
			(vias allowed)
			(pads allowed)
			(copperpour not_allowed)
			(footprints allowed)
		)
		(placement
			(enabled no)
			(sheetname "")
		)
		(fill
			(thermal_gap 0.5)
			(thermal_bridge_width 0.5)
			(island_removal_mode 0)
		)
		(polygon
			(pts
				(xy 438.350914 -292.27526) (xy 439.849514 -292.27526) (xy 439.849514 -292.795198) (xy 438.350914 -292.795198)
			)
		)
	)
	(zone
		(layer "In2.Cu")
		(hatch none 0.5)
		(connect_pads
			(clearance 0)
		)
		(min_thickness 0.25)
		(keepout
			(tracks not_allowed)
			(vias allowed)
			(pads allowed)
			(copperpour not_allowed)
			(footprints allowed)
		)
		(placement
			(enabled no)
			(sheetname "")
		)
		(fill
			(thermal_gap 0.5)
			(thermal_bridge_width 0.5)
			(island_removal_mode 0)
		)
		(polygon
			(pts
				(xy 17.848834 -105.41381) (xy 17.848834 -105.147872) (xy 17.908778 -105.147872)
				(arc
					(start 17.908778 -105.007664)
					(mid 17.879569 -104.937782)
					(end 17.809464 -104.909112)
				)
				(arc
					(start 17.50822 -104.909112)
					(mid 17.438115 -104.937782)
					(end 17.408906 -105.007664)
				)
				(xy 17.408906 -105.147872) (xy 17.46885 -105.147872) (xy 17.46885 -105.41381)
			)
		)
	)
	(zone
		(layer "In2.Cu")
		(hatch none 0.5)
		(connect_pads
			(clearance 0)
		)
		(min_thickness 0.25)
		(keepout
			(tracks not_allowed)
			(vias allowed)
			(pads allowed)
			(copperpour not_allowed)
			(footprints allowed)
		)
		(placement
			(enabled no)
			(sheetname "")
		)
		(fill
			(thermal_gap 0.5)
			(thermal_bridge_width 0.5)
			(island_removal_mode 0)
		)
		(polygon
			(pts
				(xy 36.046664 -269.325344) (xy 37.545264 -269.325344) (xy 37.545264 -269.845282) (xy 36.046664 -269.845282)
			)
		)
	)
	(zone
		(layer "In2.Cu")
		(hatch none 0.5)
		(connect_pads
			(clearance 0)
		)
		(min_thickness 0.25)
		(keepout
			(tracks not_allowed)
			(vias allowed)
			(pads allowed)
			(copperpour not_allowed)
			(footprints allowed)
		)
		(placement
			(enabled no)
			(sheetname "")
		)
		(fill
			(thermal_gap 0.5)
			(thermal_bridge_width 0.5)
			(island_removal_mode 0)
		)
		(polygon
			(pts
				(xy 302.518826 -308.425342) (xy 304.017426 -308.425342) (xy 304.017426 -308.94528) (xy 302.518826 -308.94528)
			)
		)
	)
	(zone
		(layer "In2.Cu")
		(hatch none 0.5)
		(connect_pads
			(clearance 0)
		)
		(min_thickness 0.25)
		(keepout
			(tracks not_allowed)
			(vias allowed)
			(pads allowed)
			(copperpour not_allowed)
			(footprints allowed)
		)
		(placement
			(enabled no)
			(sheetname "")
		)
		(fill
			(thermal_gap 0.5)
			(thermal_bridge_width 0.5)
			(island_removal_mode 0)
		)
		(polygon
			(pts
				(xy 287.430718 -241.275108) (xy 288.929318 -241.275108) (xy 288.929318 -241.795046) (xy 287.430718 -241.795046)
			)
		)
	)
	(zone
		(layer "In2.Cu")
		(hatch none 0.5)
		(connect_pads
			(clearance 0)
		)
		(min_thickness 0.25)
		(keepout
			(tracks not_allowed)
			(vias allowed)
			(pads allowed)
			(copperpour not_allowed)
			(footprints allowed)
		)
		(placement
			(enabled no)
			(sheetname "")
		)
		(fill
			(thermal_gap 0.5)
			(thermal_bridge_width 0.5)
			(island_removal_mode 0)
		)
		(polygon
			(pts
				(xy 430.80686 -293.975282) (xy 432.30546 -293.975282) (xy 432.30546 -294.49522) (xy 430.80686 -294.49522)
			)
		)
	)
	(zone
		(layer "In2.Cu")
		(hatch none 0.5)
		(connect_pads
			(clearance 0)
		)
		(min_thickness 0.25)
		(keepout
			(tracks not_allowed)
			(vias allowed)
			(pads allowed)
			(copperpour not_allowed)
			(footprints allowed)
		)
		(placement
			(enabled no)
			(sheetname "")
		)
		(fill
			(thermal_gap 0.5)
			(thermal_bridge_width 0.5)
			(island_removal_mode 0)
		)
		(polygon
			(pts
				(xy 283.986732 -201.325226) (xy 285.485332 -201.325226) (xy 285.485332 -201.845164) (xy 283.986732 -201.845164)
			)
		)
	)
	(zone
		(layer "In2.Cu")
		(hatch none 0.5)
		(connect_pads
			(clearance 0)
		)
		(min_thickness 0.25)
		(keepout
			(tracks not_allowed)
			(vias allowed)
			(pads allowed)
			(copperpour not_allowed)
			(footprints allowed)
		)
		(placement
			(enabled no)
			(sheetname "")
		)
		(fill
			(thermal_gap 0.5)
			(thermal_bridge_width 0.5)
			(island_removal_mode 0)
		)
		(polygon
			(pts
				(xy 294.974772 -314.375292) (xy 296.473372 -314.375292) (xy 296.473372 -314.89523) (xy 294.974772 -314.89523)
			)
		)
	)
	(zone
		(layer "In2.Cu")
		(hatch none 0.5)
		(connect_pads
			(clearance 0)
		)
		(min_thickness 0.25)
		(keepout
			(tracks not_allowed)
			(vias allowed)
			(pads allowed)
			(copperpour not_allowed)
			(footprints allowed)
		)
		(placement
			(enabled no)
			(sheetname "")
		)
		(fill
			(thermal_gap 0.5)
			(thermal_bridge_width 0.5)
			(island_removal_mode 0)
		)
		(polygon
			(pts
				(xy 434.250846 -201.325226) (xy 435.749446 -201.325226) (xy 435.749446 -201.845164) (xy 434.250846 -201.845164)
			)
		)
	)
	(zone
		(layer "In2.Cu")
		(hatch none 0.5)
		(connect_pads
			(clearance 0)
		)
		(min_thickness 0.25)
		(keepout
			(tracks not_allowed)
			(vias allowed)
			(pads allowed)
			(copperpour not_allowed)
			(footprints allowed)
		)
		(placement
			(enabled no)
			(sheetname "")
		)
		(fill
			(thermal_gap 0.5)
			(thermal_bridge_width 0.5)
			(island_removal_mode 0)
		)
		(polygon
			(pts
				(xy 54.578758 -249.775218) (xy 56.077358 -249.775218) (xy 56.077358 -250.295156) (xy 54.578758 -250.295156)
			)
		)
	)
	(zone
		(layer "In2.Cu")
		(hatch none 0.5)
		(connect_pads
			(clearance 0)
		)
		(min_thickness 0.25)
		(keepout
			(tracks not_allowed)
			(vias allowed)
			(pads allowed)
			(copperpour not_allowed)
			(footprints allowed)
		)
		(placement
			(enabled no)
			(sheetname "")
		)
		(fill
			(thermal_gap 0.5)
			(thermal_bridge_width 0.5)
			(island_removal_mode 0)
		)
		(polygon
			(pts
				(xy 434.250846 -280.375106) (xy 435.749446 -280.375106) (xy 435.749446 -280.895044) (xy 434.250846 -280.895044)
			)
		)
	)
	(zone
		(layer "In2.Cu")
		(hatch none 0.5)
		(connect_pads
			(clearance 0)
		)
		(min_thickness 0.25)
		(keepout
			(tracks not_allowed)
			(vias allowed)
			(pads allowed)
			(copperpour not_allowed)
			(footprints allowed)
		)
		(placement
			(enabled no)
			(sheetname "")
		)
		(fill
			(thermal_gap 0.5)
			(thermal_bridge_width 0.5)
			(island_removal_mode 0)
		)
		(polygon
			(pts
				(xy 419.162738 -254.025146) (xy 420.661338 -254.025146) (xy 420.661338 -254.545084) (xy 419.162738 -254.545084)
			)
		)
	)
	(zone
		(layer "In2.Cu")
		(hatch none 0.5)
		(connect_pads
			(clearance 0)
		)
		(min_thickness 0.25)
		(keepout
			(tracks not_allowed)
			(vias allowed)
			(pads allowed)
			(copperpour not_allowed)
			(footprints allowed)
		)
		(placement
			(enabled no)
			(sheetname "")
		)
		(fill
			(thermal_gap 0.5)
			(thermal_bridge_width 0.5)
			(island_removal_mode 0)
		)
		(polygon
			(pts
				(arc
					(start 318.503046 -384.288284)
					(mid 318.52297 -384.29752)
					(end 318.544702 -384.30073)
				)
				(arc
					(start 318.739266 -384.30073)
					(mid 318.793148 -384.278412)
					(end 318.815466 -384.22453)
				)
				(arc
					(start 318.815466 -383.53873)
					(mid 318.793148 -383.484848)
					(end 318.739266 -383.46253)
				)
				(arc
					(start 318.544702 -383.46253)
					(mid 318.522958 -383.465698)
					(end 318.503046 -383.474976)
				)
				(arc
					(start 318.206882 -383.667762)
					(mid 318.165198 -383.679984)
					(end 318.12357 -383.667508)
				)
				(arc
					(start 317.829946 -383.474976)
					(mid 317.810022 -383.46574)
					(end 317.78829 -383.46253)
				)
				(arc
					(start 317.593726 -383.46253)
					(mid 317.539844 -383.484848)
					(end 317.517526 -383.53873)
				)
				(arc
					(start 317.517526 -384.22453)
					(mid 317.539844 -384.278412)
					(end 317.593726 -384.30073)
				)
				(arc
					(start 317.78956 -384.30073)
					(mid 317.811304 -384.297562)
					(end 317.831216 -384.288284)
				)
				(arc
					(start 318.12484 -384.095752)
					(mid 318.166496 -384.08335)
					(end 318.208152 -384.095752)
				)
			)
		)
	)
	(zone
		(layer "In2.Cu")
		(hatch none 0.5)
		(connect_pads
			(clearance 0)
		)
		(min_thickness 0.25)
		(keepout
			(tracks allowed)
			(vias allowed)
			(pads allowed)
			(copperpour allowed)
			(footprints allowed)
		)
		(placement
			(enabled no)
			(sheetname "")
		)
		(fill
			(thermal_gap 0.5)
			(thermal_bridge_width 0.5)
			(island_removal_mode 0)
		)
		(polygon
			(pts
				(xy 26.68143 -350.440752) (xy 26.68143 -351.266252) (xy 26.52395 -351.266252) (xy 26.52395 -350.440752)
			)
		)
	)
	(zone
		(layer "In2.Cu")
		(hatch none 0.5)
		(connect_pads
			(clearance 0)
		)
		(min_thickness 0.25)
		(keepout
			(tracks not_allowed)
			(vias allowed)
			(pads allowed)
			(copperpour not_allowed)
			(footprints allowed)
		)
		(placement
			(enabled no)
			(sheetname "")
		)
		(fill
			(thermal_gap 0.5)
			(thermal_bridge_width 0.5)
			(island_removal_mode 0)
		)
		(polygon
			(pts
				(xy 294.974772 -297.375326) (xy 296.473372 -297.375326) (xy 296.473372 -297.895264) (xy 294.974772 -297.895264)
			)
		)
	)
	(zone
		(layer "In2.Cu")
		(hatch none 0.5)
		(connect_pads
			(clearance 0)
		)
		(min_thickness 0.25)
		(keepout
			(tracks not_allowed)
			(vias allowed)
			(pads allowed)
			(copperpour not_allowed)
			(footprints allowed)
		)
		(placement
			(enabled no)
			(sheetname "")
		)
		(fill
			(thermal_gap 0.5)
			(thermal_bridge_width 0.5)
			(island_removal_mode 0)
		)
		(polygon
			(pts
				(xy 47.034704 -208.975198) (xy 48.533304 -208.975198) (xy 48.533304 -209.495136) (xy 47.034704 -209.495136)
			)
		)
	)
	(zone
		(layer "In2.Cu")
		(hatch none 0.5)
		(connect_pads
			(clearance 0)
		)
		(min_thickness 0.25)
		(keepout
			(tracks not_allowed)
			(vias allowed)
			(pads allowed)
			(copperpour not_allowed)
			(footprints allowed)
		)
		(placement
			(enabled no)
			(sheetname "")
		)
		(fill
			(thermal_gap 0.5)
			(thermal_bridge_width 0.5)
			(island_removal_mode 0)
		)
		(polygon
			(pts
				(xy 197.954646 -305.875182) (xy 199.453246 -305.875182) (xy 199.453246 -306.39512) (xy 197.954646 -306.39512)
			)
		)
	)
	(zone
		(layer "In2.Cu")
		(hatch none 0.5)
		(connect_pads
			(clearance 0)
		)
		(min_thickness 0.25)
		(keepout
			(tracks not_allowed)
			(vias allowed)
			(pads allowed)
			(copperpour not_allowed)
			(footprints allowed)
		)
		(placement
			(enabled no)
			(sheetname "")
		)
		(fill
			(thermal_gap 0.5)
			(thermal_bridge_width 0.5)
			(island_removal_mode 0)
		)
		(polygon
			(pts
				(xy 167.778684 -299.925232) (xy 169.277284 -299.925232) (xy 169.277284 -300.44517) (xy 167.778684 -300.44517)
			)
		)
	)
	(zone
		(layer "In2.Cu")
		(hatch none 0.5)
		(connect_pads
			(clearance 0)
		)
		(min_thickness 0.25)
		(keepout
			(tracks not_allowed)
			(vias allowed)
			(pads allowed)
			(copperpour not_allowed)
			(footprints allowed)
		)
		(placement
			(enabled no)
			(sheetname "")
		)
		(fill
			(thermal_gap 0.5)
			(thermal_bridge_width 0.5)
			(island_removal_mode 0)
		)
		(polygon
			(pts
				(xy 36.046664 -215.775286) (xy 37.545264 -215.775286) (xy 37.545264 -216.295224) (xy 36.046664 -216.295224)
			)
		)
	)
	(zone
		(layer "In2.Cu")
		(hatch none 0.5)
		(connect_pads
			(clearance 0)
		)
		(min_thickness 0.25)
		(keepout
			(tracks not_allowed)
			(vias allowed)
			(pads allowed)
			(copperpour not_allowed)
			(footprints allowed)
		)
		(placement
			(enabled no)
			(sheetname "")
		)
		(fill
			(thermal_gap 0.5)
			(thermal_bridge_width 0.5)
			(island_removal_mode 0)
		)
		(polygon
			(pts
				(xy 434.250846 -244.675152) (xy 435.749446 -244.675152) (xy 435.749446 -245.19509) (xy 434.250846 -245.19509)
			)
		)
	)
	(zone
		(layer "In2.Cu")
		(hatch none 0.5)
		(connect_pads
			(clearance 0)
		)
		(min_thickness 0.25)
		(keepout
			(tracks not_allowed)
			(vias allowed)
			(pads allowed)
			(copperpour not_allowed)
			(footprints allowed)
		)
		(placement
			(enabled no)
			(sheetname "")
		)
		(fill
			(thermal_gap 0.5)
			(thermal_bridge_width 0.5)
			(island_removal_mode 0)
		)
		(polygon
			(pts
				(xy 167.778684 -221.725236) (xy 169.277284 -221.725236) (xy 169.277284 -222.245174) (xy 167.778684 -222.245174)
			)
		)
	)
	(zone
		(layer "In2.Cu")
		(hatch none 0.5)
		(connect_pads
			(clearance 0)
		)
		(min_thickness 0.25)
		(keepout
			(tracks not_allowed)
			(vias allowed)
			(pads allowed)
			(copperpour not_allowed)
			(footprints allowed)
		)
		(placement
			(enabled no)
			(sheetname "")
		)
		(fill
			(thermal_gap 0.5)
			(thermal_bridge_width 0.5)
			(island_removal_mode 0)
		)
		(polygon
			(pts
				(xy 299.07484 -264.225278) (xy 300.57344 -264.225278) (xy 300.57344 -264.745216) (xy 299.07484 -264.745216)
			)
		)
	)
	(zone
		(layer "In2.Cu")
		(hatch none 0.5)
		(connect_pads
			(clearance 0)
		)
		(min_thickness 0.25)
		(keepout
			(tracks not_allowed)
			(vias allowed)
			(pads allowed)
			(copperpour not_allowed)
			(footprints allowed)
		)
		(placement
			(enabled no)
			(sheetname "")
		)
		(fill
			(thermal_gap 0.5)
			(thermal_bridge_width 0.5)
			(island_removal_mode 0)
		)
		(polygon
			(pts
				(xy 453.438768 -316.925198) (xy 454.937368 -316.925198) (xy 454.937368 -317.445136) (xy 453.438768 -317.445136)
			)
		)
	)
	(zone
		(layer "In2.Cu")
		(hatch none 0.5)
		(connect_pads
			(clearance 0)
		)
		(min_thickness 0.25)
		(keepout
			(tracks not_allowed)
			(vias allowed)
			(pads allowed)
			(copperpour not_allowed)
			(footprints allowed)
		)
		(placement
			(enabled no)
			(sheetname "")
		)
		(fill
			(thermal_gap 0.5)
			(thermal_bridge_width 0.5)
			(island_removal_mode 0)
		)
		(polygon
			(pts
				(xy 190.410846 -315.225176) (xy 191.909446 -315.225176) (xy 191.909446 -315.745114) (xy 190.410846 -315.745114)
			)
		)
	)
	(zone
		(layer "In2.Cu")
		(hatch none 0.5)
		(connect_pads
			(clearance 0)
		)
		(min_thickness 0.25)
		(keepout
			(tracks not_allowed)
			(vias allowed)
			(pads allowed)
			(copperpour not_allowed)
			(footprints allowed)
		)
		(placement
			(enabled no)
			(sheetname "")
		)
		(fill
			(thermal_gap 0.5)
			(thermal_bridge_width 0.5)
			(island_removal_mode 0)
		)
		(polygon
			(pts
				(xy 28.50261 -277.8252) (xy 30.00121 -277.8252) (xy 30.00121 -278.345138) (xy 28.50261 -278.345138)
			)
		)
	)
	(zone
		(layer "In2.Cu")
		(hatch none 0.5)
		(connect_pads
			(clearance 0)
		)
		(min_thickness 0.25)
		(keepout
			(tracks not_allowed)
			(vias allowed)
			(pads allowed)
			(copperpour not_allowed)
			(footprints allowed)
		)
		(placement
			(enabled no)
			(sheetname "")
		)
		(fill
			(thermal_gap 0.5)
			(thermal_bridge_width 0.5)
			(island_removal_mode 0)
		)
		(polygon
			(pts
				(xy 272.342864 -272.725134) (xy 273.841464 -272.725134) (xy 273.841464 -273.245072) (xy 272.342864 -273.245072)
			)
		)
	)
	(zone
		(layer "In2.Cu")
		(hatch none 0.5)
		(connect_pads
			(clearance 0)
		)
		(min_thickness 0.25)
		(keepout
			(tracks not_allowed)
			(vias allowed)
			(pads allowed)
			(copperpour not_allowed)
			(footprints allowed)
		)
		(placement
			(enabled no)
			(sheetname "")
		)
		(fill
			(thermal_gap 0.5)
			(thermal_bridge_width 0.5)
			(island_removal_mode 0)
		)
		(polygon
			(pts
				(xy 415.718752 -285.475172) (xy 417.217352 -285.475172) (xy 417.217352 -285.99511) (xy 415.718752 -285.99511)
			)
		)
	)
	(zone
		(layer "In2.Cu")
		(hatch none 0.5)
		(connect_pads
			(clearance 0)
		)
		(min_thickness 0.25)
		(keepout
			(tracks not_allowed)
			(vias allowed)
			(pads allowed)
			(copperpour not_allowed)
			(footprints allowed)
		)
		(placement
			(enabled no)
			(sheetname "")
		)
		(fill
			(thermal_gap 0.5)
			(thermal_bridge_width 0.5)
			(island_removal_mode 0)
		)
		(polygon
			(pts
				(xy 36.046664 -209.825336) (xy 37.545264 -209.825336) (xy 37.545264 -210.345274) (xy 36.046664 -210.345274)
			)
		)
	)
	(zone
		(layer "In2.Cu")
		(hatch none 0.5)
		(connect_pads
			(clearance 0)
		)
		(min_thickness 0.25)
		(keepout
			(tracks not_allowed)
			(vias allowed)
			(pads allowed)
			(copperpour not_allowed)
			(footprints allowed)
		)
		(placement
			(enabled no)
			(sheetname "")
		)
		(fill
			(thermal_gap 0.5)
			(thermal_bridge_width 0.5)
			(island_removal_mode 0)
		)
		(polygon
			(pts
				(xy 299.07484 -209.825336) (xy 300.57344 -209.825336) (xy 300.57344 -210.345274) (xy 299.07484 -210.345274)
			)
		)
	)
	(zone
		(layer "In2.Cu")
		(hatch none 0.5)
		(connect_pads
			(clearance 0)
		)
		(min_thickness 0.25)
		(keepout
			(tracks not_allowed)
			(vias allowed)
			(pads allowed)
			(copperpour not_allowed)
			(footprints allowed)
		)
		(placement
			(enabled no)
			(sheetname "")
		)
		(fill
			(thermal_gap 0.5)
			(thermal_bridge_width 0.5)
			(island_removal_mode 0)
		)
		(polygon
			(pts
				(xy 20.95881 -203.025248) (xy 22.45741 -203.025248) (xy 22.45741 -203.545186) (xy 20.95881 -203.545186)
			)
		)
	)
	(zone
		(layer "In2.Cu")
		(hatch none 0.5)
		(connect_pads
			(clearance 0)
		)
		(min_thickness 0.25)
		(keepout
			(tracks not_allowed)
			(vias allowed)
			(pads allowed)
			(copperpour not_allowed)
			(footprints allowed)
		)
		(placement
			(enabled no)
			(sheetname "")
		)
		(fill
			(thermal_gap 0.5)
			(thermal_bridge_width 0.5)
			(island_removal_mode 0)
		)
		(polygon
			(pts
				(xy 54.578758 -310.12511) (xy 56.077358 -310.12511) (xy 56.077358 -310.645048) (xy 54.578758 -310.645048)
			)
		)
	)
	(zone
		(layer "In2.Cu")
		(hatch none 0.5)
		(connect_pads
			(clearance 0)
		)
		(min_thickness 0.25)
		(keepout
			(tracks not_allowed)
			(vias allowed)
			(pads allowed)
			(copperpour not_allowed)
			(footprints allowed)
		)
		(placement
			(enabled no)
			(sheetname "")
		)
		(fill
			(thermal_gap 0.5)
			(thermal_bridge_width 0.5)
			(island_removal_mode 0)
		)
		(polygon
			(pts
				(xy 283.986732 -208.125314) (xy 285.485332 -208.125314) (xy 285.485332 -208.645252) (xy 283.986732 -208.645252)
			)
		)
	)
	(zone
		(layer "In2.Cu")
		(hatch none 0.5)
		(connect_pads
			(clearance 0)
		)
		(min_thickness 0.25)
		(keepout
			(tracks not_allowed)
			(vias allowed)
			(pads allowed)
			(copperpour not_allowed)
			(footprints allowed)
		)
		(placement
			(enabled no)
			(sheetname "")
		)
		(fill
			(thermal_gap 0.5)
			(thermal_bridge_width 0.5)
			(island_removal_mode 0)
		)
		(polygon
			(pts
				(xy 449.3387 -289.725354) (xy 450.8373 -289.725354) (xy 450.8373 -290.245292) (xy 449.3387 -290.245292)
			)
		)
	)
	(zone
		(layer "In2.Cu")
		(hatch none 0.5)
		(connect_pads
			(clearance 0)
		)
		(min_thickness 0.25)
		(keepout
			(tracks not_allowed)
			(vias allowed)
			(pads allowed)
			(copperpour not_allowed)
			(footprints allowed)
		)
		(placement
			(enabled no)
			(sheetname "")
		)
		(fill
			(thermal_gap 0.5)
			(thermal_bridge_width 0.5)
			(island_removal_mode 0)
		)
		(polygon
			(pts
				(xy 36.046664 -264.225278) (xy 37.545264 -264.225278) (xy 37.545264 -264.745216) (xy 36.046664 -264.745216)
			)
		)
	)
	(zone
		(layer "In2.Cu")
		(hatch none 0.5)
		(connect_pads
			(clearance 0)
		)
		(min_thickness 0.25)
		(keepout
			(tracks not_allowed)
			(vias allowed)
			(pads allowed)
			(copperpour not_allowed)
			(footprints allowed)
		)
		(placement
			(enabled no)
			(sheetname "")
		)
		(fill
			(thermal_gap 0.5)
			(thermal_bridge_width 0.5)
			(island_removal_mode 0)
		)
		(polygon
			(pts
				(xy 20.95881 -221.725236) (xy 22.45741 -221.725236) (xy 22.45741 -222.245174) (xy 20.95881 -222.245174)
			)
		)
	)
	(zone
		(layer "In2.Cu")
		(hatch none 0.5)
		(connect_pads
			(clearance 0)
		)
		(min_thickness 0.25)
		(keepout
			(tracks not_allowed)
			(vias allowed)
			(pads allowed)
			(copperpour not_allowed)
			(footprints allowed)
		)
		(placement
			(enabled no)
			(sheetname "")
		)
		(fill
			(thermal_gap 0.5)
			(thermal_bridge_width 0.5)
			(island_removal_mode 0)
		)
		(polygon
			(pts
				(xy 24.402542 -237.02518) (xy 25.901142 -237.02518) (xy 25.901142 -237.545118) (xy 24.402542 -237.545118)
			)
		)
	)
	(zone
		(layer "In2.Cu")
		(hatch none 0.5)
		(connect_pads
			(clearance 0)
		)
		(min_thickness 0.25)
		(keepout
			(tracks not_allowed)
			(vias allowed)
			(pads allowed)
			(copperpour not_allowed)
			(footprints allowed)
		)
		(placement
			(enabled no)
			(sheetname "")
		)
		(fill
			(thermal_gap 0.5)
			(thermal_bridge_width 0.5)
			(island_removal_mode 0)
		)
		(polygon
			(pts
				(xy 175.322738 -312.67527) (xy 176.821338 -312.67527) (xy 176.821338 -313.195208) (xy 175.322738 -313.195208)
			)
		)
	)
	(zone
		(layer "In2.Cu")
		(hatch none 0.5)
		(connect_pads
			(clearance 0)
		)
		(min_thickness 0.25)
		(keepout
			(tracks allowed)
			(vias allowed)
			(pads allowed)
			(copperpour allowed)
			(footprints allowed)
		)
		(placement
			(enabled no)
			(sheetname "")
		)
		(fill
			(thermal_gap 0.5)
			(thermal_bridge_width 0.5)
			(island_removal_mode 0)
		)
		(polygon
			(pts
				(xy 33.878012 -349.943166) (xy 33.878012 -349.320866) (xy 34.429192 -349.320866) (xy 34.429192 -349.943166)
			)
		)
	)
	(zone
		(layer "In2.Cu")
		(hatch none 0.5)
		(connect_pads
			(clearance 0)
		)
		(min_thickness 0.25)
		(keepout
			(tracks not_allowed)
			(vias allowed)
			(pads allowed)
			(copperpour not_allowed)
			(footprints allowed)
		)
		(placement
			(enabled no)
			(sheetname "")
		)
		(fill
			(thermal_gap 0.5)
			(thermal_bridge_width 0.5)
			(island_removal_mode 0)
		)
		(polygon
			(pts
				(xy 16.858742 -205.575154) (xy 18.357342 -205.575154) (xy 18.357342 -206.095092) (xy 16.858742 -206.095092)
			)
		)
	)
	(zone
		(layer "In2.Cu")
		(hatch none 0.5)
		(connect_pads
			(clearance 0)
		)
		(min_thickness 0.25)
		(keepout
			(tracks not_allowed)
			(vias allowed)
			(pads allowed)
			(copperpour not_allowed)
			(footprints allowed)
		)
		(placement
			(enabled no)
			(sheetname "")
		)
		(fill
			(thermal_gap 0.5)
			(thermal_bridge_width 0.5)
			(island_removal_mode 0)
		)
		(polygon
			(pts
				(xy 15.03807 -105.92562)
				(arc
					(start 15.03807 -106.065828)
					(mid 15.067279 -106.13571)
					(end 15.137384 -106.16438)
				)
				(arc
					(start 15.438628 -106.16438)
					(mid 15.508733 -106.13571)
					(end 15.537942 -106.065828)
				)
				(xy 15.537942 -105.92562) (xy 15.477998 -105.92562)
				(arc
					(start 15.477998 -105.356406)
					(mid 15.521497 -105.320037)
					(end 15.537942 -105.265728)
				)
				(arc
					(start 15.537942 -105.005632)
					(mid 15.521623 -104.95124)
					(end 15.477998 -104.914954)
				)
				(xy 15.477998 -104.34574) (xy 15.537942 -104.34574)
				(arc
					(start 15.537942 -104.205532)
					(mid 15.508733 -104.13565)
					(end 15.438628 -104.10698)
				)
				(arc
					(start 15.137384 -104.10698)
					(mid 15.067279 -104.13565)
					(end 15.03807 -104.205532)
				)
				(xy 15.03807 -104.34574) (xy 15.098014 -104.34574)
				(arc
					(start 15.098014 -104.914954)
					(mid 15.054515 -104.951323)
					(end 15.03807 -105.005632)
				)
				(arc
					(start 15.03807 -105.265728)
					(mid 15.054389 -105.32012)
					(end 15.098014 -105.356406)
				)
				(xy 15.098014 -105.92562)
			)
		)
	)
	(zone
		(layer "In2.Cu")
		(hatch none 0.5)
		(connect_pads
			(clearance 0)
		)
		(min_thickness 0.25)
		(keepout
			(tracks not_allowed)
			(vias allowed)
			(pads allowed)
			(copperpour not_allowed)
			(footprints allowed)
		)
		(placement
			(enabled no)
			(sheetname "")
		)
		(fill
			(thermal_gap 0.5)
			(thermal_bridge_width 0.5)
			(island_removal_mode 0)
		)
		(polygon
			(pts
				(xy 47.034704 -276.125178) (xy 48.533304 -276.125178) (xy 48.533304 -276.645116) (xy 47.034704 -276.645116)
			)
		)
	)
	(zone
		(layer "In2.Cu")
		(hatch none 0.5)
		(connect_pads
			(clearance 0)
		)
		(min_thickness 0.25)
		(keepout
			(tracks allowed)
			(vias allowed)
			(pads allowed)
			(copperpour allowed)
			(footprints allowed)
		)
		(placement
			(enabled no)
			(sheetname "")
		)
		(fill
			(thermal_gap 0.5)
			(thermal_bridge_width 0.5)
			(island_removal_mode 0)
		)
		(polygon
			(pts
				(xy 92.446094 -150.933912) (xy 85.638894 -150.933912) (xy 78.653894 -157.918912) (xy 66.157094 -157.918912)
				(xy 59.680094 -164.395912) (xy 59.680094 -179.610512) (xy 58.308494 -180.982112) (xy 56.911494 -180.982112)
				(xy 56.708294 -181.185312) (xy 56.708294 -181.845712) (xy 56.886094 -182.023512) (xy 57.114694 -182.023512)
				(xy 57.292494 -181.845712) (xy 58.638694 -181.845712) (xy 60.416694 -180.067712) (xy 60.416694 -164.903912)
				(xy 66.614294 -158.706312) (xy 79.009494 -158.706312) (xy 86.045294 -151.670512) (xy 92.395294 -151.670512)
				(xy 92.598494 -151.467312) (xy 92.598494 -151.086312)
			)
		)
	)
	(zone
		(layer "In2.Cu")
		(hatch none 0.5)
		(connect_pads
			(clearance 0)
		)
		(min_thickness 0.25)
		(keepout
			(tracks not_allowed)
			(vias allowed)
			(pads allowed)
			(copperpour not_allowed)
			(footprints allowed)
		)
		(placement
			(enabled no)
			(sheetname "")
		)
		(fill
			(thermal_gap 0.5)
			(thermal_bridge_width 0.5)
			(island_removal_mode 0)
		)
		(polygon
			(pts
				(xy 441.7949 -261.675118) (xy 443.2935 -261.675118) (xy 443.2935 -262.195056) (xy 441.7949 -262.195056)
			)
		)
	)
	(zone
		(layer "In2.Cu")
		(hatch none 0.5)
		(connect_pads
			(clearance 0)
		)
		(min_thickness 0.25)
		(keepout
			(tracks not_allowed)
			(vias allowed)
			(pads allowed)
			(copperpour not_allowed)
			(footprints allowed)
		)
		(placement
			(enabled no)
			(sheetname "")
		)
		(fill
			(thermal_gap 0.5)
			(thermal_bridge_width 0.5)
			(island_removal_mode 0)
		)
		(polygon
			(pts
				(xy 201.398632 -210.67522) (xy 202.897232 -210.67522) (xy 202.897232 -211.195158) (xy 201.398632 -211.195158)
			)
		)
	)
	(zone
		(layer "In2.Cu")
		(hatch none 0.5)
		(connect_pads
			(clearance 0)
		)
		(min_thickness 0.25)
		(keepout
			(tracks not_allowed)
			(vias allowed)
			(pads allowed)
			(copperpour not_allowed)
			(footprints allowed)
		)
		(placement
			(enabled no)
			(sheetname "")
		)
		(fill
			(thermal_gap 0.5)
			(thermal_bridge_width 0.5)
			(island_removal_mode 0)
		)
		(polygon
			(pts
				(xy 24.402542 -276.975316) (xy 25.901142 -276.975316) (xy 25.901142 -277.495254) (xy 24.402542 -277.495254)
			)
		)
	)
	(zone
		(layer "In2.Cu")
		(hatch none 0.5)
		(connect_pads
			(clearance 0)
		)
		(min_thickness 0.25)
		(keepout
			(tracks not_allowed)
			(vias allowed)
			(pads allowed)
			(copperpour not_allowed)
			(footprints allowed)
		)
		(placement
			(enabled no)
			(sheetname "")
		)
		(fill
			(thermal_gap 0.5)
			(thermal_bridge_width 0.5)
			(island_removal_mode 0)
		)
		(polygon
			(pts
				(xy 47.034704 -214.925148) (xy 48.533304 -214.925148) (xy 48.533304 -215.445086) (xy 47.034704 -215.445086)
			)
		)
	)
	(zone
		(layer "In2.Cu")
		(hatch none 0.5)
		(connect_pads
			(clearance 0)
		)
		(min_thickness 0.25)
		(keepout
			(tracks not_allowed)
			(vias allowed)
			(pads allowed)
			(copperpour not_allowed)
			(footprints allowed)
		)
		(placement
			(enabled no)
			(sheetname "")
		)
		(fill
			(thermal_gap 0.5)
			(thermal_bridge_width 0.5)
			(island_removal_mode 0)
		)
		(polygon
			(pts
				(xy 51.134772 -270.175228) (xy 52.633372 -270.175228) (xy 52.633372 -270.695166) (xy 51.134772 -270.695166)
			)
		)
	)
	(zone
		(layer "In2.Cu")
		(hatch none 0.5)
		(connect_pads
			(clearance 0)
		)
		(min_thickness 0.25)
		(keepout
			(tracks not_allowed)
			(vias allowed)
			(pads allowed)
			(copperpour not_allowed)
			(footprints allowed)
		)
		(placement
			(enabled no)
			(sheetname "")
		)
		(fill
			(thermal_gap 0.5)
			(thermal_bridge_width 0.5)
			(island_removal_mode 0)
		)
		(polygon
			(pts
				(xy 411.618684 -213.225126) (xy 413.117284 -213.225126) (xy 413.117284 -213.745064) (xy 411.618684 -213.745064)
			)
		)
	)
	(zone
		(layer "In2.Cu")
		(hatch none 0.5)
		(connect_pads
			(clearance 0)
		)
		(min_thickness 0.25)
		(keepout
			(tracks allowed)
			(vias allowed)
			(pads allowed)
			(copperpour allowed)
			(footprints allowed)
		)
		(placement
			(enabled no)
			(sheetname "")
		)
		(fill
			(thermal_gap 0.5)
			(thermal_bridge_width 0.5)
			(island_removal_mode 0)
		)
		(polygon
			(pts
				(xy 302.90897 -349.117666) (xy 302.90897 -348.495366) (xy 303.46015 -348.495366) (xy 303.46015 -349.117666)
			)
		)
	)
	(zone
		(layer "In2.Cu")
		(hatch none 0.5)
		(connect_pads
			(clearance 0)
		)
		(min_thickness 0.25)
		(keepout
			(tracks not_allowed)
			(vias allowed)
			(pads allowed)
			(copperpour not_allowed)
			(footprints allowed)
		)
		(placement
			(enabled no)
			(sheetname "")
		)
		(fill
			(thermal_gap 0.5)
			(thermal_bridge_width 0.5)
			(island_removal_mode 0)
		)
		(polygon
			(pts
				(xy 197.954646 -298.22521) (xy 199.453246 -298.22521) (xy 199.453246 -298.745148) (xy 197.954646 -298.745148)
			)
		)
	)
	(zone
		(layer "In2.Cu")
		(hatch none 0.5)
		(connect_pads
			(clearance 0)
		)
		(min_thickness 0.25)
		(keepout
			(tracks not_allowed)
			(vias allowed)
			(pads allowed)
			(copperpour not_allowed)
			(footprints allowed)
		)
		(placement
			(enabled no)
			(sheetname "")
		)
		(fill
			(thermal_gap 0.5)
			(thermal_bridge_width 0.5)
			(island_removal_mode 0)
		)
		(polygon
			(pts
				(xy 306.618894 -312.67527) (xy 308.117494 -312.67527) (xy 308.117494 -313.195208) (xy 306.618894 -313.195208)
			)
		)
	)
	(zone
		(layer "In2.Cu")
		(hatch none 0.5)
		(connect_pads
			(clearance 0)
		)
		(min_thickness 0.25)
		(keepout
			(tracks not_allowed)
			(vias allowed)
			(pads allowed)
			(copperpour not_allowed)
			(footprints allowed)
		)
		(placement
			(enabled no)
			(sheetname "")
		)
		(fill
			(thermal_gap 0.5)
			(thermal_bridge_width 0.5)
			(island_removal_mode 0)
		)
		(polygon
			(pts
				(xy 423.262806 -228.525324) (xy 424.761406 -228.525324) (xy 424.761406 -229.045262) (xy 423.262806 -229.045262)
			)
		)
	)
	(zone
		(layer "In2.Cu")
		(hatch none 0.5)
		(connect_pads
			(clearance 0)
		)
		(min_thickness 0.25)
		(keepout
			(tracks not_allowed)
			(vias allowed)
			(pads allowed)
			(copperpour not_allowed)
			(footprints allowed)
		)
		(placement
			(enabled no)
			(sheetname "")
		)
		(fill
			(thermal_gap 0.5)
			(thermal_bridge_width 0.5)
			(island_removal_mode 0)
		)
		(polygon
			(pts
				(xy 272.342864 -299.075348) (xy 273.841464 -299.075348) (xy 273.841464 -299.595286) (xy 272.342864 -299.595286)
			)
		)
	)
	(zone
		(layer "In2.Cu")
		(hatch none 0.5)
		(connect_pads
			(clearance 0)
		)
		(min_thickness 0.25)
		(keepout
			(tracks not_allowed)
			(vias allowed)
			(pads allowed)
			(copperpour not_allowed)
			(footprints allowed)
		)
		(placement
			(enabled no)
			(sheetname "")
		)
		(fill
			(thermal_gap 0.5)
			(thermal_bridge_width 0.5)
			(island_removal_mode 0)
		)
		(polygon
			(pts
				(xy 197.954646 -219.17533) (xy 199.453246 -219.17533) (xy 199.453246 -219.695268) (xy 197.954646 -219.695268)
			)
		)
	)
	(zone
		(layer "In2.Cu")
		(hatch none 0.5)
		(connect_pads
			(clearance 0)
		)
		(min_thickness 0.25)
		(keepout
			(tracks not_allowed)
			(vias allowed)
			(pads allowed)
			(copperpour not_allowed)
			(footprints allowed)
		)
		(placement
			(enabled no)
			(sheetname "")
		)
		(fill
			(thermal_gap 0.5)
			(thermal_bridge_width 0.5)
			(island_removal_mode 0)
		)
		(polygon
			(pts
				(xy 438.350914 -209.825336) (xy 439.849514 -209.825336) (xy 439.849514 -210.345274) (xy 438.350914 -210.345274)
			)
		)
	)
	(zone
		(layer "In2.Cu")
		(hatch none 0.5)
		(connect_pads
			(clearance 0)
		)
		(min_thickness 0.25)
		(keepout
			(tracks not_allowed)
			(vias allowed)
			(pads allowed)
			(copperpour not_allowed)
			(footprints allowed)
		)
		(placement
			(enabled no)
			(sheetname "")
		)
		(fill
			(thermal_gap 0.5)
			(thermal_bridge_width 0.5)
			(island_removal_mode 0)
		)
		(polygon
			(pts
				(xy 16.858742 -263.37514) (xy 18.357342 -263.37514) (xy 18.357342 -263.895078) (xy 16.858742 -263.895078)
			)
		)
	)
	(zone
		(layer "In2.Cu")
		(hatch none 0.5)
		(connect_pads
			(clearance 0)
		)
		(min_thickness 0.25)
		(keepout
			(tracks not_allowed)
			(vias allowed)
			(pads allowed)
			(copperpour not_allowed)
			(footprints allowed)
		)
		(placement
			(enabled no)
			(sheetname "")
		)
		(fill
			(thermal_gap 0.5)
			(thermal_bridge_width 0.5)
			(island_removal_mode 0)
		)
		(polygon
			(pts
				(xy 186.310778 -268.475206) (xy 187.809378 -268.475206) (xy 187.809378 -268.995144) (xy 186.310778 -268.995144)
			)
		)
	)
	(zone
		(layer "In2.Cu")
		(hatch none 0.5)
		(connect_pads
			(clearance 0)
		)
		(min_thickness 0.25)
		(keepout
			(tracks not_allowed)
			(vias allowed)
			(pads allowed)
			(copperpour not_allowed)
			(footprints allowed)
		)
		(placement
			(enabled no)
			(sheetname "")
		)
		(fill
			(thermal_gap 0.5)
			(thermal_bridge_width 0.5)
			(island_removal_mode 0)
		)
		(polygon
			(pts
				(xy 299.07484 -277.8252) (xy 300.57344 -277.8252) (xy 300.57344 -278.345138) (xy 299.07484 -278.345138)
			)
		)
	)
	(zone
		(layer "In2.Cu")
		(hatch none 0.5)
		(connect_pads
			(clearance 0)
		)
		(min_thickness 0.25)
		(keepout
			(tracks not_allowed)
			(vias allowed)
			(pads allowed)
			(copperpour not_allowed)
			(footprints allowed)
		)
		(placement
			(enabled no)
			(sheetname "")
		)
		(fill
			(thermal_gap 0.5)
			(thermal_bridge_width 0.5)
			(island_removal_mode 0)
		)
		(polygon
			(pts
				(xy 268.898878 -210.67522) (xy 270.397478 -210.67522) (xy 270.397478 -211.195158) (xy 268.898878 -211.195158)
			)
		)
	)
	(zone
		(layer "In2.Cu")
		(hatch none 0.5)
		(connect_pads
			(clearance 0)
		)
		(min_thickness 0.25)
		(keepout
			(tracks allowed)
			(vias allowed)
			(pads allowed)
			(copperpour allowed)
			(footprints allowed)
		)
		(placement
			(enabled no)
			(sheetname "")
		)
		(fill
			(thermal_gap 0.5)
			(thermal_bridge_width 0.5)
			(island_removal_mode 0)
		)
		(polygon
			(pts
				(xy 90.55481 -338.116418) (xy 90.55481 -337.494118) (xy 91.10599 -337.494118) (xy 91.10599 -338.116418)
			)
		)
	)
	(zone
		(layer "In2.Cu")
		(hatch none 0.5)
		(connect_pads
			(clearance 0)
		)
		(min_thickness 0.25)
		(keepout
			(tracks not_allowed)
			(vias allowed)
			(pads allowed)
			(copperpour not_allowed)
			(footprints allowed)
		)
		(placement
			(enabled no)
			(sheetname "")
		)
		(fill
			(thermal_gap 0.5)
			(thermal_bridge_width 0.5)
			(island_removal_mode 0)
		)
		(polygon
			(pts
				(xy 279.886664 -246.375174) (xy 281.385264 -246.375174) (xy 281.385264 -246.895112) (xy 279.886664 -246.895112)
			)
		)
	)
	(zone
		(layer "In2.Cu")
		(hatch none 0.5)
		(connect_pads
			(clearance 0)
		)
		(min_thickness 0.25)
		(keepout
			(tracks not_allowed)
			(vias allowed)
			(pads allowed)
			(copperpour not_allowed)
			(footprints allowed)
		)
		(placement
			(enabled no)
			(sheetname "")
		)
		(fill
			(thermal_gap 0.5)
			(thermal_bridge_width 0.5)
			(island_removal_mode 0)
		)
		(polygon
			(pts
				(xy 54.578758 -227.675186) (xy 56.077358 -227.675186) (xy 56.077358 -228.195124) (xy 54.578758 -228.195124)
			)
		)
	)
	(zone
		(layer "In2.Cu")
		(hatch none 0.5)
		(connect_pads
			(clearance 0)
		)
		(min_thickness 0.25)
		(keepout
			(tracks not_allowed)
			(vias allowed)
			(pads allowed)
			(copperpour not_allowed)
			(footprints allowed)
		)
		(placement
			(enabled no)
			(sheetname "")
		)
		(fill
			(thermal_gap 0.5)
			(thermal_bridge_width 0.5)
			(island_removal_mode 0)
		)
		(polygon
			(pts
				(xy 272.342864 -278.675338) (xy 273.841464 -278.675338) (xy 273.841464 -279.195276) (xy 272.342864 -279.195276)
			)
		)
	)
	(zone
		(layer "In2.Cu")
		(hatch none 0.5)
		(connect_pads
			(clearance 0)
		)
		(min_thickness 0.25)
		(keepout
			(tracks not_allowed)
			(vias allowed)
			(pads allowed)
			(copperpour not_allowed)
			(footprints allowed)
		)
		(placement
			(enabled no)
			(sheetname "")
		)
		(fill
			(thermal_gap 0.5)
			(thermal_bridge_width 0.5)
			(island_removal_mode 0)
		)
		(polygon
			(pts
				(xy 171.22267 -208.975198) (xy 172.72127 -208.975198) (xy 172.72127 -209.495136) (xy 171.22267 -209.495136)
			)
		)
	)
	(zone
		(layer "In2.Cu")
		(hatch none 0.5)
		(connect_pads
			(clearance 0)
		)
		(min_thickness 0.25)
		(keepout
			(tracks not_allowed)
			(vias allowed)
			(pads allowed)
			(copperpour not_allowed)
			(footprints allowed)
		)
		(placement
			(enabled no)
			(sheetname "")
		)
		(fill
			(thermal_gap 0.5)
			(thermal_bridge_width 0.5)
			(island_removal_mode 0)
		)
		(polygon
			(pts
				(xy 167.778684 -210.67522) (xy 169.277284 -210.67522) (xy 169.277284 -211.195158) (xy 167.778684 -211.195158)
			)
		)
	)
	(zone
		(layer "In2.Cu")
		(hatch none 0.5)
		(connect_pads
			(clearance 0)
		)
		(min_thickness 0.25)
		(keepout
			(tracks not_allowed)
			(vias allowed)
			(pads allowed)
			(copperpour not_allowed)
			(footprints allowed)
		)
		(placement
			(enabled no)
			(sheetname "")
		)
		(fill
			(thermal_gap 0.5)
			(thermal_bridge_width 0.5)
			(island_removal_mode 0)
		)
		(polygon
			(pts
				(xy 441.7949 -314.375292) (xy 443.2935 -314.375292) (xy 443.2935 -314.89523) (xy 441.7949 -314.89523)
			)
		)
	)
	(zone
		(layer "In2.Cu")
		(hatch none 0.5)
		(connect_pads
			(clearance 0)
		)
		(min_thickness 0.25)
		(keepout
			(tracks not_allowed)
			(vias allowed)
			(pads allowed)
			(copperpour not_allowed)
			(footprints allowed)
		)
		(placement
			(enabled no)
			(sheetname "")
		)
		(fill
			(thermal_gap 0.5)
			(thermal_bridge_width 0.5)
			(island_removal_mode 0)
		)
		(polygon
			(pts
				(xy 47.034704 -237.02518) (xy 48.533304 -237.02518) (xy 48.533304 -237.545118) (xy 47.034704 -237.545118)
			)
		)
	)
	(zone
		(layer "In2.Cu")
		(hatch none 0.5)
		(connect_pads
			(clearance 0)
		)
		(min_thickness 0.25)
		(keepout
			(tracks not_allowed)
			(vias allowed)
			(pads allowed)
			(copperpour not_allowed)
			(footprints allowed)
		)
		(placement
			(enabled no)
			(sheetname "")
		)
		(fill
			(thermal_gap 0.5)
			(thermal_bridge_width 0.5)
			(island_removal_mode 0)
		)
		(polygon
			(pts
				(xy 306.618894 -201.325226) (xy 308.117494 -201.325226) (xy 308.117494 -201.845164) (xy 306.618894 -201.845164)
			)
		)
	)
	(zone
		(layer "In2.Cu")
		(hatch none 0.5)
		(connect_pads
			(clearance 0)
		)
		(min_thickness 0.25)
		(keepout
			(tracks not_allowed)
			(vias allowed)
			(pads allowed)
			(copperpour not_allowed)
			(footprints allowed)
		)
		(placement
			(enabled no)
			(sheetname "")
		)
		(fill
			(thermal_gap 0.5)
			(thermal_bridge_width 0.5)
			(island_removal_mode 0)
		)
		(polygon
			(pts
				(xy 434.250846 -230.225346) (xy 435.749446 -230.225346) (xy 435.749446 -230.745284) (xy 434.250846 -230.745284)
			)
		)
	)
	(zone
		(layer "In2.Cu")
		(hatch none 0.5)
		(connect_pads
			(clearance 0)
		)
		(min_thickness 0.25)
		(keepout
			(tracks not_allowed)
			(vias allowed)
			(pads allowed)
			(copperpour not_allowed)
			(footprints allowed)
		)
		(placement
			(enabled no)
			(sheetname "")
		)
		(fill
			(thermal_gap 0.5)
			(thermal_bridge_width 0.5)
			(island_removal_mode 0)
		)
		(polygon
			(pts
				(xy 283.986732 -307.575204) (xy 285.485332 -307.575204) (xy 285.485332 -308.095142) (xy 283.986732 -308.095142)
			)
		)
	)
	(zone
		(layer "In2.Cu")
		(hatch none 0.5)
		(connect_pads
			(clearance 0)
		)
		(min_thickness 0.25)
		(keepout
			(tracks not_allowed)
			(vias allowed)
			(pads allowed)
			(copperpour not_allowed)
			(footprints allowed)
		)
		(placement
			(enabled no)
			(sheetname "")
		)
		(fill
			(thermal_gap 0.5)
			(thermal_bridge_width 0.5)
			(island_removal_mode 0)
		)
		(polygon
			(pts
				(xy 287.430718 -248.075196) (xy 288.929318 -248.075196) (xy 288.929318 -248.595134) (xy 287.430718 -248.595134)
			)
		)
	)
	(zone
		(layer "In2.Cu")
		(hatch none 0.5)
		(connect_pads
			(clearance 0)
		)
		(min_thickness 0.25)
		(keepout
			(tracks not_allowed)
			(vias allowed)
			(pads allowed)
			(copperpour not_allowed)
			(footprints allowed)
		)
		(placement
			(enabled no)
			(sheetname "")
		)
		(fill
			(thermal_gap 0.5)
			(thermal_bridge_width 0.5)
			(island_removal_mode 0)
		)
		(polygon
			(pts
				(xy 268.898878 -232.775252) (xy 270.397478 -232.775252) (xy 270.397478 -233.29519) (xy 268.898878 -233.29519)
			)
		)
	)
	(zone
		(layer "In2.Cu")
		(hatch none 0.5)
		(connect_pads
			(clearance 0)
		)
		(min_thickness 0.25)
		(keepout
			(tracks not_allowed)
			(vias allowed)
			(pads allowed)
			(copperpour not_allowed)
			(footprints allowed)
		)
		(placement
			(enabled no)
			(sheetname "")
		)
		(fill
			(thermal_gap 0.5)
			(thermal_bridge_width 0.5)
			(island_removal_mode 0)
		)
		(polygon
			(pts
				(xy 291.530786 -243.825268) (xy 293.029386 -243.825268) (xy 293.029386 -244.345206) (xy 291.530786 -244.345206)
			)
		)
	)
	(zone
		(layer "In2.Cu")
		(hatch none 0.5)
		(connect_pads
			(clearance 0)
		)
		(min_thickness 0.25)
		(keepout
			(tracks not_allowed)
			(vias allowed)
			(pads allowed)
			(copperpour not_allowed)
			(footprints allowed)
		)
		(placement
			(enabled no)
			(sheetname "")
		)
		(fill
			(thermal_gap 0.5)
			(thermal_bridge_width 0.5)
			(island_removal_mode 0)
		)
		(polygon
			(pts
				(xy 445.894968 -282.925266) (xy 447.393568 -282.925266) (xy 447.393568 -283.445204) (xy 445.894968 -283.445204)
			)
		)
	)
	(zone
		(layer "In2.Cu")
		(hatch none 0.5)
		(connect_pads
			(clearance 0)
		)
		(min_thickness 0.25)
		(keepout
			(tracks not_allowed)
			(vias allowed)
			(pads allowed)
			(copperpour not_allowed)
			(footprints allowed)
		)
		(placement
			(enabled no)
			(sheetname "")
		)
		(fill
			(thermal_gap 0.5)
			(thermal_bridge_width 0.5)
			(island_removal_mode 0)
		)
		(polygon
			(pts
				(xy 268.898878 -250.625102) (xy 270.397478 -250.625102) (xy 270.397478 -251.14504) (xy 268.898878 -251.14504)
			)
		)
	)
	(zone
		(layer "In2.Cu")
		(hatch none 0.5)
		(connect_pads
			(clearance 0)
		)
		(min_thickness 0.25)
		(keepout
			(tracks not_allowed)
			(vias allowed)
			(pads allowed)
			(copperpour not_allowed)
			(footprints allowed)
		)
		(placement
			(enabled no)
			(sheetname "")
		)
		(fill
			(thermal_gap 0.5)
			(thermal_bridge_width 0.5)
			(island_removal_mode 0)
		)
		(polygon
			(pts
				(xy 426.706792 -208.975198) (xy 428.205392 -208.975198) (xy 428.205392 -209.495136) (xy 426.706792 -209.495136)
			)
		)
	)
	(zone
		(layer "In2.Cu")
		(hatch none 0.5)
		(connect_pads
			(clearance 0)
		)
		(min_thickness 0.25)
		(keepout
			(tracks not_allowed)
			(vias allowed)
			(pads allowed)
			(copperpour not_allowed)
			(footprints allowed)
		)
		(placement
			(enabled no)
			(sheetname "")
		)
		(fill
			(thermal_gap 0.5)
			(thermal_bridge_width 0.5)
			(island_removal_mode 0)
		)
		(polygon
			(pts
				(xy 28.50261 -248.925334) (xy 30.00121 -248.925334) (xy 30.00121 -249.445272) (xy 28.50261 -249.445272)
			)
		)
	)
	(zone
		(layer "In2.Cu")
		(hatch none 0.5)
		(connect_pads
			(clearance 0)
		)
		(min_thickness 0.25)
		(keepout
			(tracks not_allowed)
			(vias allowed)
			(pads allowed)
			(copperpour not_allowed)
			(footprints allowed)
		)
		(placement
			(enabled no)
			(sheetname "")
		)
		(fill
			(thermal_gap 0.5)
			(thermal_bridge_width 0.5)
			(island_removal_mode 0)
		)
		(polygon
			(pts
				(xy 299.07484 -260.825234) (xy 300.57344 -260.825234) (xy 300.57344 -261.345172) (xy 299.07484 -261.345172)
			)
		)
	)
	(zone
		(layer "In2.Cu")
		(hatch none 0.5)
		(connect_pads
			(clearance 0)
		)
		(min_thickness 0.25)
		(keepout
			(tracks not_allowed)
			(vias allowed)
			(pads allowed)
			(copperpour not_allowed)
			(footprints allowed)
		)
		(placement
			(enabled no)
			(sheetname "")
		)
		(fill
			(thermal_gap 0.5)
			(thermal_bridge_width 0.5)
			(island_removal_mode 0)
		)
		(polygon
			(pts
				(xy 302.518826 -305.025298) (xy 304.017426 -305.025298) (xy 304.017426 -305.545236) (xy 302.518826 -305.545236)
			)
		)
	)
	(zone
		(layer "In2.Cu")
		(hatch none 0.5)
		(connect_pads
			(clearance 0)
		)
		(min_thickness 0.25)
		(keepout
			(tracks not_allowed)
			(vias allowed)
			(pads allowed)
			(copperpour not_allowed)
			(footprints allowed)
		)
		(placement
			(enabled no)
			(sheetname "")
		)
		(fill
			(thermal_gap 0.5)
			(thermal_bridge_width 0.5)
			(island_removal_mode 0)
		)
		(polygon
			(pts
				(xy 58.678826 -212.375242) (xy 60.177426 -212.375242) (xy 60.177426 -212.89518) (xy 58.678826 -212.89518)
			)
		)
	)
	(zone
		(layer "In2.Cu")
		(hatch none 0.5)
		(connect_pads
			(clearance 0)
		)
		(min_thickness 0.25)
		(keepout
			(tracks not_allowed)
			(vias allowed)
			(pads allowed)
			(copperpour not_allowed)
			(footprints allowed)
		)
		(placement
			(enabled no)
			(sheetname "")
		)
		(fill
			(thermal_gap 0.5)
			(thermal_bridge_width 0.5)
			(island_removal_mode 0)
		)
		(polygon
			(pts
				(xy 58.678826 -305.875182) (xy 60.177426 -305.875182) (xy 60.177426 -306.39512) (xy 58.678826 -306.39512)
			)
		)
	)
	(zone
		(layer "In2.Cu")
		(hatch none 0.5)
		(connect_pads
			(clearance 0)
		)
		(min_thickness 0.25)
		(keepout
			(tracks not_allowed)
			(vias allowed)
			(pads allowed)
			(copperpour not_allowed)
			(footprints allowed)
		)
		(placement
			(enabled no)
			(sheetname "")
		)
		(fill
			(thermal_gap 0.5)
			(thermal_bridge_width 0.5)
			(island_removal_mode 0)
		)
		(polygon
			(pts
				(xy 54.578758 -253.175262) (xy 56.077358 -253.175262) (xy 56.077358 -253.6952) (xy 54.578758 -253.6952)
			)
		)
	)
	(zone
		(layer "In2.Cu")
		(hatch none 0.5)
		(connect_pads
			(clearance 0)
		)
		(min_thickness 0.25)
		(keepout
			(tracks not_allowed)
			(vias allowed)
			(pads allowed)
			(copperpour not_allowed)
			(footprints allowed)
		)
		(placement
			(enabled no)
			(sheetname "")
		)
		(fill
			(thermal_gap 0.5)
			(thermal_bridge_width 0.5)
			(island_removal_mode 0)
		)
		(polygon
			(pts
				(xy 20.95881 -223.425258) (xy 22.45741 -223.425258) (xy 22.45741 -223.945196) (xy 20.95881 -223.945196)
			)
		)
	)
	(zone
		(layer "In2.Cu")
		(hatch none 0.5)
		(connect_pads
			(clearance 0)
		)
		(min_thickness 0.25)
		(keepout
			(tracks not_allowed)
			(vias allowed)
			(pads allowed)
			(copperpour not_allowed)
			(footprints allowed)
		)
		(placement
			(enabled no)
			(sheetname "")
		)
		(fill
			(thermal_gap 0.5)
			(thermal_bridge_width 0.5)
			(island_removal_mode 0)
		)
		(polygon
			(pts
				(xy 175.322738 -197.075298) (xy 176.821338 -197.075298) (xy 176.821338 -197.595236) (xy 175.322738 -197.595236)
			)
		)
	)
	(zone
		(layer "In2.Cu")
		(hatch none 0.5)
		(connect_pads
			(clearance 0)
		)
		(min_thickness 0.25)
		(keepout
			(tracks allowed)
			(vias allowed)
			(pads allowed)
			(copperpour allowed)
			(footprints allowed)
		)
		(placement
			(enabled no)
			(sheetname "")
		)
		(fill
			(thermal_gap 0.5)
			(thermal_bridge_width 0.5)
			(island_removal_mode 0)
		)
		(polygon
			(pts
				(xy 95.083122 -179.443634) (xy 95.083122 -178.89728) (xy 95.635572 -178.89728) (xy 95.635572 -179.443634)
			)
		)
	)
	(zone
		(layer "In2.Cu")
		(hatch none 0.5)
		(connect_pads
			(clearance 0)
		)
		(min_thickness 0.25)
		(keepout
			(tracks not_allowed)
			(vias allowed)
			(pads allowed)
			(copperpour not_allowed)
			(footprints allowed)
		)
		(placement
			(enabled no)
			(sheetname "")
		)
		(fill
			(thermal_gap 0.5)
			(thermal_bridge_width 0.5)
			(island_removal_mode 0)
		)
		(polygon
			(pts
				(xy 186.310778 -295.675304) (xy 187.809378 -295.675304) (xy 187.809378 -296.195242) (xy 186.310778 -296.195242)
			)
		)
	)
	(zone
		(layer "In2.Cu")
		(hatch none 0.5)
		(connect_pads
			(clearance 0)
		)
		(min_thickness 0.25)
		(keepout
			(tracks not_allowed)
			(vias allowed)
			(pads allowed)
			(copperpour not_allowed)
			(footprints allowed)
		)
		(placement
			(enabled no)
			(sheetname "")
		)
		(fill
			(thermal_gap 0.5)
			(thermal_bridge_width 0.5)
			(island_removal_mode 0)
		)
		(polygon
			(pts
				(xy 171.22267 -294.825166) (xy 172.72127 -294.825166) (xy 172.72127 -295.345104) (xy 171.22267 -295.345104)
			)
		)
	)
	(zone
		(layer "In2.Cu")
		(hatch none 0.5)
		(connect_pads
			(clearance 0)
		)
		(min_thickness 0.25)
		(keepout
			(tracks allowed)
			(vias allowed)
			(pads allowed)
			(copperpour allowed)
			(footprints allowed)
		)
		(placement
			(enabled no)
			(sheetname "")
		)
		(fill
			(thermal_gap 0.5)
			(thermal_bridge_width 0.5)
			(island_removal_mode 0)
		)
		(polygon
			(pts
				(xy 277.96617 -349.854266) (xy 277.96617 -349.231966) (xy 278.51735 -349.231966) (xy 278.51735 -349.854266)
			)
		)
	)
	(zone
		(layer "In2.Cu")
		(hatch none 0.5)
		(connect_pads
			(clearance 0)
		)
		(min_thickness 0.25)
		(keepout
			(tracks not_allowed)
			(vias allowed)
			(pads allowed)
			(copperpour not_allowed)
			(footprints allowed)
		)
		(placement
			(enabled no)
			(sheetname "")
		)
		(fill
			(thermal_gap 0.5)
			(thermal_bridge_width 0.5)
			(island_removal_mode 0)
		)
		(polygon
			(pts
				(xy 171.22267 -299.075348) (xy 172.72127 -299.075348) (xy 172.72127 -299.595286) (xy 171.22267 -299.595286)
			)
		)
	)
	(zone
		(layer "In2.Cu")
		(hatch none 0.5)
		(connect_pads
			(clearance 0)
		)
		(min_thickness 0.25)
		(keepout
			(tracks not_allowed)
			(vias allowed)
			(pads allowed)
			(copperpour not_allowed)
			(footprints allowed)
		)
		(placement
			(enabled no)
			(sheetname "")
		)
		(fill
			(thermal_gap 0.5)
			(thermal_bridge_width 0.5)
			(island_removal_mode 0)
		)
		(polygon
			(pts
				(xy 434.250846 -282.075128) (xy 435.749446 -282.075128) (xy 435.749446 -282.595066) (xy 434.250846 -282.595066)
			)
		)
	)
	(zone
		(layer "In2.Cu")
		(hatch none 0.5)
		(connect_pads
			(clearance 0)
		)
		(min_thickness 0.25)
		(keepout
			(tracks not_allowed)
			(vias allowed)
			(pads allowed)
			(copperpour not_allowed)
			(footprints allowed)
		)
		(placement
			(enabled no)
			(sheetname "")
		)
		(fill
			(thermal_gap 0.5)
			(thermal_bridge_width 0.5)
			(island_removal_mode 0)
		)
		(polygon
			(pts
				(xy 426.706792 -266.775184) (xy 428.205392 -266.775184) (xy 428.205392 -267.295122) (xy 426.706792 -267.295122)
			)
		)
	)
	(zone
		(layer "In2.Cu")
		(hatch none 0.5)
		(connect_pads
			(clearance 0)
		)
		(min_thickness 0.25)
		(keepout
			(tracks allowed)
			(vias allowed)
			(pads allowed)
			(copperpour allowed)
			(footprints allowed)
		)
		(placement
			(enabled no)
			(sheetname "")
		)
		(fill
			(thermal_gap 0.5)
			(thermal_bridge_width 0.5)
			(island_removal_mode 0)
		)
		(polygon
			(pts
				(xy 271.530572 -349.93834) (xy 271.530572 -349.31604) (xy 272.081752 -349.31604) (xy 272.081752 -349.93834)
			)
		)
	)
	(zone
		(layer "In2.Cu")
		(hatch none 0.5)
		(connect_pads
			(clearance 0)
		)
		(min_thickness 0.25)
		(keepout
			(tracks allowed)
			(vias allowed)
			(pads allowed)
			(copperpour allowed)
			(footprints allowed)
		)
		(placement
			(enabled no)
			(sheetname "")
		)
		(fill
			(thermal_gap 0.5)
			(thermal_bridge_width 0.5)
			(island_removal_mode 0)
		)
		(polygon
			(pts
				(xy 408.592528 -165.996874) (xy 408.592528 -165.45052) (xy 409.144978 -165.45052) (xy 409.144978 -165.996874)
			)
		)
	)
	(zone
		(layer "In2.Cu")
		(hatch none 0.5)
		(connect_pads
			(clearance 0)
		)
		(min_thickness 0.25)
		(keepout
			(tracks not_allowed)
			(vias allowed)
			(pads allowed)
			(copperpour not_allowed)
			(footprints allowed)
		)
		(placement
			(enabled no)
			(sheetname "")
		)
		(fill
			(thermal_gap 0.5)
			(thermal_bridge_width 0.5)
			(island_removal_mode 0)
		)
		(polygon
			(pts
				(xy 430.80686 -290.575238) (xy 432.30546 -290.575238) (xy 432.30546 -291.095176) (xy 430.80686 -291.095176)
			)
		)
	)
	(zone
		(layer "In2.Cu")
		(hatch none 0.5)
		(connect_pads
			(clearance 0)
		)
		(min_thickness 0.25)
		(keepout
			(tracks not_allowed)
			(vias allowed)
			(pads allowed)
			(copperpour not_allowed)
			(footprints allowed)
		)
		(placement
			(enabled no)
			(sheetname "")
		)
		(fill
			(thermal_gap 0.5)
			(thermal_bridge_width 0.5)
			(island_removal_mode 0)
		)
		(polygon
			(pts
				(xy 306.618894 -206.425292) (xy 308.117494 -206.425292) (xy 308.117494 -206.94523) (xy 306.618894 -206.94523)
			)
		)
	)
	(zone
		(layer "In2.Cu")
		(hatch none 0.5)
		(connect_pads
			(clearance 0)
		)
		(min_thickness 0.25)
		(keepout
			(tracks not_allowed)
			(vias allowed)
			(pads allowed)
			(copperpour not_allowed)
			(footprints allowed)
		)
		(placement
			(enabled no)
			(sheetname "")
		)
		(fill
			(thermal_gap 0.5)
			(thermal_bridge_width 0.5)
			(island_removal_mode 0)
		)
		(polygon
			(pts
				(xy 186.310778 -224.275142) (xy 187.809378 -224.275142) (xy 187.809378 -224.79508) (xy 186.310778 -224.79508)
			)
		)
	)
	(zone
		(layer "In2.Cu")
		(hatch none 0.5)
		(connect_pads
			(clearance 0)
		)
		(min_thickness 0.25)
		(keepout
			(tracks not_allowed)
			(vias allowed)
			(pads allowed)
			(copperpour not_allowed)
			(footprints allowed)
		)
		(placement
			(enabled no)
			(sheetname "")
		)
		(fill
			(thermal_gap 0.5)
			(thermal_bridge_width 0.5)
			(island_removal_mode 0)
		)
		(polygon
			(pts
				(xy 272.342864 -201.325226) (xy 273.841464 -201.325226) (xy 273.841464 -201.845164) (xy 272.342864 -201.845164)
			)
		)
	)
	(zone
		(layer "In2.Cu")
		(hatch none 0.5)
		(connect_pads
			(clearance 0)
		)
		(min_thickness 0.25)
		(keepout
			(tracks not_allowed)
			(vias allowed)
			(pads allowed)
			(copperpour not_allowed)
			(footprints allowed)
		)
		(placement
			(enabled no)
			(sheetname "")
		)
		(fill
			(thermal_gap 0.5)
			(thermal_bridge_width 0.5)
			(island_removal_mode 0)
		)
		(polygon
			(pts
				(xy 279.886664 -295.675304) (xy 281.385264 -295.675304) (xy 281.385264 -296.195242) (xy 279.886664 -296.195242)
			)
		)
	)
	(zone
		(layer "In2.Cu")
		(hatch none 0.5)
		(connect_pads
			(clearance 0)
		)
		(min_thickness 0.25)
		(keepout
			(tracks not_allowed)
			(vias allowed)
			(pads allowed)
			(copperpour not_allowed)
			(footprints allowed)
		)
		(placement
			(enabled no)
			(sheetname "")
		)
		(fill
			(thermal_gap 0.5)
			(thermal_bridge_width 0.5)
			(island_removal_mode 0)
		)
		(polygon
			(pts
				(xy 415.718752 -228.525324) (xy 417.217352 -228.525324) (xy 417.217352 -229.045262) (xy 415.718752 -229.045262)
			)
		)
	)
	(zone
		(layer "In2.Cu")
		(hatch none 0.5)
		(connect_pads
			(clearance 0)
		)
		(min_thickness 0.25)
		(keepout
			(tracks not_allowed)
			(vias allowed)
			(pads allowed)
			(copperpour not_allowed)
			(footprints allowed)
		)
		(placement
			(enabled no)
			(sheetname "")
		)
		(fill
			(thermal_gap 0.5)
			(thermal_bridge_width 0.5)
			(island_removal_mode 0)
		)
		(polygon
			(pts
				(xy 426.706792 -199.625204) (xy 428.205392 -199.625204) (xy 428.205392 -200.145142) (xy 426.706792 -200.145142)
			)
		)
	)
	(zone
		(layer "In2.Cu")
		(hatch none 0.5)
		(connect_pads
			(clearance 0)
		)
		(min_thickness 0.25)
		(keepout
			(tracks not_allowed)
			(vias allowed)
			(pads allowed)
			(copperpour not_allowed)
			(footprints allowed)
		)
		(placement
			(enabled no)
			(sheetname "")
		)
		(fill
			(thermal_gap 0.5)
			(thermal_bridge_width 0.5)
			(island_removal_mode 0)
		)
		(polygon
			(pts
				(xy 190.410846 -269.325344) (xy 191.909446 -269.325344) (xy 191.909446 -269.845282) (xy 190.410846 -269.845282)
			)
		)
	)
	(zone
		(layer "In2.Cu")
		(hatch none 0.5)
		(connect_pads
			(clearance 0)
		)
		(min_thickness 0.25)
		(keepout
			(tracks not_allowed)
			(vias allowed)
			(pads allowed)
			(copperpour not_allowed)
			(footprints allowed)
		)
		(placement
			(enabled no)
			(sheetname "")
		)
		(fill
			(thermal_gap 0.5)
			(thermal_bridge_width 0.5)
			(island_removal_mode 0)
		)
		(polygon
			(pts
				(xy 430.80686 -285.475172) (xy 432.30546 -285.475172) (xy 432.30546 -285.99511) (xy 430.80686 -285.99511)
			)
		)
	)
	(zone
		(layer "In2.Cu")
		(hatch none 0.5)
		(connect_pads
			(clearance 0)
		)
		(min_thickness 0.25)
		(keepout
			(tracks not_allowed)
			(vias allowed)
			(pads allowed)
			(copperpour not_allowed)
			(footprints allowed)
		)
		(placement
			(enabled no)
			(sheetname "")
		)
		(fill
			(thermal_gap 0.5)
			(thermal_bridge_width 0.5)
			(island_removal_mode 0)
		)
		(polygon
			(pts
				(xy 419.162738 -293.125144) (xy 420.661338 -293.125144) (xy 420.661338 -293.645082) (xy 419.162738 -293.645082)
			)
		)
	)
	(zone
		(layer "In2.Cu")
		(hatch none 0.5)
		(connect_pads
			(clearance 0)
		)
		(min_thickness 0.25)
		(keepout
			(tracks not_allowed)
			(vias allowed)
			(pads allowed)
			(copperpour not_allowed)
			(footprints allowed)
		)
		(placement
			(enabled no)
			(sheetname "")
		)
		(fill
			(thermal_gap 0.5)
			(thermal_bridge_width 0.5)
			(island_removal_mode 0)
		)
		(polygon
			(pts
				(xy 40.34028 -426.813472)
				(arc
					(start 40.480488 -426.813472)
					(mid 40.55037 -426.784263)
					(end 40.57904 -426.714158)
				)
				(arc
					(start 40.57904 -426.412914)
					(mid 40.55037 -426.342809)
					(end 40.480488 -426.3136)
				)
				(xy 40.34028 -426.3136) (xy 40.34028 -426.373544)
				(arc
					(start 39.771066 -426.373544)
					(mid 39.734697 -426.330045)
					(end 39.680388 -426.3136)
				)
				(arc
					(start 39.420292 -426.3136)
					(mid 39.3659 -426.329919)
					(end 39.329614 -426.373544)
				)
				(xy 38.7604 -426.373544) (xy 38.7604 -426.3136)
				(arc
					(start 38.620192 -426.3136)
					(mid 38.55031 -426.342809)
					(end 38.52164 -426.412914)
				)
				(arc
					(start 38.52164 -426.714158)
					(mid 38.55031 -426.784263)
					(end 38.620192 -426.813472)
				)
				(xy 38.7604 -426.813472) (xy 38.7604 -426.753528)
				(arc
					(start 39.329614 -426.753528)
					(mid 39.365983 -426.797027)
					(end 39.420292 -426.813472)
				)
				(arc
					(start 39.680388 -426.813472)
					(mid 39.73478 -426.797153)
					(end 39.771066 -426.753528)
				)
				(xy 40.34028 -426.753528)
			)
		)
	)
	(zone
		(layer "In2.Cu")
		(hatch none 0.5)
		(connect_pads
			(clearance 0)
		)
		(min_thickness 0.25)
		(keepout
			(tracks not_allowed)
			(vias allowed)
			(pads allowed)
			(copperpour not_allowed)
			(footprints allowed)
		)
		(placement
			(enabled no)
			(sheetname "")
		)
		(fill
			(thermal_gap 0.5)
			(thermal_bridge_width 0.5)
			(island_removal_mode 0)
		)
		(polygon
			(pts
				(xy 167.778684 -315.225176) (xy 169.277284 -315.225176) (xy 169.277284 -315.745114) (xy 167.778684 -315.745114)
			)
		)
	)
	(zone
		(layer "In2.Cu")
		(hatch none 0.5)
		(connect_pads
			(clearance 0)
		)
		(min_thickness 0.25)
		(keepout
			(tracks not_allowed)
			(vias allowed)
			(pads allowed)
			(copperpour not_allowed)
			(footprints allowed)
		)
		(placement
			(enabled no)
			(sheetname "")
		)
		(fill
			(thermal_gap 0.5)
			(thermal_bridge_width 0.5)
			(island_removal_mode 0)
		)
		(polygon
			(pts
				(xy 306.618894 -248.925334) (xy 308.117494 -248.925334) (xy 308.117494 -249.445272) (xy 306.618894 -249.445272)
			)
		)
	)
	(zone
		(layer "In2.Cu")
		(hatch none 0.5)
		(connect_pads
			(clearance 0)
		)
		(min_thickness 0.25)
		(keepout
			(tracks not_allowed)
			(vias allowed)
			(pads allowed)
			(copperpour not_allowed)
			(footprints allowed)
		)
		(placement
			(enabled no)
			(sheetname "")
		)
		(fill
			(thermal_gap 0.5)
			(thermal_bridge_width 0.5)
			(island_removal_mode 0)
		)
		(polygon
			(pts
				(xy 36.046664 -313.525154) (xy 37.545264 -313.525154) (xy 37.545264 -314.045092) (xy 36.046664 -314.045092)
			)
		)
	)
	(zone
		(layer "In2.Cu")
		(hatch none 0.5)
		(connect_pads
			(clearance 0)
		)
		(min_thickness 0.25)
		(keepout
			(tracks not_allowed)
			(vias allowed)
			(pads allowed)
			(copperpour not_allowed)
			(footprints allowed)
		)
		(placement
			(enabled no)
			(sheetname "")
		)
		(fill
			(thermal_gap 0.5)
			(thermal_bridge_width 0.5)
			(island_removal_mode 0)
		)
		(polygon
			(pts
				(xy 299.07484 -225.12528) (xy 300.57344 -225.12528) (xy 300.57344 -225.645218) (xy 299.07484 -225.645218)
			)
		)
	)
	(zone
		(layer "In2.Cu")
		(hatch none 0.5)
		(connect_pads
			(clearance 0)
		)
		(min_thickness 0.25)
		(keepout
			(tracks not_allowed)
			(vias allowed)
			(pads allowed)
			(copperpour not_allowed)
			(footprints allowed)
		)
		(placement
			(enabled no)
			(sheetname "")
		)
		(fill
			(thermal_gap 0.5)
			(thermal_bridge_width 0.5)
			(island_removal_mode 0)
		)
		(polygon
			(pts
				(xy 54.578758 -199.625204) (xy 56.077358 -199.625204) (xy 56.077358 -200.145142) (xy 54.578758 -200.145142)
			)
		)
	)
	(zone
		(layer "In2.Cu")
		(hatch none 0.5)
		(connect_pads
			(clearance 0)
		)
		(min_thickness 0.25)
		(keepout
			(tracks not_allowed)
			(vias allowed)
			(pads allowed)
			(copperpour not_allowed)
			(footprints allowed)
		)
		(placement
			(enabled no)
			(sheetname "")
		)
		(fill
			(thermal_gap 0.5)
			(thermal_bridge_width 0.5)
			(island_removal_mode 0)
		)
		(polygon
			(pts
				(xy 31.946596 -244.675152) (xy 33.445196 -244.675152) (xy 33.445196 -245.19509) (xy 31.946596 -245.19509)
			)
		)
	)
	(zone
		(layer "In2.Cu")
		(hatch none 0.5)
		(connect_pads
			(clearance 0)
		)
		(min_thickness 0.25)
		(keepout
			(tracks not_allowed)
			(vias allowed)
			(pads allowed)
			(copperpour not_allowed)
			(footprints allowed)
		)
		(placement
			(enabled no)
			(sheetname "")
		)
		(fill
			(thermal_gap 0.5)
			(thermal_bridge_width 0.5)
			(island_removal_mode 0)
		)
		(polygon
			(pts
				(xy 171.22267 -238.725202) (xy 172.72127 -238.725202) (xy 172.72127 -239.24514) (xy 171.22267 -239.24514)
			)
		)
	)
	(zone
		(layer "In2.Cu")
		(hatch none 0.5)
		(connect_pads
			(clearance 0)
		)
		(min_thickness 0.25)
		(keepout
			(tracks not_allowed)
			(vias allowed)
			(pads allowed)
			(copperpour not_allowed)
			(footprints allowed)
		)
		(placement
			(enabled no)
			(sheetname "")
		)
		(fill
			(thermal_gap 0.5)
			(thermal_bridge_width 0.5)
			(island_removal_mode 0)
		)
		(polygon
			(pts
				(xy 197.954646 -276.125178) (xy 199.453246 -276.125178) (xy 199.453246 -276.645116) (xy 197.954646 -276.645116)
			)
		)
	)
	(zone
		(layer "In2.Cu")
		(hatch none 0.5)
		(connect_pads
			(clearance 0)
		)
		(min_thickness 0.25)
		(keepout
			(tracks not_allowed)
			(vias allowed)
			(pads allowed)
			(copperpour not_allowed)
			(footprints allowed)
		)
		(placement
			(enabled no)
			(sheetname "")
		)
		(fill
			(thermal_gap 0.5)
			(thermal_bridge_width 0.5)
			(island_removal_mode 0)
		)
		(polygon
			(pts
				(xy 411.618684 -282.075128) (xy 413.117284 -282.075128) (xy 413.117284 -282.595066) (xy 411.618684 -282.595066)
			)
		)
	)
	(zone
		(layer "In2.Cu")
		(hatch none 0.5)
		(connect_pads
			(clearance 0)
		)
		(min_thickness 0.25)
		(keepout
			(tracks not_allowed)
			(vias allowed)
			(pads allowed)
			(copperpour not_allowed)
			(footprints allowed)
		)
		(placement
			(enabled no)
			(sheetname "")
		)
		(fill
			(thermal_gap 0.5)
			(thermal_bridge_width 0.5)
			(island_removal_mode 0)
		)
		(polygon
			(pts
				(xy 51.134772 -223.425258) (xy 52.633372 -223.425258) (xy 52.633372 -223.945196) (xy 51.134772 -223.945196)
			)
		)
	)
	(zone
		(layer "In2.Cu")
		(hatch none 0.5)
		(connect_pads
			(clearance 0)
		)
		(min_thickness 0.25)
		(keepout
			(tracks not_allowed)
			(vias allowed)
			(pads allowed)
			(copperpour not_allowed)
			(footprints allowed)
		)
		(placement
			(enabled no)
			(sheetname "")
		)
		(fill
			(thermal_gap 0.5)
			(thermal_bridge_width 0.5)
			(island_removal_mode 0)
		)
		(polygon
			(pts
				(xy 47.034704 -211.525104) (xy 48.533304 -211.525104) (xy 48.533304 -212.045042) (xy 47.034704 -212.045042)
			)
		)
	)
	(zone
		(layer "In2.Cu")
		(hatch none 0.5)
		(connect_pads
			(clearance 0)
		)
		(min_thickness 0.25)
		(keepout
			(tracks not_allowed)
			(vias allowed)
			(pads allowed)
			(copperpour not_allowed)
			(footprints allowed)
		)
		(placement
			(enabled no)
			(sheetname "")
		)
		(fill
			(thermal_gap 0.5)
			(thermal_bridge_width 0.5)
			(island_removal_mode 0)
		)
		(polygon
			(pts
				(xy 430.80686 -248.925334) (xy 432.30546 -248.925334) (xy 432.30546 -249.445272) (xy 430.80686 -249.445272)
			)
		)
	)
	(zone
		(layer "In2.Cu")
		(hatch none 0.5)
		(connect_pads
			(clearance 0)
		)
		(min_thickness 0.25)
		(keepout
			(tracks not_allowed)
			(vias allowed)
			(pads allowed)
			(copperpour not_allowed)
			(footprints allowed)
		)
		(placement
			(enabled no)
			(sheetname "")
		)
		(fill
			(thermal_gap 0.5)
			(thermal_bridge_width 0.5)
			(island_removal_mode 0)
		)
		(polygon
			(pts
				(xy 291.530786 -265.9253) (xy 293.029386 -265.9253) (xy 293.029386 -266.445238) (xy 291.530786 -266.445238)
			)
		)
	)
	(zone
		(layer "In2.Cu")
		(hatch none 0.5)
		(connect_pads
			(clearance 0)
		)
		(min_thickness 0.25)
		(keepout
			(tracks not_allowed)
			(vias allowed)
			(pads allowed)
			(copperpour not_allowed)
			(footprints allowed)
		)
		(placement
			(enabled no)
			(sheetname "")
		)
		(fill
			(thermal_gap 0.5)
			(thermal_bridge_width 0.5)
			(island_removal_mode 0)
		)
		(polygon
			(pts
				(xy 167.778684 -264.225278) (xy 169.277284 -264.225278) (xy 169.277284 -264.745216) (xy 167.778684 -264.745216)
			)
		)
	)
	(zone
		(layer "In2.Cu")
		(hatch none 0.5)
		(connect_pads
			(clearance 0)
		)
		(min_thickness 0.25)
		(keepout
			(tracks not_allowed)
			(vias allowed)
			(pads allowed)
			(copperpour not_allowed)
			(footprints allowed)
		)
		(placement
			(enabled no)
			(sheetname "")
		)
		(fill
			(thermal_gap 0.5)
			(thermal_bridge_width 0.5)
			(island_removal_mode 0)
		)
		(polygon
			(pts
				(xy 31.946596 -308.425342) (xy 33.445196 -308.425342) (xy 33.445196 -308.94528) (xy 31.946596 -308.94528)
			)
		)
	)
	(zone
		(layer "In2.Cu")
		(hatch none 0.5)
		(connect_pads
			(clearance 0)
		)
		(min_thickness 0.25)
		(keepout
			(tracks not_allowed)
			(vias allowed)
			(pads allowed)
			(copperpour not_allowed)
			(footprints allowed)
		)
		(placement
			(enabled no)
			(sheetname "")
		)
		(fill
			(thermal_gap 0.5)
			(thermal_bridge_width 0.5)
			(island_removal_mode 0)
		)
		(polygon
			(pts
				(xy 167.778684 -292.27526) (xy 169.277284 -292.27526) (xy 169.277284 -292.795198) (xy 167.778684 -292.795198)
			)
		)
	)
	(zone
		(layer "In2.Cu")
		(hatch none 0.5)
		(connect_pads
			(clearance 0)
		)
		(min_thickness 0.25)
		(keepout
			(tracks not_allowed)
			(vias allowed)
			(pads allowed)
			(copperpour not_allowed)
			(footprints allowed)
		)
		(placement
			(enabled no)
			(sheetname "")
		)
		(fill
			(thermal_gap 0.5)
			(thermal_bridge_width 0.5)
			(island_removal_mode 0)
		)
		(polygon
			(pts
				(xy 287.430718 -222.57512) (xy 288.929318 -222.57512) (xy 288.929318 -223.095058) (xy 287.430718 -223.095058)
			)
		)
	)
	(zone
		(layer "In2.Cu")
		(hatch none 0.5)
		(connect_pads
			(clearance 0)
		)
		(min_thickness 0.25)
		(keepout
			(tracks not_allowed)
			(vias allowed)
			(pads allowed)
			(copperpour not_allowed)
			(footprints allowed)
		)
		(placement
			(enabled no)
			(sheetname "")
		)
		(fill
			(thermal_gap 0.5)
			(thermal_bridge_width 0.5)
			(island_removal_mode 0)
		)
		(polygon
			(pts
				(xy 438.350914 -201.325226) (xy 439.849514 -201.325226) (xy 439.849514 -201.845164) (xy 438.350914 -201.845164)
			)
		)
	)
	(zone
		(layer "In2.Cu")
		(hatch none 0.5)
		(connect_pads
			(clearance 0)
		)
		(min_thickness 0.25)
		(keepout
			(tracks not_allowed)
			(vias allowed)
			(pads allowed)
			(copperpour not_allowed)
			(footprints allowed)
		)
		(placement
			(enabled no)
			(sheetname "")
		)
		(fill
			(thermal_gap 0.5)
			(thermal_bridge_width 0.5)
			(island_removal_mode 0)
		)
		(polygon
			(pts
				(xy 294.974772 -202.17511) (xy 296.473372 -202.17511) (xy 296.473372 -202.695048) (xy 294.974772 -202.695048)
			)
		)
	)
	(zone
		(layer "In2.Cu")
		(hatch none 0.5)
		(connect_pads
			(clearance 0)
		)
		(min_thickness 0.25)
		(keepout
			(tracks not_allowed)
			(vias allowed)
			(pads allowed)
			(copperpour not_allowed)
			(footprints allowed)
		)
		(placement
			(enabled no)
			(sheetname "")
		)
		(fill
			(thermal_gap 0.5)
			(thermal_bridge_width 0.5)
			(island_removal_mode 0)
		)
		(polygon
			(pts
				(xy 415.718752 -232.775252) (xy 417.217352 -232.775252) (xy 417.217352 -233.29519) (xy 415.718752 -233.29519)
			)
		)
	)
	(zone
		(layer "In2.Cu")
		(hatch none 0.5)
		(connect_pads
			(clearance 0)
		)
		(min_thickness 0.25)
		(keepout
			(tracks not_allowed)
			(vias allowed)
			(pads allowed)
			(copperpour not_allowed)
			(footprints allowed)
		)
		(placement
			(enabled no)
			(sheetname "")
		)
		(fill
			(thermal_gap 0.5)
			(thermal_bridge_width 0.5)
			(island_removal_mode 0)
		)
		(polygon
			(pts
				(xy 186.310778 -289.725354) (xy 187.809378 -289.725354) (xy 187.809378 -290.245292) (xy 186.310778 -290.245292)
			)
		)
	)
	(zone
		(layer "In2.Cu")
		(hatch none 0.5)
		(connect_pads
			(clearance 0)
		)
		(min_thickness 0.25)
		(keepout
			(tracks not_allowed)
			(vias allowed)
			(pads allowed)
			(copperpour not_allowed)
			(footprints allowed)
		)
		(placement
			(enabled no)
			(sheetname "")
		)
		(fill
			(thermal_gap 0.5)
			(thermal_bridge_width 0.5)
			(island_removal_mode 0)
		)
		(polygon
			(pts
				(xy 171.22267 -313.525154) (xy 172.72127 -313.525154) (xy 172.72127 -314.045092) (xy 171.22267 -314.045092)
			)
		)
	)
	(zone
		(layer "In2.Cu")
		(hatch none 0.5)
		(connect_pads
			(clearance 0)
		)
		(min_thickness 0.25)
		(keepout
			(tracks not_allowed)
			(vias allowed)
			(pads allowed)
			(copperpour not_allowed)
			(footprints allowed)
		)
		(placement
			(enabled no)
			(sheetname "")
		)
		(fill
			(thermal_gap 0.5)
			(thermal_bridge_width 0.5)
			(island_removal_mode 0)
		)
		(polygon
			(pts
				(xy 291.530786 -236.175296) (xy 293.029386 -236.175296) (xy 293.029386 -236.695234) (xy 291.530786 -236.695234)
			)
		)
	)
	(zone
		(layer "In2.Cu")
		(hatch none 0.5)
		(connect_pads
			(clearance 0)
		)
		(min_thickness 0.25)
		(keepout
			(tracks not_allowed)
			(vias allowed)
			(pads allowed)
			(copperpour not_allowed)
			(footprints allowed)
		)
		(placement
			(enabled no)
			(sheetname "")
		)
		(fill
			(thermal_gap 0.5)
			(thermal_bridge_width 0.5)
			(island_removal_mode 0)
		)
		(polygon
			(pts
				(xy 419.162738 -199.625204) (xy 420.661338 -199.625204) (xy 420.661338 -200.145142) (xy 419.162738 -200.145142)
			)
		)
	)
	(zone
		(layer "In2.Cu")
		(hatch none 0.5)
		(connect_pads
			(clearance 0)
		)
		(min_thickness 0.25)
		(keepout
			(tracks allowed)
			(vias allowed)
			(pads allowed)
			(copperpour allowed)
			(footprints allowed)
		)
		(placement
			(enabled no)
			(sheetname "")
		)
		(fill
			(thermal_gap 0.5)
			(thermal_bridge_width 0.5)
			(island_removal_mode 0)
		)
		(polygon
			(pts
				(xy 43.430698 -350.385888) (xy 43.430698 -351.310448) (xy 43.141138 -351.310448) (xy 43.141138 -350.385888)
			)
		)
	)
	(zone
		(layer "In2.Cu")
		(hatch none 0.5)
		(connect_pads
			(clearance 0)
		)
		(min_thickness 0.25)
		(keepout
			(tracks not_allowed)
			(vias allowed)
			(pads allowed)
			(copperpour not_allowed)
			(footprints allowed)
		)
		(placement
			(enabled no)
			(sheetname "")
		)
		(fill
			(thermal_gap 0.5)
			(thermal_bridge_width 0.5)
			(island_removal_mode 0)
		)
		(polygon
			(pts
				(xy 438.350914 -293.975282) (xy 439.849514 -293.975282) (xy 439.849514 -294.49522) (xy 438.350914 -294.49522)
			)
		)
	)
	(zone
		(layer "In2.Cu")
		(hatch none 0.5)
		(connect_pads
			(clearance 0)
		)
		(min_thickness 0.25)
		(keepout
			(tracks not_allowed)
			(vias allowed)
			(pads allowed)
			(copperpour not_allowed)
			(footprints allowed)
		)
		(placement
			(enabled no)
			(sheetname "")
		)
		(fill
			(thermal_gap 0.5)
			(thermal_bridge_width 0.5)
			(island_removal_mode 0)
		)
		(polygon
			(pts
				(xy 411.618684 -276.125178) (xy 413.117284 -276.125178) (xy 413.117284 -276.645116) (xy 411.618684 -276.645116)
			)
		)
	)
	(zone
		(layer "In2.Cu")
		(hatch none 0.5)
		(connect_pads
			(clearance 0)
		)
		(min_thickness 0.25)
		(keepout
			(tracks not_allowed)
			(vias allowed)
			(pads allowed)
			(copperpour not_allowed)
			(footprints allowed)
		)
		(placement
			(enabled no)
			(sheetname "")
		)
		(fill
			(thermal_gap 0.5)
			(thermal_bridge_width 0.5)
			(island_removal_mode 0)
		)
		(polygon
			(pts
				(xy 186.310778 -261.675118) (xy 187.809378 -261.675118) (xy 187.809378 -262.195056) (xy 186.310778 -262.195056)
			)
		)
	)
	(zone
		(layer "In2.Cu")
		(hatch none 0.5)
		(connect_pads
			(clearance 0)
		)
		(min_thickness 0.25)
		(keepout
			(tracks not_allowed)
			(vias allowed)
			(pads allowed)
			(copperpour not_allowed)
			(footprints allowed)
		)
		(placement
			(enabled no)
			(sheetname "")
		)
		(fill
			(thermal_gap 0.5)
			(thermal_bridge_width 0.5)
			(island_removal_mode 0)
		)
		(polygon
			(pts
				(xy 434.250846 -233.625136) (xy 435.749446 -233.625136) (xy 435.749446 -234.145074) (xy 434.250846 -234.145074)
			)
		)
	)
	(zone
		(layer "In2.Cu")
		(hatch none 0.5)
		(connect_pads
			(clearance 0)
		)
		(min_thickness 0.25)
		(keepout
			(tracks not_allowed)
			(vias allowed)
			(pads allowed)
			(copperpour not_allowed)
			(footprints allowed)
		)
		(placement
			(enabled no)
			(sheetname "")
		)
		(fill
			(thermal_gap 0.5)
			(thermal_bridge_width 0.5)
			(island_removal_mode 0)
		)
		(polygon
			(pts
				(xy 272.342864 -268.475206) (xy 273.841464 -268.475206) (xy 273.841464 -268.995144) (xy 272.342864 -268.995144)
			)
		)
	)
	(zone
		(layer "In2.Cu")
		(hatch none 0.5)
		(connect_pads
			(clearance 0)
		)
		(min_thickness 0.25)
		(keepout
			(tracks not_allowed)
			(vias allowed)
			(pads allowed)
			(copperpour not_allowed)
			(footprints allowed)
		)
		(placement
			(enabled no)
			(sheetname "")
		)
		(fill
			(thermal_gap 0.5)
			(thermal_bridge_width 0.5)
			(island_removal_mode 0)
		)
		(polygon
			(pts
				(xy 449.3387 -282.075128) (xy 450.8373 -282.075128) (xy 450.8373 -282.595066) (xy 449.3387 -282.595066)
			)
		)
	)
	(zone
		(layer "In2.Cu")
		(hatch none 0.5)
		(connect_pads
			(clearance 0)
		)
		(min_thickness 0.25)
		(keepout
			(tracks not_allowed)
			(vias allowed)
			(pads allowed)
			(copperpour not_allowed)
			(footprints allowed)
		)
		(placement
			(enabled no)
			(sheetname "")
		)
		(fill
			(thermal_gap 0.5)
			(thermal_bridge_width 0.5)
			(island_removal_mode 0)
		)
		(polygon
			(pts
				(xy 190.410846 -248.925334) (xy 191.909446 -248.925334) (xy 191.909446 -249.445272) (xy 190.410846 -249.445272)
			)
		)
	)
	(zone
		(layer "In2.Cu")
		(hatch none 0.5)
		(connect_pads
			(clearance 0)
		)
		(min_thickness 0.25)
		(keepout
			(tracks not_allowed)
			(vias allowed)
			(pads allowed)
			(copperpour not_allowed)
			(footprints allowed)
		)
		(placement
			(enabled no)
			(sheetname "")
		)
		(fill
			(thermal_gap 0.5)
			(thermal_bridge_width 0.5)
			(island_removal_mode 0)
		)
		(polygon
			(pts
				(xy 186.310778 -253.175262) (xy 187.809378 -253.175262) (xy 187.809378 -253.6952) (xy 186.310778 -253.6952)
			)
		)
	)
	(zone
		(layer "In2.Cu")
		(hatch none 0.5)
		(connect_pads
			(clearance 0)
		)
		(min_thickness 0.25)
		(keepout
			(tracks not_allowed)
			(vias allowed)
			(pads allowed)
			(copperpour not_allowed)
			(footprints allowed)
		)
		(placement
			(enabled no)
			(sheetname "")
		)
		(fill
			(thermal_gap 0.5)
			(thermal_bridge_width 0.5)
			(island_removal_mode 0)
		)
		(polygon
			(pts
				(xy 272.342864 -237.02518) (xy 273.841464 -237.02518) (xy 273.841464 -237.545118) (xy 272.342864 -237.545118)
			)
		)
	)
	(zone
		(layer "In2.Cu")
		(hatch none 0.5)
		(connect_pads
			(clearance 0)
		)
		(min_thickness 0.25)
		(keepout
			(tracks not_allowed)
			(vias allowed)
			(pads allowed)
			(copperpour not_allowed)
			(footprints allowed)
		)
		(placement
			(enabled no)
			(sheetname "")
		)
		(fill
			(thermal_gap 0.5)
			(thermal_bridge_width 0.5)
			(island_removal_mode 0)
		)
		(polygon
			(pts
				(xy 28.50261 -262.525256) (xy 30.00121 -262.525256) (xy 30.00121 -263.045194) (xy 28.50261 -263.045194)
			)
		)
	)
	(zone
		(layer "In2.Cu")
		(hatch none 0.5)
		(connect_pads
			(clearance 0)
		)
		(min_thickness 0.25)
		(keepout
			(tracks not_allowed)
			(vias allowed)
			(pads allowed)
			(copperpour not_allowed)
			(footprints allowed)
		)
		(placement
			(enabled no)
			(sheetname "")
		)
		(fill
			(thermal_gap 0.5)
			(thermal_bridge_width 0.5)
			(island_removal_mode 0)
		)
		(polygon
			(pts
				(xy 167.778684 -310.975248) (xy 169.277284 -310.975248) (xy 169.277284 -311.495186) (xy 167.778684 -311.495186)
			)
		)
	)
	(zone
		(layer "In2.Cu")
		(hatch none 0.5)
		(connect_pads
			(clearance 0)
		)
		(min_thickness 0.25)
		(keepout
			(tracks not_allowed)
			(vias allowed)
			(pads allowed)
			(copperpour not_allowed)
			(footprints allowed)
		)
		(placement
			(enabled no)
			(sheetname "")
		)
		(fill
			(thermal_gap 0.5)
			(thermal_bridge_width 0.5)
			(island_removal_mode 0)
		)
		(polygon
			(pts
				(xy 171.22267 -211.525104) (xy 172.72127 -211.525104) (xy 172.72127 -212.045042) (xy 171.22267 -212.045042)
			)
		)
	)
	(zone
		(layer "In2.Cu")
		(hatch none 0.5)
		(connect_pads
			(clearance 0)
		)
		(min_thickness 0.25)
		(keepout
			(tracks not_allowed)
			(vias allowed)
			(pads allowed)
			(copperpour not_allowed)
			(footprints allowed)
		)
		(placement
			(enabled no)
			(sheetname "")
		)
		(fill
			(thermal_gap 0.5)
			(thermal_bridge_width 0.5)
			(island_removal_mode 0)
		)
		(polygon
			(pts
				(arc
					(start 340.819994 -379.360684)
					(mid 340.839918 -379.36992)
					(end 340.86165 -379.37313)
				)
				(arc
					(start 341.056214 -379.37313)
					(mid 341.110096 -379.350812)
					(end 341.132414 -379.29693)
				)
				(arc
					(start 341.132414 -378.61113)
					(mid 341.110096 -378.557248)
					(end 341.056214 -378.53493)
				)
				(arc
					(start 340.86165 -378.53493)
					(mid 340.839906 -378.538098)
					(end 340.819994 -378.547376)
				)
				(arc
					(start 340.52383 -378.740162)
					(mid 340.482146 -378.752384)
					(end 340.440518 -378.739908)
				)
				(arc
					(start 340.146894 -378.547376)
					(mid 340.12697 -378.53814)
					(end 340.105238 -378.53493)
				)
				(arc
					(start 339.910674 -378.53493)
					(mid 339.856792 -378.557248)
					(end 339.834474 -378.61113)
				)
				(arc
					(start 339.834474 -379.29693)
					(mid 339.856792 -379.350812)
					(end 339.910674 -379.37313)
				)
				(arc
					(start 340.106508 -379.37313)
					(mid 340.128252 -379.369962)
					(end 340.148164 -379.360684)
				)
				(arc
					(start 340.441788 -379.168152)
					(mid 340.483444 -379.15575)
					(end 340.5251 -379.168152)
				)
			)
		)
	)
	(zone
		(layer "In2.Cu")
		(hatch none 0.5)
		(connect_pads
			(clearance 0)
		)
		(min_thickness 0.25)
		(keepout
			(tracks not_allowed)
			(vias allowed)
			(pads allowed)
			(copperpour not_allowed)
			(footprints allowed)
		)
		(placement
			(enabled no)
			(sheetname "")
		)
		(fill
			(thermal_gap 0.5)
			(thermal_bridge_width 0.5)
			(island_removal_mode 0)
		)
		(polygon
			(pts
				(xy 272.342864 -288.025332) (xy 273.841464 -288.025332) (xy 273.841464 -288.54527) (xy 272.342864 -288.54527)
			)
		)
	)
	(zone
		(layer "In2.Cu")
		(hatch none 0.5)
		(connect_pads
			(clearance 0)
		)
		(min_thickness 0.25)
		(keepout
			(tracks not_allowed)
			(vias allowed)
			(pads allowed)
			(copperpour not_allowed)
			(footprints allowed)
		)
		(placement
			(enabled no)
			(sheetname "")
		)
		(fill
			(thermal_gap 0.5)
			(thermal_bridge_width 0.5)
			(island_removal_mode 0)
		)
		(polygon
			(pts
				(xy 415.718752 -215.775286) (xy 417.217352 -215.775286) (xy 417.217352 -216.295224) (xy 415.718752 -216.295224)
			)
		)
	)
	(zone
		(layer "In2.Cu")
		(hatch none 0.5)
		(connect_pads
			(clearance 0)
		)
		(min_thickness 0.25)
		(keepout
			(tracks not_allowed)
			(vias allowed)
			(pads allowed)
			(copperpour not_allowed)
			(footprints allowed)
		)
		(placement
			(enabled no)
			(sheetname "")
		)
		(fill
			(thermal_gap 0.5)
			(thermal_bridge_width 0.5)
			(island_removal_mode 0)
		)
		(polygon
			(pts
				(xy 58.678826 -276.125178) (xy 60.177426 -276.125178) (xy 60.177426 -276.645116) (xy 58.678826 -276.645116)
			)
		)
	)
	(zone
		(layer "In2.Cu")
		(hatch none 0.5)
		(connect_pads
			(clearance 0)
		)
		(min_thickness 0.25)
		(keepout
			(tracks not_allowed)
			(vias allowed)
			(pads allowed)
			(copperpour not_allowed)
			(footprints allowed)
		)
		(placement
			(enabled no)
			(sheetname "")
		)
		(fill
			(thermal_gap 0.5)
			(thermal_bridge_width 0.5)
			(island_removal_mode 0)
		)
		(polygon
			(pts
				(xy 415.718752 -219.17533) (xy 417.217352 -219.17533) (xy 417.217352 -219.695268) (xy 415.718752 -219.695268)
			)
		)
	)
	(zone
		(layer "In2.Cu")
		(hatch none 0.5)
		(connect_pads
			(clearance 0)
		)
		(min_thickness 0.25)
		(keepout
			(tracks not_allowed)
			(vias allowed)
			(pads allowed)
			(copperpour not_allowed)
			(footprints allowed)
		)
		(placement
			(enabled no)
			(sheetname "")
		)
		(fill
			(thermal_gap 0.5)
			(thermal_bridge_width 0.5)
			(island_removal_mode 0)
		)
		(polygon
			(pts
				(xy 193.854578 -214.925148) (xy 195.353178 -214.925148) (xy 195.353178 -215.445086) (xy 193.854578 -215.445086)
			)
		)
	)
	(zone
		(layer "In2.Cu")
		(hatch none 0.5)
		(connect_pads
			(clearance 0)
		)
		(min_thickness 0.25)
		(keepout
			(tracks not_allowed)
			(vias allowed)
			(pads allowed)
			(copperpour not_allowed)
			(footprints allowed)
		)
		(placement
			(enabled no)
			(sheetname "")
		)
		(fill
			(thermal_gap 0.5)
			(thermal_bridge_width 0.5)
			(island_removal_mode 0)
		)
		(polygon
			(pts
				(xy 36.046664 -290.575238) (xy 37.545264 -290.575238) (xy 37.545264 -291.095176) (xy 36.046664 -291.095176)
			)
		)
	)
	(zone
		(layer "In2.Cu")
		(hatch none 0.5)
		(connect_pads
			(clearance 0)
		)
		(min_thickness 0.25)
		(keepout
			(tracks not_allowed)
			(vias allowed)
			(pads allowed)
			(copperpour not_allowed)
			(footprints allowed)
		)
		(placement
			(enabled no)
			(sheetname "")
		)
		(fill
			(thermal_gap 0.5)
			(thermal_bridge_width 0.5)
			(island_removal_mode 0)
		)
		(polygon
			(pts
				(xy 276.442932 -298.22521) (xy 277.941532 -298.22521) (xy 277.941532 -298.745148) (xy 276.442932 -298.745148)
			)
		)
	)
	(zone
		(layer "In2.Cu")
		(hatch none 0.5)
		(connect_pads
			(clearance 0)
		)
		(min_thickness 0.25)
		(keepout
			(tracks not_allowed)
			(vias allowed)
			(pads allowed)
			(copperpour not_allowed)
			(footprints allowed)
		)
		(placement
			(enabled no)
			(sheetname "")
		)
		(fill
			(thermal_gap 0.5)
			(thermal_bridge_width 0.5)
			(island_removal_mode 0)
		)
		(polygon
			(pts
				(xy 419.162738 -310.12511) (xy 420.661338 -310.12511) (xy 420.661338 -310.645048) (xy 419.162738 -310.645048)
			)
		)
	)
	(zone
		(layer "In2.Cu")
		(hatch none 0.5)
		(connect_pads
			(clearance 0)
		)
		(min_thickness 0.25)
		(keepout
			(tracks not_allowed)
			(vias allowed)
			(pads allowed)
			(copperpour not_allowed)
			(footprints allowed)
		)
		(placement
			(enabled no)
			(sheetname "")
		)
		(fill
			(thermal_gap 0.5)
			(thermal_bridge_width 0.5)
			(island_removal_mode 0)
		)
		(polygon
			(pts
				(xy 201.398632 -253.175262) (xy 202.897232 -253.175262) (xy 202.897232 -253.6952) (xy 201.398632 -253.6952)
			)
		)
	)
	(zone
		(layer "In2.Cu")
		(hatch none 0.5)
		(connect_pads
			(clearance 0)
		)
		(min_thickness 0.25)
		(keepout
			(tracks not_allowed)
			(vias allowed)
			(pads allowed)
			(copperpour not_allowed)
			(footprints allowed)
		)
		(placement
			(enabled no)
			(sheetname "")
		)
		(fill
			(thermal_gap 0.5)
			(thermal_bridge_width 0.5)
			(island_removal_mode 0)
		)
		(polygon
			(pts
				(xy 423.262806 -260.825234) (xy 424.761406 -260.825234) (xy 424.761406 -261.345172) (xy 423.262806 -261.345172)
			)
		)
	)
	(zone
		(layer "In2.Cu")
		(hatch none 0.5)
		(connect_pads
			(clearance 0)
		)
		(min_thickness 0.25)
		(keepout
			(tracks not_allowed)
			(vias allowed)
			(pads allowed)
			(copperpour not_allowed)
			(footprints allowed)
		)
		(placement
			(enabled no)
			(sheetname "")
		)
		(fill
			(thermal_gap 0.5)
			(thermal_bridge_width 0.5)
			(island_removal_mode 0)
		)
		(polygon
			(pts
				(xy 171.22267 -231.925114) (xy 172.72127 -231.925114) (xy 172.72127 -232.445052) (xy 171.22267 -232.445052)
			)
		)
	)
	(zone
		(layer "In2.Cu")
		(hatch none 0.5)
		(connect_pads
			(clearance 0)
		)
		(min_thickness 0.25)
		(keepout
			(tracks not_allowed)
			(vias allowed)
			(pads allowed)
			(copperpour not_allowed)
			(footprints allowed)
		)
		(placement
			(enabled no)
			(sheetname "")
		)
		(fill
			(thermal_gap 0.5)
			(thermal_bridge_width 0.5)
			(island_removal_mode 0)
		)
		(polygon
			(pts
				(xy 453.438768 -223.425258) (xy 454.937368 -223.425258) (xy 454.937368 -223.945196) (xy 453.438768 -223.945196)
			)
		)
	)
	(zone
		(layer "In2.Cu")
		(hatch none 0.5)
		(connect_pads
			(clearance 0)
		)
		(min_thickness 0.25)
		(keepout
			(tracks not_allowed)
			(vias allowed)
			(pads allowed)
			(copperpour not_allowed)
			(footprints allowed)
		)
		(placement
			(enabled no)
			(sheetname "")
		)
		(fill
			(thermal_gap 0.5)
			(thermal_bridge_width 0.5)
			(island_removal_mode 0)
		)
		(polygon
			(pts
				(xy 186.310778 -282.075128) (xy 187.809378 -282.075128) (xy 187.809378 -282.595066) (xy 186.310778 -282.595066)
			)
		)
	)
	(zone
		(layer "In2.Cu")
		(hatch none 0.5)
		(connect_pads
			(clearance 0)
		)
		(min_thickness 0.25)
		(keepout
			(tracks not_allowed)
			(vias allowed)
			(pads allowed)
			(copperpour not_allowed)
			(footprints allowed)
		)
		(placement
			(enabled no)
			(sheetname "")
		)
		(fill
			(thermal_gap 0.5)
			(thermal_bridge_width 0.5)
			(island_removal_mode 0)
		)
		(polygon
			(pts
				(xy 167.778684 -237.875318) (xy 169.277284 -237.875318) (xy 169.277284 -238.395256) (xy 167.778684 -238.395256)
			)
		)
	)
	(zone
		(layer "In2.Cu")
		(hatch none 0.5)
		(connect_pads
			(clearance 0)
		)
		(min_thickness 0.25)
		(keepout
			(tracks not_allowed)
			(vias allowed)
			(pads allowed)
			(copperpour not_allowed)
			(footprints allowed)
		)
		(placement
			(enabled no)
			(sheetname "")
		)
		(fill
			(thermal_gap 0.5)
			(thermal_bridge_width 0.5)
			(island_removal_mode 0)
		)
		(polygon
			(pts
				(xy 47.034704 -288.025332) (xy 48.533304 -288.025332) (xy 48.533304 -288.54527) (xy 47.034704 -288.54527)
			)
		)
	)
	(zone
		(layer "In2.Cu")
		(hatch none 0.5)
		(connect_pads
			(clearance 0)
		)
		(min_thickness 0.25)
		(keepout
			(tracks not_allowed)
			(vias allowed)
			(pads allowed)
			(copperpour not_allowed)
			(footprints allowed)
		)
		(placement
			(enabled no)
			(sheetname "")
		)
		(fill
			(thermal_gap 0.5)
			(thermal_bridge_width 0.5)
			(island_removal_mode 0)
		)
		(polygon
			(pts
				(xy 291.530786 -228.525324) (xy 293.029386 -228.525324) (xy 293.029386 -229.045262) (xy 291.530786 -229.045262)
			)
		)
	)
	(zone
		(layer "In2.Cu")
		(hatch none 0.5)
		(connect_pads
			(clearance 0)
		)
		(min_thickness 0.25)
		(keepout
			(tracks not_allowed)
			(vias allowed)
			(pads allowed)
			(copperpour not_allowed)
			(footprints allowed)
		)
		(placement
			(enabled no)
			(sheetname "")
		)
		(fill
			(thermal_gap 0.5)
			(thermal_bridge_width 0.5)
			(island_removal_mode 0)
		)
		(polygon
			(pts
				(xy 54.578758 -306.72532) (xy 56.077358 -306.72532) (xy 56.077358 -307.245258) (xy 54.578758 -307.245258)
			)
		)
	)
	(zone
		(layer "In2.Cu")
		(hatch none 0.5)
		(connect_pads
			(clearance 0)
		)
		(min_thickness 0.25)
		(keepout
			(tracks not_allowed)
			(vias allowed)
			(pads allowed)
			(copperpour not_allowed)
			(footprints allowed)
		)
		(placement
			(enabled no)
			(sheetname "")
		)
		(fill
			(thermal_gap 0.5)
			(thermal_bridge_width 0.5)
			(island_removal_mode 0)
		)
		(polygon
			(pts
				(xy 171.22267 -283.77515) (xy 172.72127 -283.77515) (xy 172.72127 -284.295088) (xy 171.22267 -284.295088)
			)
		)
	)
	(zone
		(layer "In2.Cu")
		(hatch none 0.5)
		(connect_pads
			(clearance 0)
		)
		(min_thickness 0.25)
		(keepout
			(tracks allowed)
			(vias allowed)
			(pads allowed)
			(copperpour allowed)
			(footprints allowed)
		)
		(placement
			(enabled no)
			(sheetname "")
		)
		(fill
			(thermal_gap 0.5)
			(thermal_bridge_width 0.5)
			(island_removal_mode 0)
		)
		(polygon
			(pts
				(xy 25.597612 -349.943166) (xy 25.597612 -349.320866) (xy 26.148792 -349.320866) (xy 26.148792 -349.943166)
			)
		)
	)
	(zone
		(layer "In2.Cu")
		(hatch none 0.5)
		(connect_pads
			(clearance 0)
		)
		(min_thickness 0.25)
		(keepout
			(tracks not_allowed)
			(vias allowed)
			(pads allowed)
			(copperpour not_allowed)
			(footprints allowed)
		)
		(placement
			(enabled no)
			(sheetname "")
		)
		(fill
			(thermal_gap 0.5)
			(thermal_bridge_width 0.5)
			(island_removal_mode 0)
		)
		(polygon
			(pts
				(xy 411.618684 -280.375106) (xy 413.117284 -280.375106) (xy 413.117284 -280.895044) (xy 411.618684 -280.895044)
			)
		)
	)
	(zone
		(layer "In2.Cu")
		(hatch none 0.5)
		(connect_pads
			(clearance 0)
		)
		(min_thickness 0.25)
		(keepout
			(tracks not_allowed)
			(vias allowed)
			(pads allowed)
			(copperpour not_allowed)
			(footprints allowed)
		)
		(placement
			(enabled no)
			(sheetname "")
		)
		(fill
			(thermal_gap 0.5)
			(thermal_bridge_width 0.5)
			(island_removal_mode 0)
		)
		(polygon
			(pts
				(xy 51.134772 -221.725236) (xy 52.633372 -221.725236) (xy 52.633372 -222.245174) (xy 51.134772 -222.245174)
			)
		)
	)
	(zone
		(layer "In2.Cu")
		(hatch none 0.5)
		(connect_pads
			(clearance 0)
		)
		(min_thickness 0.25)
		(keepout
			(tracks not_allowed)
			(vias allowed)
			(pads allowed)
			(copperpour not_allowed)
			(footprints allowed)
		)
		(placement
			(enabled no)
			(sheetname "")
		)
		(fill
			(thermal_gap 0.5)
			(thermal_bridge_width 0.5)
			(island_removal_mode 0)
		)
		(polygon
			(pts
				(xy 441.7949 -316.075314) (xy 443.2935 -316.075314) (xy 443.2935 -316.595252) (xy 441.7949 -316.595252)
			)
		)
	)
	(zone
		(layer "In2.Cu")
		(hatch none 0.5)
		(connect_pads
			(clearance 0)
		)
		(min_thickness 0.25)
		(keepout
			(tracks not_allowed)
			(vias allowed)
			(pads allowed)
			(copperpour not_allowed)
			(footprints allowed)
		)
		(placement
			(enabled no)
			(sheetname "")
		)
		(fill
			(thermal_gap 0.5)
			(thermal_bridge_width 0.5)
			(island_removal_mode 0)
		)
		(polygon
			(pts
				(xy 36.046664 -310.975248) (xy 37.545264 -310.975248) (xy 37.545264 -311.495186) (xy 36.046664 -311.495186)
			)
		)
	)
	(zone
		(layer "In2.Cu")
		(hatch none 0.5)
		(connect_pads
			(clearance 0)
		)
		(min_thickness 0.25)
		(keepout
			(tracks not_allowed)
			(vias allowed)
			(pads allowed)
			(copperpour not_allowed)
			(footprints allowed)
		)
		(placement
			(enabled no)
			(sheetname "")
		)
		(fill
			(thermal_gap 0.5)
			(thermal_bridge_width 0.5)
			(island_removal_mode 0)
		)
		(polygon
			(pts
				(xy 423.262806 -212.375242) (xy 424.761406 -212.375242) (xy 424.761406 -212.89518) (xy 423.262806 -212.89518)
			)
		)
	)
	(zone
		(layer "In2.Cu")
		(hatch none 0.5)
		(connect_pads
			(clearance 0)
		)
		(min_thickness 0.25)
		(keepout
			(tracks not_allowed)
			(vias allowed)
			(pads allowed)
			(copperpour not_allowed)
			(footprints allowed)
		)
		(placement
			(enabled no)
			(sheetname "")
		)
		(fill
			(thermal_gap 0.5)
			(thermal_bridge_width 0.5)
			(island_removal_mode 0)
		)
		(polygon
			(pts
				(xy 163.678616 -233.625136) (xy 165.177216 -233.625136) (xy 165.177216 -234.145074) (xy 163.678616 -234.145074)
			)
		)
	)
	(zone
		(layer "In2.Cu")
		(hatch none 0.5)
		(connect_pads
			(clearance 0)
		)
		(min_thickness 0.25)
		(keepout
			(tracks not_allowed)
			(vias allowed)
			(pads allowed)
			(copperpour not_allowed)
			(footprints allowed)
		)
		(placement
			(enabled no)
			(sheetname "")
		)
		(fill
			(thermal_gap 0.5)
			(thermal_bridge_width 0.5)
			(island_removal_mode 0)
		)
		(polygon
			(pts
				(xy 449.3387 -235.325158) (xy 450.8373 -235.325158) (xy 450.8373 -235.845096) (xy 449.3387 -235.845096)
			)
		)
	)
	(zone
		(layer "In2.Cu")
		(hatch none 0.5)
		(connect_pads
			(clearance 0)
		)
		(min_thickness 0.25)
		(keepout
			(tracks not_allowed)
			(vias allowed)
			(pads allowed)
			(copperpour not_allowed)
			(footprints allowed)
		)
		(placement
			(enabled no)
			(sheetname "")
		)
		(fill
			(thermal_gap 0.5)
			(thermal_bridge_width 0.5)
			(island_removal_mode 0)
		)
		(polygon
			(pts
				(xy 299.07484 -250.625102) (xy 300.57344 -250.625102) (xy 300.57344 -251.14504) (xy 299.07484 -251.14504)
			)
		)
	)
	(zone
		(layer "In2.Cu")
		(hatch none 0.5)
		(connect_pads
			(clearance 0)
		)
		(min_thickness 0.25)
		(keepout
			(tracks not_allowed)
			(vias allowed)
			(pads allowed)
			(copperpour not_allowed)
			(footprints allowed)
		)
		(placement
			(enabled no)
			(sheetname "")
		)
		(fill
			(thermal_gap 0.5)
			(thermal_bridge_width 0.5)
			(island_removal_mode 0)
		)
		(polygon
			(pts
				(xy 197.954646 -208.125314) (xy 199.453246 -208.125314) (xy 199.453246 -208.645252) (xy 197.954646 -208.645252)
			)
		)
	)
	(zone
		(layer "In2.Cu")
		(hatch none 0.5)
		(connect_pads
			(clearance 0)
		)
		(min_thickness 0.25)
		(keepout
			(tracks not_allowed)
			(vias allowed)
			(pads allowed)
			(copperpour not_allowed)
			(footprints allowed)
		)
		(placement
			(enabled no)
			(sheetname "")
		)
		(fill
			(thermal_gap 0.5)
			(thermal_bridge_width 0.5)
			(island_removal_mode 0)
		)
		(polygon
			(pts
				(xy 58.678826 -229.375208) (xy 60.177426 -229.375208) (xy 60.177426 -229.895146) (xy 58.678826 -229.895146)
			)
		)
	)
	(zone
		(layer "In2.Cu")
		(hatch none 0.5)
		(connect_pads
			(clearance 0)
		)
		(min_thickness 0.25)
		(keepout
			(tracks not_allowed)
			(vias allowed)
			(pads allowed)
			(copperpour not_allowed)
			(footprints allowed)
		)
		(placement
			(enabled no)
			(sheetname "")
		)
		(fill
			(thermal_gap 0.5)
			(thermal_bridge_width 0.5)
			(island_removal_mode 0)
		)
		(polygon
			(pts
				(xy 434.250846 -211.525104) (xy 435.749446 -211.525104) (xy 435.749446 -212.045042) (xy 434.250846 -212.045042)
			)
		)
	)
	(zone
		(layer "In2.Cu")
		(hatch none 0.5)
		(connect_pads
			(clearance 0)
		)
		(min_thickness 0.25)
		(keepout
			(tracks not_allowed)
			(vias allowed)
			(pads allowed)
			(copperpour not_allowed)
			(footprints allowed)
		)
		(placement
			(enabled no)
			(sheetname "")
		)
		(fill
			(thermal_gap 0.5)
			(thermal_bridge_width 0.5)
			(island_removal_mode 0)
		)
		(polygon
			(pts
				(xy 291.530786 -238.725202) (xy 293.029386 -238.725202) (xy 293.029386 -239.24514) (xy 291.530786 -239.24514)
			)
		)
	)
	(zone
		(layer "In2.Cu")
		(hatch none 0.5)
		(connect_pads
			(clearance 0)
		)
		(min_thickness 0.25)
		(keepout
			(tracks not_allowed)
			(vias allowed)
			(pads allowed)
			(copperpour not_allowed)
			(footprints allowed)
		)
		(placement
			(enabled no)
			(sheetname "")
		)
		(fill
			(thermal_gap 0.5)
			(thermal_bridge_width 0.5)
			(island_removal_mode 0)
		)
		(polygon
			(pts
				(arc
					(start 347.627194 -379.360684)
					(mid 347.647118 -379.36992)
					(end 347.66885 -379.37313)
				)
				(arc
					(start 347.863414 -379.37313)
					(mid 347.917296 -379.350812)
					(end 347.939614 -379.29693)
				)
				(arc
					(start 347.939614 -378.61113)
					(mid 347.917296 -378.557248)
					(end 347.863414 -378.53493)
				)
				(arc
					(start 347.66885 -378.53493)
					(mid 347.647106 -378.538098)
					(end 347.627194 -378.547376)
				)
				(arc
					(start 347.33103 -378.740162)
					(mid 347.289346 -378.752384)
					(end 347.247718 -378.739908)
				)
				(arc
					(start 346.954094 -378.547376)
					(mid 346.93417 -378.53814)
					(end 346.912438 -378.53493)
				)
				(arc
					(start 346.717874 -378.53493)
					(mid 346.663992 -378.557248)
					(end 346.641674 -378.61113)
				)
				(arc
					(start 346.641674 -379.29693)
					(mid 346.663992 -379.350812)
					(end 346.717874 -379.37313)
				)
				(arc
					(start 346.913708 -379.37313)
					(mid 346.935452 -379.369962)
					(end 346.955364 -379.360684)
				)
				(arc
					(start 347.248988 -379.168152)
					(mid 347.290644 -379.15575)
					(end 347.3323 -379.168152)
				)
			)
		)
	)
	(zone
		(layer "In2.Cu")
		(hatch none 0.5)
		(connect_pads
			(clearance 0)
		)
		(min_thickness 0.25)
		(keepout
			(tracks not_allowed)
			(vias allowed)
			(pads allowed)
			(copperpour not_allowed)
			(footprints allowed)
		)
		(placement
			(enabled no)
			(sheetname "")
		)
		(fill
			(thermal_gap 0.5)
			(thermal_bridge_width 0.5)
			(island_removal_mode 0)
		)
		(polygon
			(pts
				(xy 186.310778 -274.425156) (xy 187.809378 -274.425156) (xy 187.809378 -274.945094) (xy 186.310778 -274.945094)
			)
		)
	)
	(zone
		(layer "In2.Cu")
		(hatch none 0.5)
		(connect_pads
			(clearance 0)
		)
		(min_thickness 0.25)
		(keepout
			(tracks not_allowed)
			(vias allowed)
			(pads allowed)
			(copperpour not_allowed)
			(footprints allowed)
		)
		(placement
			(enabled no)
			(sheetname "")
		)
		(fill
			(thermal_gap 0.5)
			(thermal_bridge_width 0.5)
			(island_removal_mode 0)
		)
		(polygon
			(pts
				(xy 415.718752 -201.325226) (xy 417.217352 -201.325226) (xy 417.217352 -201.845164) (xy 415.718752 -201.845164)
			)
		)
	)
	(zone
		(layer "In2.Cu")
		(hatch none 0.5)
		(connect_pads
			(clearance 0)
		)
		(min_thickness 0.25)
		(keepout
			(tracks not_allowed)
			(vias allowed)
			(pads allowed)
			(copperpour not_allowed)
			(footprints allowed)
		)
		(placement
			(enabled no)
			(sheetname "")
		)
		(fill
			(thermal_gap 0.5)
			(thermal_bridge_width 0.5)
			(island_removal_mode 0)
		)
		(polygon
			(pts
				(xy 449.3387 -276.125178) (xy 450.8373 -276.125178) (xy 450.8373 -276.645116) (xy 449.3387 -276.645116)
			)
		)
	)
	(zone
		(layer "In2.Cu")
		(hatch none 0.5)
		(connect_pads
			(clearance 0)
		)
		(min_thickness 0.25)
		(keepout
			(tracks not_allowed)
			(vias allowed)
			(pads allowed)
			(copperpour not_allowed)
			(footprints allowed)
		)
		(placement
			(enabled no)
			(sheetname "")
		)
		(fill
			(thermal_gap 0.5)
			(thermal_bridge_width 0.5)
			(island_removal_mode 0)
		)
		(polygon
			(pts
				(xy 193.854578 -285.475172) (xy 195.353178 -285.475172) (xy 195.353178 -285.99511) (xy 193.854578 -285.99511)
			)
		)
	)
	(zone
		(layer "In2.Cu")
		(hatch none 0.5)
		(connect_pads
			(clearance 0)
		)
		(min_thickness 0.25)
		(keepout
			(tracks not_allowed)
			(vias allowed)
			(pads allowed)
			(copperpour not_allowed)
			(footprints allowed)
		)
		(placement
			(enabled no)
			(sheetname "")
		)
		(fill
			(thermal_gap 0.5)
			(thermal_bridge_width 0.5)
			(island_removal_mode 0)
		)
		(polygon
			(pts
				(xy 449.3387 -291.425122) (xy 450.8373 -291.425122) (xy 450.8373 -291.94506) (xy 449.3387 -291.94506)
			)
		)
	)
	(zone
		(layer "In2.Cu")
		(hatch none 0.5)
		(connect_pads
			(clearance 0)
		)
		(min_thickness 0.25)
		(keepout
			(tracks not_allowed)
			(vias allowed)
			(pads allowed)
			(copperpour not_allowed)
			(footprints allowed)
		)
		(placement
			(enabled no)
			(sheetname "")
		)
		(fill
			(thermal_gap 0.5)
			(thermal_bridge_width 0.5)
			(island_removal_mode 0)
		)
		(polygon
			(pts
				(xy 58.678826 -248.925334) (xy 60.177426 -248.925334) (xy 60.177426 -249.445272) (xy 58.678826 -249.445272)
			)
		)
	)
	(zone
		(layer "In2.Cu")
		(hatch none 0.5)
		(connect_pads
			(clearance 0)
		)
		(min_thickness 0.25)
		(keepout
			(tracks not_allowed)
			(vias allowed)
			(pads allowed)
			(copperpour not_allowed)
			(footprints allowed)
		)
		(placement
			(enabled no)
			(sheetname "")
		)
		(fill
			(thermal_gap 0.5)
			(thermal_bridge_width 0.5)
			(island_removal_mode 0)
		)
		(polygon
			(pts
				(xy 438.350914 -275.275294) (xy 439.849514 -275.275294) (xy 439.849514 -275.795232) (xy 438.350914 -275.795232)
			)
		)
	)
	(zone
		(layer "In2.Cu")
		(hatch none 0.5)
		(connect_pads
			(clearance 0)
		)
		(min_thickness 0.25)
		(keepout
			(tracks not_allowed)
			(vias allowed)
			(pads allowed)
			(copperpour not_allowed)
			(footprints allowed)
		)
		(placement
			(enabled no)
			(sheetname "")
		)
		(fill
			(thermal_gap 0.5)
			(thermal_bridge_width 0.5)
			(island_removal_mode 0)
		)
		(polygon
			(pts
				(xy 291.530786 -269.325344) (xy 293.029386 -269.325344) (xy 293.029386 -269.845282) (xy 291.530786 -269.845282)
			)
		)
	)
	(zone
		(layer "In2.Cu")
		(hatch none 0.5)
		(connect_pads
			(clearance 0)
		)
		(min_thickness 0.25)
		(keepout
			(tracks not_allowed)
			(vias allowed)
			(pads allowed)
			(copperpour not_allowed)
			(footprints allowed)
		)
		(placement
			(enabled no)
			(sheetname "")
		)
		(fill
			(thermal_gap 0.5)
			(thermal_bridge_width 0.5)
			(island_removal_mode 0)
		)
		(polygon
			(pts
				(xy 201.398632 -227.675186) (xy 202.897232 -227.675186) (xy 202.897232 -228.195124) (xy 201.398632 -228.195124)
			)
		)
	)
	(zone
		(layer "In2.Cu")
		(hatch none 0.5)
		(connect_pads
			(clearance 0)
		)
		(min_thickness 0.25)
		(keepout
			(tracks not_allowed)
			(vias allowed)
			(pads allowed)
			(copperpour not_allowed)
			(footprints allowed)
		)
		(placement
			(enabled no)
			(sheetname "")
		)
		(fill
			(thermal_gap 0.5)
			(thermal_bridge_width 0.5)
			(island_removal_mode 0)
		)
		(polygon
			(pts
				(xy 58.678826 -245.52529) (xy 60.177426 -245.52529) (xy 60.177426 -246.045228) (xy 58.678826 -246.045228)
			)
		)
	)
	(zone
		(layer "In2.Cu")
		(hatch none 0.5)
		(connect_pads
			(clearance 0)
		)
		(min_thickness 0.25)
		(keepout
			(tracks not_allowed)
			(vias allowed)
			(pads allowed)
			(copperpour not_allowed)
			(footprints allowed)
		)
		(placement
			(enabled no)
			(sheetname "")
		)
		(fill
			(thermal_gap 0.5)
			(thermal_bridge_width 0.5)
			(island_removal_mode 0)
		)
		(polygon
			(pts
				(xy 415.718752 -217.475308) (xy 417.217352 -217.475308) (xy 417.217352 -217.995246) (xy 415.718752 -217.995246)
			)
		)
	)
	(zone
		(layer "In2.Cu")
		(hatch none 0.5)
		(connect_pads
			(clearance 0)
		)
		(min_thickness 0.25)
		(keepout
			(tracks not_allowed)
			(vias allowed)
			(pads allowed)
			(copperpour not_allowed)
			(footprints allowed)
		)
		(placement
			(enabled no)
			(sheetname "")
		)
		(fill
			(thermal_gap 0.5)
			(thermal_bridge_width 0.5)
			(island_removal_mode 0)
		)
		(polygon
			(pts
				(xy 306.618894 -219.17533) (xy 308.117494 -219.17533) (xy 308.117494 -219.695268) (xy 306.618894 -219.695268)
			)
		)
	)
	(zone
		(layer "In2.Cu")
		(hatch none 0.5)
		(connect_pads
			(clearance 0)
		)
		(min_thickness 0.25)
		(keepout
			(tracks not_allowed)
			(vias allowed)
			(pads allowed)
			(copperpour not_allowed)
			(footprints allowed)
		)
		(placement
			(enabled no)
			(sheetname "")
		)
		(fill
			(thermal_gap 0.5)
			(thermal_bridge_width 0.5)
			(island_removal_mode 0)
		)
		(polygon
			(pts
				(xy 24.402542 -241.275108) (xy 25.901142 -241.275108) (xy 25.901142 -241.795046) (xy 24.402542 -241.795046)
			)
		)
	)
	(zone
		(layer "In2.Cu")
		(hatch none 0.5)
		(connect_pads
			(clearance 0)
		)
		(min_thickness 0.25)
		(keepout
			(tracks not_allowed)
			(vias allowed)
			(pads allowed)
			(copperpour not_allowed)
			(footprints allowed)
		)
		(placement
			(enabled no)
			(sheetname "")
		)
		(fill
			(thermal_gap 0.5)
			(thermal_bridge_width 0.5)
			(island_removal_mode 0)
		)
		(polygon
			(pts
				(xy 16.858742 -294.825166) (xy 18.357342 -294.825166) (xy 18.357342 -295.345104) (xy 16.858742 -295.345104)
			)
		)
	)
	(zone
		(layer "In2.Cu")
		(hatch none 0.5)
		(connect_pads
			(clearance 0)
		)
		(min_thickness 0.25)
		(keepout
			(tracks not_allowed)
			(vias allowed)
			(pads allowed)
			(copperpour not_allowed)
			(footprints allowed)
		)
		(placement
			(enabled no)
			(sheetname "")
		)
		(fill
			(thermal_gap 0.5)
			(thermal_bridge_width 0.5)
			(island_removal_mode 0)
		)
		(polygon
			(pts
				(xy 434.250846 -288.025332) (xy 435.749446 -288.025332) (xy 435.749446 -288.54527) (xy 434.250846 -288.54527)
			)
		)
	)
	(zone
		(layer "In2.Cu")
		(hatch none 0.5)
		(connect_pads
			(clearance 0)
		)
		(min_thickness 0.25)
		(keepout
			(tracks not_allowed)
			(vias allowed)
			(pads allowed)
			(copperpour not_allowed)
			(footprints allowed)
		)
		(placement
			(enabled no)
			(sheetname "")
		)
		(fill
			(thermal_gap 0.5)
			(thermal_bridge_width 0.5)
			(island_removal_mode 0)
		)
		(polygon
			(pts
				(xy 302.518826 -224.275142) (xy 304.017426 -224.275142) (xy 304.017426 -224.79508) (xy 302.518826 -224.79508)
			)
		)
	)
	(zone
		(layer "In2.Cu")
		(hatch none 0.5)
		(connect_pads
			(clearance 0)
		)
		(min_thickness 0.25)
		(keepout
			(tracks not_allowed)
			(vias allowed)
			(pads allowed)
			(copperpour not_allowed)
			(footprints allowed)
		)
		(placement
			(enabled no)
			(sheetname "")
		)
		(fill
			(thermal_gap 0.5)
			(thermal_bridge_width 0.5)
			(island_removal_mode 0)
		)
		(polygon
			(pts
				(xy 36.046664 -248.925334) (xy 37.545264 -248.925334) (xy 37.545264 -249.445272) (xy 36.046664 -249.445272)
			)
		)
	)
	(zone
		(layer "In2.Cu")
		(hatch none 0.5)
		(connect_pads
			(clearance 0)
		)
		(min_thickness 0.25)
		(keepout
			(tracks not_allowed)
			(vias allowed)
			(pads allowed)
			(copperpour not_allowed)
			(footprints allowed)
		)
		(placement
			(enabled no)
			(sheetname "")
		)
		(fill
			(thermal_gap 0.5)
			(thermal_bridge_width 0.5)
			(island_removal_mode 0)
		)
		(polygon
			(pts
				(xy 167.778684 -247.225312) (xy 169.277284 -247.225312) (xy 169.277284 -247.74525) (xy 167.778684 -247.74525)
			)
		)
	)
	(zone
		(layer "In2.Cu")
		(hatch none 0.5)
		(connect_pads
			(clearance 0)
		)
		(min_thickness 0.25)
		(keepout
			(tracks allowed)
			(vias allowed)
			(pads allowed)
			(copperpour allowed)
			(footprints allowed)
		)
		(placement
			(enabled no)
			(sheetname "")
		)
		(fill
			(thermal_gap 0.5)
			(thermal_bridge_width 0.5)
			(island_removal_mode 0)
		)
		(polygon
			(pts
				(xy 413.55899 -162.069018) (xy 413.55899 -161.522664) (xy 414.11144 -161.522664) (xy 414.11144 -162.069018)
			)
		)
	)
	(zone
		(layer "In2.Cu")
		(hatch none 0.5)
		(connect_pads
			(clearance 0)
		)
		(min_thickness 0.25)
		(keepout
			(tracks not_allowed)
			(vias allowed)
			(pads allowed)
			(copperpour not_allowed)
			(footprints allowed)
		)
		(placement
			(enabled no)
			(sheetname "")
		)
		(fill
			(thermal_gap 0.5)
			(thermal_bridge_width 0.5)
			(island_removal_mode 0)
		)
		(polygon
			(pts
				(xy 20.95881 -225.12528) (xy 22.45741 -225.12528) (xy 22.45741 -225.645218) (xy 20.95881 -225.645218)
			)
		)
	)
	(zone
		(layer "In2.Cu")
		(hatch none 0.5)
		(connect_pads
			(clearance 0)
		)
		(min_thickness 0.25)
		(keepout
			(tracks not_allowed)
			(vias allowed)
			(pads allowed)
			(copperpour not_allowed)
			(footprints allowed)
		)
		(placement
			(enabled no)
			(sheetname "")
		)
		(fill
			(thermal_gap 0.5)
			(thermal_bridge_width 0.5)
			(island_removal_mode 0)
		)
		(polygon
			(pts
				(xy 419.162738 -268.475206) (xy 420.661338 -268.475206) (xy 420.661338 -268.995144) (xy 419.162738 -268.995144)
			)
		)
	)
	(zone
		(layer "In2.Cu")
		(hatch none 0.5)
		(connect_pads
			(clearance 0)
		)
		(min_thickness 0.25)
		(keepout
			(tracks not_allowed)
			(vias allowed)
			(pads allowed)
			(copperpour not_allowed)
			(footprints allowed)
		)
		(placement
			(enabled no)
			(sheetname "")
		)
		(fill
			(thermal_gap 0.5)
			(thermal_bridge_width 0.5)
			(island_removal_mode 0)
		)
		(polygon
			(pts
				(xy 268.898878 -237.875318) (xy 270.397478 -237.875318) (xy 270.397478 -238.395256) (xy 268.898878 -238.395256)
			)
		)
	)
	(zone
		(layer "In2.Cu")
		(hatch none 0.5)
		(connect_pads
			(clearance 0)
		)
		(min_thickness 0.25)
		(keepout
			(tracks not_allowed)
			(vias allowed)
			(pads allowed)
			(copperpour not_allowed)
			(footprints allowed)
		)
		(placement
			(enabled no)
			(sheetname "")
		)
		(fill
			(thermal_gap 0.5)
			(thermal_bridge_width 0.5)
			(island_removal_mode 0)
		)
		(polygon
			(pts
				(xy 306.618894 -287.175194) (xy 308.117494 -287.175194) (xy 308.117494 -287.695132) (xy 306.618894 -287.695132)
			)
		)
	)
	(zone
		(layer "In2.Cu")
		(hatch none 0.5)
		(connect_pads
			(clearance 0)
		)
		(min_thickness 0.25)
		(keepout
			(tracks not_allowed)
			(vias allowed)
			(pads allowed)
			(copperpour not_allowed)
			(footprints allowed)
		)
		(placement
			(enabled no)
			(sheetname "")
		)
		(fill
			(thermal_gap 0.5)
			(thermal_bridge_width 0.5)
			(island_removal_mode 0)
		)
		(polygon
			(pts
				(xy 279.886664 -289.725354) (xy 281.385264 -289.725354) (xy 281.385264 -290.245292) (xy 279.886664 -290.245292)
			)
		)
	)
	(zone
		(layer "In2.Cu")
		(hatch none 0.5)
		(connect_pads
			(clearance 0)
		)
		(min_thickness 0.25)
		(keepout
			(tracks not_allowed)
			(vias allowed)
			(pads allowed)
			(copperpour not_allowed)
			(footprints allowed)
		)
		(placement
			(enabled no)
			(sheetname "")
		)
		(fill
			(thermal_gap 0.5)
			(thermal_bridge_width 0.5)
			(island_removal_mode 0)
		)
		(polygon
			(pts
				(xy 279.886664 -306.72532) (xy 281.385264 -306.72532) (xy 281.385264 -307.245258) (xy 279.886664 -307.245258)
			)
		)
	)
	(zone
		(layer "In2.Cu")
		(hatch none 0.5)
		(connect_pads
			(clearance 0)
		)
		(min_thickness 0.25)
		(keepout
			(tracks not_allowed)
			(vias allowed)
			(pads allowed)
			(copperpour not_allowed)
			(footprints allowed)
		)
		(placement
			(enabled no)
			(sheetname "")
		)
		(fill
			(thermal_gap 0.5)
			(thermal_bridge_width 0.5)
			(island_removal_mode 0)
		)
		(polygon
			(pts
				(xy 294.974772 -229.375208) (xy 296.473372 -229.375208) (xy 296.473372 -229.895146) (xy 294.974772 -229.895146)
			)
		)
	)
	(zone
		(layer "In2.Cu")
		(hatch none 0.5)
		(connect_pads
			(clearance 0)
		)
		(min_thickness 0.25)
		(keepout
			(tracks not_allowed)
			(vias allowed)
			(pads allowed)
			(copperpour not_allowed)
			(footprints allowed)
		)
		(placement
			(enabled no)
			(sheetname "")
		)
		(fill
			(thermal_gap 0.5)
			(thermal_bridge_width 0.5)
			(island_removal_mode 0)
		)
		(polygon
			(pts
				(xy 279.886664 -244.675152) (xy 281.385264 -244.675152) (xy 281.385264 -245.19509) (xy 279.886664 -245.19509)
			)
		)
	)
	(zone
		(layer "In2.Cu")
		(hatch none 0.5)
		(connect_pads
			(clearance 0)
		)
		(min_thickness 0.25)
		(keepout
			(tracks not_allowed)
			(vias allowed)
			(pads allowed)
			(copperpour not_allowed)
			(footprints allowed)
		)
		(placement
			(enabled no)
			(sheetname "")
		)
		(fill
			(thermal_gap 0.5)
			(thermal_bridge_width 0.5)
			(island_removal_mode 0)
		)
		(polygon
			(pts
				(xy 163.678616 -293.125144) (xy 165.177216 -293.125144) (xy 165.177216 -293.645082) (xy 163.678616 -293.645082)
			)
		)
	)
	(zone
		(layer "In2.Cu")
		(hatch none 0.5)
		(connect_pads
			(clearance 0)
		)
		(min_thickness 0.25)
		(keepout
			(tracks not_allowed)
			(vias allowed)
			(pads allowed)
			(copperpour not_allowed)
			(footprints allowed)
		)
		(placement
			(enabled no)
			(sheetname "")
		)
		(fill
			(thermal_gap 0.5)
			(thermal_bridge_width 0.5)
			(island_removal_mode 0)
		)
		(polygon
			(pts
				(xy 51.134772 -252.325124) (xy 52.633372 -252.325124) (xy 52.633372 -252.845062) (xy 51.134772 -252.845062)
			)
		)
	)
	(zone
		(layer "In2.Cu")
		(hatch none 0.5)
		(connect_pads
			(clearance 0)
		)
		(min_thickness 0.25)
		(keepout
			(tracks not_allowed)
			(vias allowed)
			(pads allowed)
			(copperpour not_allowed)
			(footprints allowed)
		)
		(placement
			(enabled no)
			(sheetname "")
		)
		(fill
			(thermal_gap 0.5)
			(thermal_bridge_width 0.5)
			(island_removal_mode 0)
		)
		(polygon
			(pts
				(xy 306.618894 -267.625322) (xy 308.117494 -267.625322) (xy 308.117494 -268.14526) (xy 306.618894 -268.14526)
			)
		)
	)
	(zone
		(layer "In2.Cu")
		(hatch none 0.5)
		(connect_pads
			(clearance 0)
		)
		(min_thickness 0.25)
		(keepout
			(tracks not_allowed)
			(vias allowed)
			(pads allowed)
			(copperpour not_allowed)
			(footprints allowed)
		)
		(placement
			(enabled no)
			(sheetname "")
		)
		(fill
			(thermal_gap 0.5)
			(thermal_bridge_width 0.5)
			(island_removal_mode 0)
		)
		(polygon
			(pts
				(xy 279.886664 -302.475138) (xy 281.385264 -302.475138) (xy 281.385264 -302.995076) (xy 279.886664 -302.995076)
			)
		)
	)
	(zone
		(layer "In2.Cu")
		(hatch none 0.5)
		(connect_pads
			(clearance 0)
		)
		(min_thickness 0.25)
		(keepout
			(tracks not_allowed)
			(vias allowed)
			(pads allowed)
			(copperpour not_allowed)
			(footprints allowed)
		)
		(placement
			(enabled no)
			(sheetname "")
		)
		(fill
			(thermal_gap 0.5)
			(thermal_bridge_width 0.5)
			(island_removal_mode 0)
		)
		(polygon
			(pts
				(xy 438.350914 -243.825268) (xy 439.849514 -243.825268) (xy 439.849514 -244.345206) (xy 438.350914 -244.345206)
			)
		)
	)
	(zone
		(layer "In2.Cu")
		(hatch none 0.5)
		(connect_pads
			(clearance 0)
		)
		(min_thickness 0.25)
		(keepout
			(tracks allowed)
			(vias allowed)
			(pads allowed)
			(copperpour allowed)
			(footprints allowed)
		)
		(placement
			(enabled no)
			(sheetname "")
		)
		(fill
			(thermal_gap 0.5)
			(thermal_bridge_width 0.5)
			(island_removal_mode 0)
		)
		(polygon
			(pts
				(xy 427.076616 -354.252784) (xy 427.076616 -353.630484) (xy 427.627796 -353.630484) (xy 427.627796 -354.252784)
			)
		)
	)
	(zone
		(layer "In2.Cu")
		(hatch none 0.5)
		(connect_pads
			(clearance 0)
		)
		(min_thickness 0.25)
		(keepout
			(tracks not_allowed)
			(vias allowed)
			(pads allowed)
			(copperpour not_allowed)
			(footprints allowed)
		)
		(placement
			(enabled no)
			(sheetname "")
		)
		(fill
			(thermal_gap 0.5)
			(thermal_bridge_width 0.5)
			(island_removal_mode 0)
		)
		(polygon
			(pts
				(xy 171.22267 -227.675186) (xy 172.72127 -227.675186) (xy 172.72127 -228.195124) (xy 171.22267 -228.195124)
			)
		)
	)
	(zone
		(layer "In2.Cu")
		(hatch none 0.5)
		(connect_pads
			(clearance 0)
		)
		(min_thickness 0.25)
		(keepout
			(tracks not_allowed)
			(vias allowed)
			(pads allowed)
			(copperpour not_allowed)
			(footprints allowed)
		)
		(placement
			(enabled no)
			(sheetname "")
		)
		(fill
			(thermal_gap 0.5)
			(thermal_bridge_width 0.5)
			(island_removal_mode 0)
		)
		(polygon
			(pts
				(xy 423.262806 -203.025248) (xy 424.761406 -203.025248) (xy 424.761406 -203.545186) (xy 423.262806 -203.545186)
			)
		)
	)
	(zone
		(layer "In2.Cu")
		(hatch none 0.5)
		(connect_pads
			(clearance 0)
		)
		(min_thickness 0.25)
		(keepout
			(tracks allowed)
			(vias allowed)
			(pads allowed)
			(copperpour allowed)
			(footprints allowed)
		)
		(placement
			(enabled no)
			(sheetname "")
		)
		(fill
			(thermal_gap 0.5)
			(thermal_bridge_width 0.5)
			(island_removal_mode 0)
		)
		(polygon
			(pts
				(xy 32.03321 -349.859092) (xy 32.03321 -349.236792) (xy 32.58439 -349.236792) (xy 32.58439 -349.859092)
			)
		)
	)
	(zone
		(layer "In2.Cu")
		(hatch none 0.5)
		(connect_pads
			(clearance 0)
		)
		(min_thickness 0.25)
		(keepout
			(tracks not_allowed)
			(vias allowed)
			(pads allowed)
			(copperpour not_allowed)
			(footprints allowed)
		)
		(placement
			(enabled no)
			(sheetname "")
		)
		(fill
			(thermal_gap 0.5)
			(thermal_bridge_width 0.5)
			(island_removal_mode 0)
		)
		(polygon
			(pts
				(xy 171.22267 -251.47524) (xy 172.72127 -251.47524) (xy 172.72127 -251.995178) (xy 171.22267 -251.995178)
			)
		)
	)
	(zone
		(layer "In2.Cu")
		(hatch none 0.5)
		(connect_pads
			(clearance 0)
		)
		(min_thickness 0.25)
		(keepout
			(tracks not_allowed)
			(vias allowed)
			(pads allowed)
			(copperpour not_allowed)
			(footprints allowed)
		)
		(placement
			(enabled no)
			(sheetname "")
		)
		(fill
			(thermal_gap 0.5)
			(thermal_bridge_width 0.5)
			(island_removal_mode 0)
		)
		(polygon
			(pts
				(xy 291.530786 -220.025214) (xy 293.029386 -220.025214) (xy 293.029386 -220.545152) (xy 291.530786 -220.545152)
			)
		)
	)
	(zone
		(layer "In2.Cu")
		(hatch none 0.5)
		(connect_pads
			(clearance 0)
		)
		(min_thickness 0.25)
		(keepout
			(tracks not_allowed)
			(vias allowed)
			(pads allowed)
			(copperpour not_allowed)
			(footprints allowed)
		)
		(placement
			(enabled no)
			(sheetname "")
		)
		(fill
			(thermal_gap 0.5)
			(thermal_bridge_width 0.5)
			(island_removal_mode 0)
		)
		(polygon
			(pts
				(xy 299.07484 -265.9253) (xy 300.57344 -265.9253) (xy 300.57344 -266.445238) (xy 299.07484 -266.445238)
			)
		)
	)
	(zone
		(layer "In2.Cu")
		(hatch none 0.5)
		(connect_pads
			(clearance 0)
		)
		(min_thickness 0.25)
		(keepout
			(tracks allowed)
			(vias allowed)
			(pads allowed)
			(copperpour allowed)
			(footprints allowed)
		)
		(placement
			(enabled no)
			(sheetname "")
		)
		(fill
			(thermal_gap 0.5)
			(thermal_bridge_width 0.5)
			(island_removal_mode 0)
		)
		(polygon
			(pts
				(xy 83.51901 -335.866232) (xy 83.51901 -336.696812) (xy 83.37423 -336.696812) (xy 83.37423 -335.866232)
			)
		)
	)
	(zone
		(layer "In2.Cu")
		(hatch none 0.5)
		(connect_pads
			(clearance 0)
		)
		(min_thickness 0.25)
		(keepout
			(tracks not_allowed)
			(vias allowed)
			(pads allowed)
			(copperpour not_allowed)
			(footprints allowed)
		)
		(placement
			(enabled no)
			(sheetname "")
		)
		(fill
			(thermal_gap 0.5)
			(thermal_bridge_width 0.5)
			(island_removal_mode 0)
		)
		(polygon
			(pts
				(xy 167.778684 -225.12528) (xy 169.277284 -225.12528) (xy 169.277284 -225.645218) (xy 167.778684 -225.645218)
			)
		)
	)
	(zone
		(layer "In2.Cu")
		(hatch none 0.5)
		(connect_pads
			(clearance 0)
		)
		(min_thickness 0.25)
		(keepout
			(tracks not_allowed)
			(vias allowed)
			(pads allowed)
			(copperpour not_allowed)
			(footprints allowed)
		)
		(placement
			(enabled no)
			(sheetname "")
		)
		(fill
			(thermal_gap 0.5)
			(thermal_bridge_width 0.5)
			(island_removal_mode 0)
		)
		(polygon
			(pts
				(xy 201.398632 -266.775184) (xy 202.897232 -266.775184) (xy 202.897232 -267.295122) (xy 201.398632 -267.295122)
			)
		)
	)
	(zone
		(layer "In2.Cu")
		(hatch none 0.5)
		(connect_pads
			(clearance 0)
		)
		(min_thickness 0.25)
		(keepout
			(tracks not_allowed)
			(vias allowed)
			(pads allowed)
			(copperpour not_allowed)
			(footprints allowed)
		)
		(placement
			(enabled no)
			(sheetname "")
		)
		(fill
			(thermal_gap 0.5)
			(thermal_bridge_width 0.5)
			(island_removal_mode 0)
		)
		(polygon
			(pts
				(xy 445.894968 -197.075298) (xy 447.393568 -197.075298) (xy 447.393568 -197.595236) (xy 445.894968 -197.595236)
			)
		)
	)
	(zone
		(layer "In2.Cu")
		(hatch none 0.5)
		(connect_pads
			(clearance 0)
		)
		(min_thickness 0.25)
		(keepout
			(tracks allowed)
			(vias allowed)
			(pads allowed)
			(copperpour allowed)
			(footprints allowed)
		)
		(placement
			(enabled no)
			(sheetname "")
		)
		(fill
			(thermal_gap 0.5)
			(thermal_bridge_width 0.5)
			(island_removal_mode 0)
		)
		(polygon
			(pts
				(xy 108.067094 -327.248012) (xy 106.355134 -328.959972) (xy 106.355134 -344.034872) (xy 103.202994 -347.187012)
				(xy 96.126554 -347.187012) (xy 91.298014 -342.358472) (xy 76.860654 -342.358472) (xy 64.008254 -355.210872)
				(xy 59.415934 -355.210872) (xy 58.557414 -356.069392) (xy 56.273954 -356.069392) (xy 56.050434 -355.845872)
				(xy 55.179214 -355.845872) (xy 54.942994 -356.082092) (xy 54.942994 -356.348792) (xy 55.522114 -356.927912)
				(xy 58.793634 -356.927912) (xy 59.758834 -355.962712) (xy 64.325754 -355.962712) (xy 77.137514 -343.150952)
				(xy 90.970354 -343.150952) (xy 95.745554 -347.926152) (xy 103.596694 -347.926152) (xy 107.160314 -344.362532)
				(xy 107.160314 -329.742292) (xy 109.075474 -327.827132) (xy 109.075474 -327.248012)
			)
		)
	)
	(zone
		(layer "In2.Cu")
		(hatch none 0.5)
		(connect_pads
			(clearance 0)
		)
		(min_thickness 0.25)
		(keepout
			(tracks not_allowed)
			(vias allowed)
			(pads allowed)
			(copperpour not_allowed)
			(footprints allowed)
		)
		(placement
			(enabled no)
			(sheetname "")
		)
		(fill
			(thermal_gap 0.5)
			(thermal_bridge_width 0.5)
			(island_removal_mode 0)
		)
		(polygon
			(pts
				(xy 299.07484 -292.27526) (xy 300.57344 -292.27526) (xy 300.57344 -292.795198) (xy 299.07484 -292.795198)
			)
		)
	)
	(zone
		(layer "In2.Cu")
		(hatch none 0.5)
		(connect_pads
			(clearance 0)
		)
		(min_thickness 0.25)
		(keepout
			(tracks not_allowed)
			(vias allowed)
			(pads allowed)
			(copperpour not_allowed)
			(footprints allowed)
		)
		(placement
			(enabled no)
			(sheetname "")
		)
		(fill
			(thermal_gap 0.5)
			(thermal_bridge_width 0.5)
			(island_removal_mode 0)
		)
		(polygon
			(pts
				(xy 201.398632 -213.225126) (xy 202.897232 -213.225126) (xy 202.897232 -213.745064) (xy 201.398632 -213.745064)
			)
		)
	)
	(zone
		(layer "In2.Cu")
		(hatch none 0.5)
		(connect_pads
			(clearance 0)
		)
		(min_thickness 0.25)
		(keepout
			(tracks not_allowed)
			(vias allowed)
			(pads allowed)
			(copperpour not_allowed)
			(footprints allowed)
		)
		(placement
			(enabled no)
			(sheetname "")
		)
		(fill
			(thermal_gap 0.5)
			(thermal_bridge_width 0.5)
			(island_removal_mode 0)
		)
		(polygon
			(pts
				(xy 306.618894 -232.775252) (xy 308.117494 -232.775252) (xy 308.117494 -233.29519) (xy 306.618894 -233.29519)
			)
		)
	)
	(zone
		(layer "In2.Cu")
		(hatch none 0.5)
		(connect_pads
			(clearance 0)
		)
		(min_thickness 0.25)
		(keepout
			(tracks not_allowed)
			(vias allowed)
			(pads allowed)
			(copperpour not_allowed)
			(footprints allowed)
		)
		(placement
			(enabled no)
			(sheetname "")
		)
		(fill
			(thermal_gap 0.5)
			(thermal_bridge_width 0.5)
			(island_removal_mode 0)
		)
		(polygon
			(pts
				(xy 283.986732 -238.725202) (xy 285.485332 -238.725202) (xy 285.485332 -239.24514) (xy 283.986732 -239.24514)
			)
		)
	)
	(zone
		(layer "In2.Cu")
		(hatch none 0.5)
		(connect_pads
			(clearance 0)
		)
		(min_thickness 0.25)
		(keepout
			(tracks not_allowed)
			(vias allowed)
			(pads allowed)
			(copperpour not_allowed)
			(footprints allowed)
		)
		(placement
			(enabled no)
			(sheetname "")
		)
		(fill
			(thermal_gap 0.5)
			(thermal_bridge_width 0.5)
			(island_removal_mode 0)
		)
		(polygon
			(pts
				(xy 279.886664 -293.125144) (xy 281.385264 -293.125144) (xy 281.385264 -293.645082) (xy 279.886664 -293.645082)
			)
		)
	)
	(zone
		(layer "In2.Cu")
		(hatch none 0.5)
		(connect_pads
			(clearance 0)
		)
		(min_thickness 0.25)
		(keepout
			(tracks not_allowed)
			(vias allowed)
			(pads allowed)
			(copperpour not_allowed)
			(footprints allowed)
		)
		(placement
			(enabled no)
			(sheetname "")
		)
		(fill
			(thermal_gap 0.5)
			(thermal_bridge_width 0.5)
			(island_removal_mode 0)
		)
		(polygon
			(pts
				(xy 268.898878 -242.125246) (xy 270.397478 -242.125246) (xy 270.397478 -242.645184) (xy 268.898878 -242.645184)
			)
		)
	)
	(zone
		(layer "In2.Cu")
		(hatch none 0.5)
		(connect_pads
			(clearance 0)
		)
		(min_thickness 0.25)
		(keepout
			(tracks not_allowed)
			(vias allowed)
			(pads allowed)
			(copperpour not_allowed)
			(footprints allowed)
		)
		(placement
			(enabled no)
			(sheetname "")
		)
		(fill
			(thermal_gap 0.5)
			(thermal_bridge_width 0.5)
			(island_removal_mode 0)
		)
		(polygon
			(pts
				(xy 423.262806 -252.325124) (xy 424.761406 -252.325124) (xy 424.761406 -252.845062) (xy 423.262806 -252.845062)
			)
		)
	)
	(zone
		(layer "In2.Cu")
		(hatch none 0.5)
		(connect_pads
			(clearance 0)
		)
		(min_thickness 0.25)
		(keepout
			(tracks not_allowed)
			(vias allowed)
			(pads allowed)
			(copperpour not_allowed)
			(footprints allowed)
		)
		(placement
			(enabled no)
			(sheetname "")
		)
		(fill
			(thermal_gap 0.5)
			(thermal_bridge_width 0.5)
			(island_removal_mode 0)
		)
		(polygon
			(pts
				(xy 287.430718 -300.775116) (xy 288.929318 -300.775116) (xy 288.929318 -301.295054) (xy 287.430718 -301.295054)
			)
		)
	)
	(zone
		(layer "In2.Cu")
		(hatch none 0.5)
		(connect_pads
			(clearance 0)
		)
		(min_thickness 0.25)
		(keepout
			(tracks not_allowed)
			(vias allowed)
			(pads allowed)
			(copperpour not_allowed)
			(footprints allowed)
		)
		(placement
			(enabled no)
			(sheetname "")
		)
		(fill
			(thermal_gap 0.5)
			(thermal_bridge_width 0.5)
			(island_removal_mode 0)
		)
		(polygon
			(pts
				(xy 453.438768 -200.475342) (xy 454.937368 -200.475342) (xy 454.937368 -200.99528) (xy 453.438768 -200.99528)
			)
		)
	)
	(zone
		(layer "In2.Cu")
		(hatch none 0.5)
		(connect_pads
			(clearance 0)
		)
		(min_thickness 0.25)
		(keepout
			(tracks not_allowed)
			(vias allowed)
			(pads allowed)
			(copperpour not_allowed)
			(footprints allowed)
		)
		(placement
			(enabled no)
			(sheetname "")
		)
		(fill
			(thermal_gap 0.5)
			(thermal_bridge_width 0.5)
			(island_removal_mode 0)
		)
		(polygon
			(pts
				(xy 276.442932 -264.225278) (xy 277.941532 -264.225278) (xy 277.941532 -264.745216) (xy 276.442932 -264.745216)
			)
		)
	)
	(zone
		(layer "In2.Cu")
		(hatch none 0.5)
		(connect_pads
			(clearance 0)
		)
		(min_thickness 0.25)
		(keepout
			(tracks not_allowed)
			(vias allowed)
			(pads allowed)
			(copperpour not_allowed)
			(footprints allowed)
		)
		(placement
			(enabled no)
			(sheetname "")
		)
		(fill
			(thermal_gap 0.5)
			(thermal_bridge_width 0.5)
			(island_removal_mode 0)
		)
		(polygon
			(pts
				(arc
					(start 23.698708 -17.966436)
					(mid 23.721026 -18.020318)
					(end 23.774908 -18.042636)
				)
				(arc
					(start 23.970488 -18.042636)
					(mid 23.992364 -18.039504)
					(end 24.012398 -18.03019)
				)
				(arc
					(start 24.306022 -17.837658)
					(mid 24.347678 -17.825256)
					(end 24.389334 -17.837658)
				)
				(arc
					(start 24.684228 -18.03019)
					(mid 24.704152 -18.039426)
					(end 24.725884 -18.042636)
				)
				(arc
					(start 24.920448 -18.042636)
					(mid 24.97433 -18.020318)
					(end 24.996648 -17.966436)
				)
				(arc
					(start 24.996648 -17.280636)
					(mid 24.97433 -17.226754)
					(end 24.920448 -17.204436)
				)
				(arc
					(start 24.725884 -17.204436)
					(mid 24.70414 -17.207604)
					(end 24.684228 -17.216882)
				)
				(arc
					(start 24.388064 -17.409668)
					(mid 24.34638 -17.42189)
					(end 24.304752 -17.409414)
				)
				(arc
					(start 24.011128 -17.216882)
					(mid 23.991204 -17.207646)
					(end 23.969472 -17.204436)
				)
				(arc
					(start 23.774908 -17.204436)
					(mid 23.721026 -17.226754)
					(end 23.698708 -17.280636)
				)
			)
		)
	)
	(zone
		(layer "In2.Cu")
		(hatch none 0.5)
		(connect_pads
			(clearance 0)
		)
		(min_thickness 0.25)
		(keepout
			(tracks not_allowed)
			(vias allowed)
			(pads allowed)
			(copperpour not_allowed)
			(footprints allowed)
		)
		(placement
			(enabled no)
			(sheetname "")
		)
		(fill
			(thermal_gap 0.5)
			(thermal_bridge_width 0.5)
			(island_removal_mode 0)
		)
		(polygon
			(pts
				(xy 291.530786 -292.27526) (xy 293.029386 -292.27526) (xy 293.029386 -292.795198) (xy 291.530786 -292.795198)
			)
		)
	)
	(zone
		(layer "In2.Cu")
		(hatch none 0.5)
		(connect_pads
			(clearance 0)
		)
		(min_thickness 0.25)
		(keepout
			(tracks not_allowed)
			(vias allowed)
			(pads allowed)
			(copperpour not_allowed)
			(footprints allowed)
		)
		(placement
			(enabled no)
			(sheetname "")
		)
		(fill
			(thermal_gap 0.5)
			(thermal_bridge_width 0.5)
			(island_removal_mode 0)
		)
		(polygon
			(pts
				(xy 24.402542 -244.675152) (xy 25.901142 -244.675152) (xy 25.901142 -245.19509) (xy 24.402542 -245.19509)
			)
		)
	)
	(zone
		(layer "In2.Cu")
		(hatch none 0.5)
		(connect_pads
			(clearance 0)
		)
		(min_thickness 0.25)
		(keepout
			(tracks not_allowed)
			(vias allowed)
			(pads allowed)
			(copperpour not_allowed)
			(footprints allowed)
		)
		(placement
			(enabled no)
			(sheetname "")
		)
		(fill
			(thermal_gap 0.5)
			(thermal_bridge_width 0.5)
			(island_removal_mode 0)
		)
		(polygon
			(pts
				(xy 279.886664 -300.775116) (xy 281.385264 -300.775116) (xy 281.385264 -301.295054) (xy 279.886664 -301.295054)
			)
		)
	)
	(zone
		(layer "In2.Cu")
		(hatch none 0.5)
		(connect_pads
			(clearance 0)
		)
		(min_thickness 0.25)
		(keepout
			(tracks allowed)
			(vias allowed)
			(pads allowed)
			(copperpour allowed)
			(footprints allowed)
		)
		(placement
			(enabled no)
			(sheetname "")
		)
		(fill
			(thermal_gap 0.5)
			(thermal_bridge_width 0.5)
			(island_removal_mode 0)
		)
		(polygon
			(pts
				(xy 328.130154 -338.86267) (xy 328.130154 -338.24037) (xy 328.681334 -338.24037) (xy 328.681334 -338.86267)
			)
		)
	)
	(zone
		(layer "In2.Cu")
		(hatch none 0.5)
		(connect_pads
			(clearance 0)
		)
		(min_thickness 0.25)
		(keepout
			(tracks not_allowed)
			(vias allowed)
			(pads allowed)
			(copperpour not_allowed)
			(footprints allowed)
		)
		(placement
			(enabled no)
			(sheetname "")
		)
		(fill
			(thermal_gap 0.5)
			(thermal_bridge_width 0.5)
			(island_removal_mode 0)
		)
		(polygon
			(pts
				(xy 31.946596 -282.075128) (xy 33.445196 -282.075128) (xy 33.445196 -282.595066) (xy 31.946596 -282.595066)
			)
		)
	)
	(zone
		(layer "In2.Cu")
		(hatch none 0.5)
		(connect_pads
			(clearance 0)
		)
		(min_thickness 0.25)
		(keepout
			(tracks not_allowed)
			(vias allowed)
			(pads allowed)
			(copperpour not_allowed)
			(footprints allowed)
		)
		(placement
			(enabled no)
			(sheetname "")
		)
		(fill
			(thermal_gap 0.5)
			(thermal_bridge_width 0.5)
			(island_removal_mode 0)
		)
		(polygon
			(pts
				(xy 415.718752 -206.425292) (xy 417.217352 -206.425292) (xy 417.217352 -206.94523) (xy 415.718752 -206.94523)
			)
		)
	)
	(zone
		(layer "In2.Cu")
		(hatch none 0.5)
		(connect_pads
			(clearance 0)
		)
		(min_thickness 0.25)
		(keepout
			(tracks not_allowed)
			(vias allowed)
			(pads allowed)
			(copperpour not_allowed)
			(footprints allowed)
		)
		(placement
			(enabled no)
			(sheetname "")
		)
		(fill
			(thermal_gap 0.5)
			(thermal_bridge_width 0.5)
			(island_removal_mode 0)
		)
		(polygon
			(pts
				(xy 441.7949 -231.925114) (xy 443.2935 -231.925114) (xy 443.2935 -232.445052) (xy 441.7949 -232.445052)
			)
		)
	)
	(zone
		(layer "In2.Cu")
		(hatch none 0.5)
		(connect_pads
			(clearance 0)
		)
		(min_thickness 0.25)
		(keepout
			(tracks not_allowed)
			(vias allowed)
			(pads allowed)
			(copperpour not_allowed)
			(footprints allowed)
		)
		(placement
			(enabled no)
			(sheetname "")
		)
		(fill
			(thermal_gap 0.5)
			(thermal_bridge_width 0.5)
			(island_removal_mode 0)
		)
		(polygon
			(pts
				(xy 434.250846 -222.57512) (xy 435.749446 -222.57512) (xy 435.749446 -223.095058) (xy 434.250846 -223.095058)
			)
		)
	)
	(zone
		(layer "In2.Cu")
		(hatch none 0.5)
		(connect_pads
			(clearance 0)
		)
		(min_thickness 0.25)
		(keepout
			(tracks not_allowed)
			(vias allowed)
			(pads allowed)
			(copperpour not_allowed)
			(footprints allowed)
		)
		(placement
			(enabled no)
			(sheetname "")
		)
		(fill
			(thermal_gap 0.5)
			(thermal_bridge_width 0.5)
			(island_removal_mode 0)
		)
		(polygon
			(pts
				(xy 438.350914 -296.525188) (xy 439.849514 -296.525188) (xy 439.849514 -297.045126) (xy 438.350914 -297.045126)
			)
		)
	)
	(zone
		(layer "In2.Cu")
		(hatch none 0.5)
		(connect_pads
			(clearance 0)
		)
		(min_thickness 0.25)
		(keepout
			(tracks not_allowed)
			(vias allowed)
			(pads allowed)
			(copperpour not_allowed)
			(footprints allowed)
		)
		(placement
			(enabled no)
			(sheetname "")
		)
		(fill
			(thermal_gap 0.5)
			(thermal_bridge_width 0.5)
			(island_removal_mode 0)
		)
		(polygon
			(pts
				(xy 272.342864 -246.375174) (xy 273.841464 -246.375174) (xy 273.841464 -246.895112) (xy 272.342864 -246.895112)
			)
		)
	)
	(zone
		(layer "In2.Cu")
		(hatch none 0.5)
		(connect_pads
			(clearance 0)
		)
		(min_thickness 0.25)
		(keepout
			(tracks not_allowed)
			(vias allowed)
			(pads allowed)
			(copperpour not_allowed)
			(footprints allowed)
		)
		(placement
			(enabled no)
			(sheetname "")
		)
		(fill
			(thermal_gap 0.5)
			(thermal_bridge_width 0.5)
			(island_removal_mode 0)
		)
		(polygon
			(pts
				(xy 31.946596 -224.275142) (xy 33.445196 -224.275142) (xy 33.445196 -224.79508) (xy 31.946596 -224.79508)
			)
		)
	)
	(zone
		(layer "In2.Cu")
		(hatch none 0.5)
		(connect_pads
			(clearance 0)
		)
		(min_thickness 0.25)
		(keepout
			(tracks not_allowed)
			(vias allowed)
			(pads allowed)
			(copperpour not_allowed)
			(footprints allowed)
		)
		(placement
			(enabled no)
			(sheetname "")
		)
		(fill
			(thermal_gap 0.5)
			(thermal_bridge_width 0.5)
			(island_removal_mode 0)
		)
		(polygon
			(pts
				(xy 294.974772 -317.775336) (xy 296.473372 -317.775336) (xy 296.473372 -318.295274) (xy 294.974772 -318.295274)
			)
		)
	)
	(zone
		(layer "In2.Cu")
		(hatch none 0.5)
		(connect_pads
			(clearance 0)
		)
		(min_thickness 0.25)
		(keepout
			(tracks not_allowed)
			(vias allowed)
			(pads allowed)
			(copperpour not_allowed)
			(footprints allowed)
		)
		(placement
			(enabled no)
			(sheetname "")
		)
		(fill
			(thermal_gap 0.5)
			(thermal_bridge_width 0.5)
			(island_removal_mode 0)
		)
		(polygon
			(pts
				(xy 291.530786 -301.625254) (xy 293.029386 -301.625254) (xy 293.029386 -302.145192) (xy 291.530786 -302.145192)
			)
		)
	)
	(zone
		(layer "In2.Cu")
		(hatch none 0.5)
		(connect_pads
			(clearance 0)
		)
		(min_thickness 0.25)
		(keepout
			(tracks not_allowed)
			(vias allowed)
			(pads allowed)
			(copperpour not_allowed)
			(footprints allowed)
		)
		(placement
			(enabled no)
			(sheetname "")
		)
		(fill
			(thermal_gap 0.5)
			(thermal_bridge_width 0.5)
			(island_removal_mode 0)
		)
		(polygon
			(pts
				(xy 268.898878 -214.075264) (xy 270.397478 -214.075264) (xy 270.397478 -214.595202) (xy 268.898878 -214.595202)
			)
		)
	)
	(zone
		(layer "In2.Cu")
		(hatch none 0.5)
		(connect_pads
			(clearance 0)
		)
		(min_thickness 0.25)
		(keepout
			(tracks not_allowed)
			(vias allowed)
			(pads allowed)
			(copperpour not_allowed)
			(footprints allowed)
		)
		(placement
			(enabled no)
			(sheetname "")
		)
		(fill
			(thermal_gap 0.5)
			(thermal_bridge_width 0.5)
			(island_removal_mode 0)
		)
		(polygon
			(pts
				(xy 441.7949 -210.67522) (xy 443.2935 -210.67522) (xy 443.2935 -211.195158) (xy 441.7949 -211.195158)
			)
		)
	)
	(zone
		(layer "In2.Cu")
		(hatch none 0.5)
		(connect_pads
			(clearance 0)
		)
		(min_thickness 0.25)
		(keepout
			(tracks not_allowed)
			(vias allowed)
			(pads allowed)
			(copperpour not_allowed)
			(footprints allowed)
		)
		(placement
			(enabled no)
			(sheetname "")
		)
		(fill
			(thermal_gap 0.5)
			(thermal_bridge_width 0.5)
			(island_removal_mode 0)
		)
		(polygon
			(pts
				(xy 441.7949 -317.775336) (xy 443.2935 -317.775336) (xy 443.2935 -318.295274) (xy 441.7949 -318.295274)
			)
		)
	)
	(zone
		(layer "In2.Cu")
		(hatch none 0.5)
		(connect_pads
			(clearance 0)
		)
		(min_thickness 0.25)
		(keepout
			(tracks not_allowed)
			(vias allowed)
			(pads allowed)
			(copperpour not_allowed)
			(footprints allowed)
		)
		(placement
			(enabled no)
			(sheetname "")
		)
		(fill
			(thermal_gap 0.5)
			(thermal_bridge_width 0.5)
			(island_removal_mode 0)
		)
		(polygon
			(pts
				(xy 449.3387 -230.225346) (xy 450.8373 -230.225346) (xy 450.8373 -230.745284) (xy 449.3387 -230.745284)
			)
		)
	)
	(zone
		(layer "In2.Cu")
		(hatch none 0.5)
		(connect_pads
			(clearance 0)
		)
		(min_thickness 0.25)
		(keepout
			(tracks not_allowed)
			(vias allowed)
			(pads allowed)
			(copperpour not_allowed)
			(footprints allowed)
		)
		(placement
			(enabled no)
			(sheetname "")
		)
		(fill
			(thermal_gap 0.5)
			(thermal_bridge_width 0.5)
			(island_removal_mode 0)
		)
		(polygon
			(pts
				(xy 47.034704 -314.375292) (xy 48.533304 -314.375292) (xy 48.533304 -314.89523) (xy 47.034704 -314.89523)
			)
		)
	)
	(zone
		(layer "In2.Cu")
		(hatch none 0.5)
		(connect_pads
			(clearance 0)
		)
		(min_thickness 0.25)
		(keepout
			(tracks allowed)
			(vias allowed)
			(pads allowed)
			(copperpour allowed)
			(footprints allowed)
		)
		(placement
			(enabled no)
			(sheetname "")
		)
		(fill
			(thermal_gap 0.5)
			(thermal_bridge_width 0.5)
			(island_removal_mode 0)
		)
		(polygon
			(pts
				(xy 40.31361 -350.595692) (xy 40.31361 -349.973392) (xy 40.86479 -349.973392) (xy 40.86479 -350.595692)
			)
		)
	)
	(zone
		(layer "In2.Cu")
		(hatch none 0.5)
		(connect_pads
			(clearance 0)
		)
		(min_thickness 0.25)
		(keepout
			(tracks not_allowed)
			(vias allowed)
			(pads allowed)
			(copperpour not_allowed)
			(footprints allowed)
		)
		(placement
			(enabled no)
			(sheetname "")
		)
		(fill
			(thermal_gap 0.5)
			(thermal_bridge_width 0.5)
			(island_removal_mode 0)
		)
		(polygon
			(pts
				(xy 51.134772 -315.225176) (xy 52.633372 -315.225176) (xy 52.633372 -315.745114) (xy 51.134772 -315.745114)
			)
		)
	)
	(zone
		(layer "In2.Cu")
		(hatch none 0.5)
		(connect_pads
			(clearance 0)
		)
		(min_thickness 0.25)
		(keepout
			(tracks not_allowed)
			(vias allowed)
			(pads allowed)
			(copperpour not_allowed)
			(footprints allowed)
		)
		(placement
			(enabled no)
			(sheetname "")
		)
		(fill
			(thermal_gap 0.5)
			(thermal_bridge_width 0.5)
			(island_removal_mode 0)
		)
		(polygon
			(pts
				(xy 426.706792 -254.025146) (xy 428.205392 -254.025146) (xy 428.205392 -254.545084) (xy 426.706792 -254.545084)
			)
		)
	)
	(zone
		(layer "In2.Cu")
		(hatch none 0.5)
		(connect_pads
			(clearance 0)
		)
		(min_thickness 0.25)
		(keepout
			(tracks allowed)
			(vias allowed)
			(pads allowed)
			(copperpour allowed)
			(footprints allowed)
		)
		(placement
			(enabled no)
			(sheetname "")
		)
		(fill
			(thermal_gap 0.5)
			(thermal_bridge_width 0.5)
			(island_removal_mode 0)
		)
		(polygon
			(pts
				(xy 358.090978 -164.916612) (xy 358.090978 -165.932612) (xy 357.852218 -165.932612) (xy 357.852218 -164.916612)
			)
		)
	)
	(zone
		(layer "In2.Cu")
		(hatch none 0.5)
		(connect_pads
			(clearance 0)
		)
		(min_thickness 0.25)
		(keepout
			(tracks not_allowed)
			(vias allowed)
			(pads allowed)
			(copperpour not_allowed)
			(footprints allowed)
		)
		(placement
			(enabled no)
			(sheetname "")
		)
		(fill
			(thermal_gap 0.5)
			(thermal_bridge_width 0.5)
			(island_removal_mode 0)
		)
		(polygon
			(pts
				(xy 294.974772 -313.525154) (xy 296.473372 -313.525154) (xy 296.473372 -314.045092) (xy 294.974772 -314.045092)
			)
		)
	)
	(zone
		(layer "In2.Cu")
		(hatch none 0.5)
		(connect_pads
			(clearance 0)
		)
		(min_thickness 0.25)
		(keepout
			(tracks not_allowed)
			(vias allowed)
			(pads allowed)
			(copperpour not_allowed)
			(footprints allowed)
		)
		(placement
			(enabled no)
			(sheetname "")
		)
		(fill
			(thermal_gap 0.5)
			(thermal_bridge_width 0.5)
			(island_removal_mode 0)
		)
		(polygon
			(pts
				(xy 434.250846 -304.17516) (xy 435.749446 -304.17516) (xy 435.749446 -304.695098) (xy 434.250846 -304.695098)
			)
		)
	)
	(zone
		(layer "In2.Cu")
		(hatch none 0.5)
		(connect_pads
			(clearance 0)
		)
		(min_thickness 0.25)
		(keepout
			(tracks not_allowed)
			(vias allowed)
			(pads allowed)
			(copperpour not_allowed)
			(footprints allowed)
		)
		(placement
			(enabled no)
			(sheetname "")
		)
		(fill
			(thermal_gap 0.5)
			(thermal_bridge_width 0.5)
			(island_removal_mode 0)
		)
		(polygon
			(pts
				(xy 163.678616 -305.025298) (xy 165.177216 -305.025298) (xy 165.177216 -305.545236) (xy 163.678616 -305.545236)
			)
		)
	)
	(zone
		(layer "In2.Cu")
		(hatch none 0.5)
		(connect_pads
			(clearance 0)
		)
		(min_thickness 0.25)
		(keepout
			(tracks not_allowed)
			(vias allowed)
			(pads allowed)
			(copperpour not_allowed)
			(footprints allowed)
		)
		(placement
			(enabled no)
			(sheetname "")
		)
		(fill
			(thermal_gap 0.5)
			(thermal_bridge_width 0.5)
			(island_removal_mode 0)
		)
		(polygon
			(pts
				(xy 294.974772 -199.625204) (xy 296.473372 -199.625204) (xy 296.473372 -200.145142) (xy 294.974772 -200.145142)
			)
		)
	)
	(zone
		(layer "In2.Cu")
		(hatch none 0.5)
		(connect_pads
			(clearance 0)
		)
		(min_thickness 0.25)
		(keepout
			(tracks not_allowed)
			(vias allowed)
			(pads allowed)
			(copperpour not_allowed)
			(footprints allowed)
		)
		(placement
			(enabled no)
			(sheetname "")
		)
		(fill
			(thermal_gap 0.5)
			(thermal_bridge_width 0.5)
			(island_removal_mode 0)
		)
		(polygon
			(pts
				(xy 276.442932 -287.175194) (xy 277.941532 -287.175194) (xy 277.941532 -287.695132) (xy 276.442932 -287.695132)
			)
		)
	)
	(zone
		(layer "In2.Cu")
		(hatch none 0.5)
		(connect_pads
			(clearance 0)
		)
		(min_thickness 0.25)
		(keepout
			(tracks not_allowed)
			(vias allowed)
			(pads allowed)
			(copperpour not_allowed)
			(footprints allowed)
		)
		(placement
			(enabled no)
			(sheetname "")
		)
		(fill
			(thermal_gap 0.5)
			(thermal_bridge_width 0.5)
			(island_removal_mode 0)
		)
		(polygon
			(pts
				(xy 283.986732 -296.525188) (xy 285.485332 -296.525188) (xy 285.485332 -297.045126) (xy 283.986732 -297.045126)
			)
		)
	)
	(zone
		(layer "In2.Cu")
		(hatch none 0.5)
		(connect_pads
			(clearance 0)
		)
		(min_thickness 0.25)
		(keepout
			(tracks not_allowed)
			(vias allowed)
			(pads allowed)
			(copperpour not_allowed)
			(footprints allowed)
		)
		(placement
			(enabled no)
			(sheetname "")
		)
		(fill
			(thermal_gap 0.5)
			(thermal_bridge_width 0.5)
			(island_removal_mode 0)
		)
		(polygon
			(pts
				(xy 441.7949 -208.975198) (xy 443.2935 -208.975198) (xy 443.2935 -209.495136) (xy 441.7949 -209.495136)
			)
		)
	)
	(zone
		(layer "In2.Cu")
		(hatch none 0.5)
		(connect_pads
			(clearance 0)
		)
		(min_thickness 0.25)
		(keepout
			(tracks not_allowed)
			(vias allowed)
			(pads allowed)
			(copperpour not_allowed)
			(footprints allowed)
		)
		(placement
			(enabled no)
			(sheetname "")
		)
		(fill
			(thermal_gap 0.5)
			(thermal_bridge_width 0.5)
			(island_removal_mode 0)
		)
		(polygon
			(pts
				(xy 283.986732 -316.925198) (xy 285.485332 -316.925198) (xy 285.485332 -317.445136) (xy 283.986732 -317.445136)
			)
		)
	)
	(zone
		(layer "In2.Cu")
		(hatch none 0.5)
		(connect_pads
			(clearance 0)
		)
		(min_thickness 0.25)
		(keepout
			(tracks not_allowed)
			(vias allowed)
			(pads allowed)
			(copperpour not_allowed)
			(footprints allowed)
		)
		(placement
			(enabled no)
			(sheetname "")
		)
		(fill
			(thermal_gap 0.5)
			(thermal_bridge_width 0.5)
			(island_removal_mode 0)
		)
		(polygon
			(pts
				(xy 299.07484 -223.425258) (xy 300.57344 -223.425258) (xy 300.57344 -223.945196) (xy 299.07484 -223.945196)
			)
		)
	)
	(zone
		(layer "In2.Cu")
		(hatch none 0.5)
		(connect_pads
			(clearance 0)
		)
		(min_thickness 0.25)
		(keepout
			(tracks not_allowed)
			(vias allowed)
			(pads allowed)
			(copperpour not_allowed)
			(footprints allowed)
		)
		(placement
			(enabled no)
			(sheetname "")
		)
		(fill
			(thermal_gap 0.5)
			(thermal_bridge_width 0.5)
			(island_removal_mode 0)
		)
		(polygon
			(pts
				(xy 287.430718 -304.17516) (xy 288.929318 -304.17516) (xy 288.929318 -304.695098) (xy 287.430718 -304.695098)
			)
		)
	)
	(zone
		(layer "In2.Cu")
		(hatch none 0.5)
		(connect_pads
			(clearance 0)
		)
		(min_thickness 0.25)
		(keepout
			(tracks not_allowed)
			(vias allowed)
			(pads allowed)
			(copperpour not_allowed)
			(footprints allowed)
		)
		(placement
			(enabled no)
			(sheetname "")
		)
		(fill
			(thermal_gap 0.5)
			(thermal_bridge_width 0.5)
			(island_removal_mode 0)
		)
		(polygon
			(pts
				(xy 434.250846 -197.925182) (xy 435.749446 -197.925182) (xy 435.749446 -198.44512) (xy 434.250846 -198.44512)
			)
		)
	)
	(zone
		(layer "In2.Cu")
		(hatch none 0.5)
		(connect_pads
			(clearance 0)
		)
		(min_thickness 0.25)
		(keepout
			(tracks not_allowed)
			(vias allowed)
			(pads allowed)
			(copperpour not_allowed)
			(footprints allowed)
		)
		(placement
			(enabled no)
			(sheetname "")
		)
		(fill
			(thermal_gap 0.5)
			(thermal_bridge_width 0.5)
			(island_removal_mode 0)
		)
		(polygon
			(pts
				(arc
					(start 308.292246 -379.360684)
					(mid 308.31217 -379.36992)
					(end 308.333902 -379.37313)
				)
				(arc
					(start 308.528466 -379.37313)
					(mid 308.582348 -379.350812)
					(end 308.604666 -379.29693)
				)
				(arc
					(start 308.604666 -378.61113)
					(mid 308.582348 -378.557248)
					(end 308.528466 -378.53493)
				)
				(arc
					(start 308.333902 -378.53493)
					(mid 308.312158 -378.538098)
					(end 308.292246 -378.547376)
				)
				(arc
					(start 307.996082 -378.740162)
					(mid 307.954398 -378.752384)
					(end 307.91277 -378.739908)
				)
				(arc
					(start 307.619146 -378.547376)
					(mid 307.599222 -378.53814)
					(end 307.57749 -378.53493)
				)
				(arc
					(start 307.382926 -378.53493)
					(mid 307.329044 -378.557248)
					(end 307.306726 -378.61113)
				)
				(arc
					(start 307.306726 -379.29693)
					(mid 307.329044 -379.350812)
					(end 307.382926 -379.37313)
				)
				(arc
					(start 307.57876 -379.37313)
					(mid 307.600504 -379.369962)
					(end 307.620416 -379.360684)
				)
				(arc
					(start 307.91404 -379.168152)
					(mid 307.955696 -379.15575)
					(end 307.997352 -379.168152)
				)
			)
		)
	)
	(zone
		(layer "In2.Cu")
		(hatch none 0.5)
		(connect_pads
			(clearance 0)
		)
		(min_thickness 0.25)
		(keepout
			(tracks not_allowed)
			(vias allowed)
			(pads allowed)
			(copperpour not_allowed)
			(footprints allowed)
		)
		(placement
			(enabled no)
			(sheetname "")
		)
		(fill
			(thermal_gap 0.5)
			(thermal_bridge_width 0.5)
			(island_removal_mode 0)
		)
		(polygon
			(pts
				(xy 31.946596 -241.275108) (xy 33.445196 -241.275108) (xy 33.445196 -241.795046) (xy 31.946596 -241.795046)
			)
		)
	)
	(zone
		(layer "In2.Cu")
		(hatch none 0.5)
		(connect_pads
			(clearance 0)
		)
		(min_thickness 0.25)
		(keepout
			(tracks not_allowed)
			(vias allowed)
			(pads allowed)
			(copperpour not_allowed)
			(footprints allowed)
		)
		(placement
			(enabled no)
			(sheetname "")
		)
		(fill
			(thermal_gap 0.5)
			(thermal_bridge_width 0.5)
			(island_removal_mode 0)
		)
		(polygon
			(pts
				(xy 36.046664 -232.775252) (xy 37.545264 -232.775252) (xy 37.545264 -233.29519) (xy 36.046664 -233.29519)
			)
		)
	)
	(zone
		(layer "In2.Cu")
		(hatch none 0.5)
		(connect_pads
			(clearance 0)
		)
		(min_thickness 0.25)
		(keepout
			(tracks not_allowed)
			(vias allowed)
			(pads allowed)
			(copperpour not_allowed)
			(footprints allowed)
		)
		(placement
			(enabled no)
			(sheetname "")
		)
		(fill
			(thermal_gap 0.5)
			(thermal_bridge_width 0.5)
			(island_removal_mode 0)
		)
		(polygon
			(pts
				(xy 430.80686 -245.52529) (xy 432.30546 -245.52529) (xy 432.30546 -246.045228) (xy 430.80686 -246.045228)
			)
		)
	)
	(zone
		(layer "In2.Cu")
		(hatch none 0.5)
		(connect_pads
			(clearance 0)
		)
		(min_thickness 0.25)
		(keepout
			(tracks not_allowed)
			(vias allowed)
			(pads allowed)
			(copperpour not_allowed)
			(footprints allowed)
		)
		(placement
			(enabled no)
			(sheetname "")
		)
		(fill
			(thermal_gap 0.5)
			(thermal_bridge_width 0.5)
			(island_removal_mode 0)
		)
		(polygon
			(pts
				(xy 445.894968 -275.275294) (xy 447.393568 -275.275294) (xy 447.393568 -275.795232) (xy 445.894968 -275.795232)
			)
		)
	)
	(zone
		(layer "In2.Cu")
		(hatch none 0.5)
		(connect_pads
			(clearance 0)
		)
		(min_thickness 0.25)
		(keepout
			(tracks allowed)
			(vias allowed)
			(pads allowed)
			(copperpour allowed)
			(footprints allowed)
		)
		(placement
			(enabled no)
			(sheetname "")
		)
		(fill
			(thermal_gap 0.5)
			(thermal_bridge_width 0.5)
			(island_removal_mode 0)
		)
		(polygon
			(pts
				(xy 356.810818 -326.257412) (xy 356.633018 -326.435212) (xy 356.633018 -327.705212) (xy 356.887018 -327.959212)
				(xy 356.887018 -332.810612) (xy 354.347018 -335.350612) (xy 354.347018 -344.393012) (xy 351.045018 -347.695012)
				(xy 344.390218 -347.695012) (xy 340.554818 -343.859612) (xy 323.562218 -343.859612) (xy 314.316618 -353.105212)
				(xy 314.316618 -358.032812) (xy 312.284618 -360.064812) (xy 311.954418 -360.064812) (xy 311.700418 -360.318812)
				(xy 311.700418 -361.207812) (xy 311.852818 -361.360212) (xy 312.183018 -361.360212) (xy 315.078618 -358.464612)
				(xy 315.078618 -353.486212) (xy 323.943218 -344.621612) (xy 340.199218 -344.621612) (xy 343.983818 -348.406212)
				(xy 351.426018 -348.406212) (xy 355.159818 -344.672412) (xy 355.159818 -335.604612) (xy 357.674418 -333.090012)
				(xy 357.674418 -326.943212) (xy 356.988618 -326.257412)
			)
		)
	)
	(zone
		(layer "In2.Cu")
		(hatch none 0.5)
		(connect_pads
			(clearance 0)
		)
		(min_thickness 0.25)
		(keepout
			(tracks not_allowed)
			(vias allowed)
			(pads allowed)
			(copperpour not_allowed)
			(footprints allowed)
		)
		(placement
			(enabled no)
			(sheetname "")
		)
		(fill
			(thermal_gap 0.5)
			(thermal_bridge_width 0.5)
			(island_removal_mode 0)
		)
		(polygon
			(pts
				(xy 419.162738 -283.77515) (xy 420.661338 -283.77515) (xy 420.661338 -284.295088) (xy 419.162738 -284.295088)
			)
		)
	)
	(zone
		(layer "In2.Cu")
		(hatch none 0.5)
		(connect_pads
			(clearance 0)
		)
		(min_thickness 0.25)
		(keepout
			(tracks not_allowed)
			(vias allowed)
			(pads allowed)
			(copperpour not_allowed)
			(footprints allowed)
		)
		(placement
			(enabled no)
			(sheetname "")
		)
		(fill
			(thermal_gap 0.5)
			(thermal_bridge_width 0.5)
			(island_removal_mode 0)
		)
		(polygon
			(pts
				(xy 306.618894 -247.225312) (xy 308.117494 -247.225312) (xy 308.117494 -247.74525) (xy 306.618894 -247.74525)
			)
		)
	)
	(zone
		(layer "In2.Cu")
		(hatch none 0.5)
		(connect_pads
			(clearance 0)
		)
		(min_thickness 0.25)
		(keepout
			(tracks not_allowed)
			(vias allowed)
			(pads allowed)
			(copperpour not_allowed)
			(footprints allowed)
		)
		(placement
			(enabled no)
			(sheetname "")
		)
		(fill
			(thermal_gap 0.5)
			(thermal_bridge_width 0.5)
			(island_removal_mode 0)
		)
		(polygon
			(pts
				(xy 283.986732 -254.025146) (xy 285.485332 -254.025146) (xy 285.485332 -254.545084) (xy 283.986732 -254.545084)
			)
		)
	)
	(zone
		(layer "In2.Cu")
		(hatch none 0.5)
		(connect_pads
			(clearance 0)
		)
		(min_thickness 0.25)
		(keepout
			(tracks allowed)
			(vias allowed)
			(pads allowed)
			(copperpour allowed)
			(footprints allowed)
		)
		(placement
			(enabled no)
			(sheetname "")
		)
		(fill
			(thermal_gap 0.5)
			(thermal_bridge_width 0.5)
			(island_removal_mode 0)
		)
		(polygon
			(pts
				(xy 10.72134 -411.718252) (xy 10.195052 -411.718252) (xy 10.195052 -411.183836) (xy 10.72134 -411.183836)
			)
		)
	)
	(zone
		(layer "In2.Cu")
		(hatch none 0.5)
		(connect_pads
			(clearance 0)
		)
		(min_thickness 0.25)
		(keepout
			(tracks not_allowed)
			(vias allowed)
			(pads allowed)
			(copperpour not_allowed)
			(footprints allowed)
		)
		(placement
			(enabled no)
			(sheetname "")
		)
		(fill
			(thermal_gap 0.5)
			(thermal_bridge_width 0.5)
			(island_removal_mode 0)
		)
		(polygon
			(pts
				(xy 453.438768 -310.975248) (xy 454.937368 -310.975248) (xy 454.937368 -311.495186) (xy 453.438768 -311.495186)
			)
		)
	)
	(zone
		(layer "In2.Cu")
		(hatch none 0.5)
		(connect_pads
			(clearance 0)
		)
		(min_thickness 0.25)
		(keepout
			(tracks not_allowed)
			(vias allowed)
			(pads allowed)
			(copperpour not_allowed)
			(footprints allowed)
		)
		(placement
			(enabled no)
			(sheetname "")
		)
		(fill
			(thermal_gap 0.5)
			(thermal_bridge_width 0.5)
			(island_removal_mode 0)
		)
		(polygon
			(pts
				(xy 58.678826 -228.525324) (xy 60.177426 -228.525324) (xy 60.177426 -229.045262) (xy 58.678826 -229.045262)
			)
		)
	)
	(zone
		(layer "In2.Cu")
		(hatch none 0.5)
		(connect_pads
			(clearance 0)
		)
		(min_thickness 0.25)
		(keepout
			(tracks allowed)
			(vias allowed)
			(pads allowed)
			(copperpour allowed)
			(footprints allowed)
		)
		(placement
			(enabled no)
			(sheetname "")
		)
		(fill
			(thermal_gap 0.5)
			(thermal_bridge_width 0.5)
			(island_removal_mode 0)
		)
		(polygon
			(pts
				(xy 36.468812 -417.72967) (xy 35.942524 -417.72967) (xy 35.942524 -416.384994) (xy 36.468812 -416.384994)
			)
		)
	)
	(zone
		(layer "In2.Cu")
		(hatch none 0.5)
		(connect_pads
			(clearance 0)
		)
		(min_thickness 0.25)
		(keepout
			(tracks not_allowed)
			(vias allowed)
			(pads allowed)
			(copperpour not_allowed)
			(footprints allowed)
		)
		(placement
			(enabled no)
			(sheetname "")
		)
		(fill
			(thermal_gap 0.5)
			(thermal_bridge_width 0.5)
			(island_removal_mode 0)
		)
		(polygon
			(pts
				(xy 36.046664 -299.925232) (xy 37.545264 -299.925232) (xy 37.545264 -300.44517) (xy 36.046664 -300.44517)
			)
		)
	)
	(zone
		(layer "In2.Cu")
		(hatch none 0.5)
		(connect_pads
			(clearance 0)
		)
		(min_thickness 0.25)
		(keepout
			(tracks not_allowed)
			(vias allowed)
			(pads allowed)
			(copperpour not_allowed)
			(footprints allowed)
		)
		(placement
			(enabled no)
			(sheetname "")
		)
		(fill
			(thermal_gap 0.5)
			(thermal_bridge_width 0.5)
			(island_removal_mode 0)
		)
		(polygon
			(pts
				(xy 171.22267 -229.375208) (xy 172.72127 -229.375208) (xy 172.72127 -229.895146) (xy 171.22267 -229.895146)
			)
		)
	)
	(zone
		(layer "In2.Cu")
		(hatch none 0.5)
		(connect_pads
			(clearance 0)
		)
		(min_thickness 0.25)
		(keepout
			(tracks not_allowed)
			(vias allowed)
			(pads allowed)
			(copperpour not_allowed)
			(footprints allowed)
		)
		(placement
			(enabled no)
			(sheetname "")
		)
		(fill
			(thermal_gap 0.5)
			(thermal_bridge_width 0.5)
			(island_removal_mode 0)
		)
		(polygon
			(pts
				(xy 272.342864 -276.125178) (xy 273.841464 -276.125178) (xy 273.841464 -276.645116) (xy 272.342864 -276.645116)
			)
		)
	)
	(zone
		(layer "In2.Cu")
		(hatch none 0.5)
		(connect_pads
			(clearance 0)
		)
		(min_thickness 0.25)
		(keepout
			(tracks not_allowed)
			(vias allowed)
			(pads allowed)
			(copperpour not_allowed)
			(footprints allowed)
		)
		(placement
			(enabled no)
			(sheetname "")
		)
		(fill
			(thermal_gap 0.5)
			(thermal_bridge_width 0.5)
			(island_removal_mode 0)
		)
		(polygon
			(pts
				(xy 449.3387 -314.375292) (xy 450.8373 -314.375292) (xy 450.8373 -314.89523) (xy 449.3387 -314.89523)
			)
		)
	)
	(zone
		(layer "In2.Cu")
		(hatch none 0.5)
		(connect_pads
			(clearance 0)
		)
		(min_thickness 0.25)
		(keepout
			(tracks not_allowed)
			(vias allowed)
			(pads allowed)
			(copperpour not_allowed)
			(footprints allowed)
		)
		(placement
			(enabled no)
			(sheetname "")
		)
		(fill
			(thermal_gap 0.5)
			(thermal_bridge_width 0.5)
			(island_removal_mode 0)
		)
		(polygon
			(pts
				(xy 51.134772 -208.125314) (xy 52.633372 -208.125314) (xy 52.633372 -208.645252) (xy 51.134772 -208.645252)
			)
		)
	)
	(zone
		(layer "In2.Cu")
		(hatch none 0.5)
		(connect_pads
			(clearance 0)
		)
		(min_thickness 0.25)
		(keepout
			(tracks not_allowed)
			(vias allowed)
			(pads allowed)
			(copperpour not_allowed)
			(footprints allowed)
		)
		(placement
			(enabled no)
			(sheetname "")
		)
		(fill
			(thermal_gap 0.5)
			(thermal_bridge_width 0.5)
			(island_removal_mode 0)
		)
		(polygon
			(pts
				(xy 441.7949 -304.17516) (xy 443.2935 -304.17516) (xy 443.2935 -304.695098) (xy 441.7949 -304.695098)
			)
		)
	)
	(zone
		(layer "In2.Cu")
		(hatch none 0.5)
		(connect_pads
			(clearance 0)
		)
		(min_thickness 0.25)
		(keepout
			(tracks not_allowed)
			(vias allowed)
			(pads allowed)
			(copperpour not_allowed)
			(footprints allowed)
		)
		(placement
			(enabled no)
			(sheetname "")
		)
		(fill
			(thermal_gap 0.5)
			(thermal_bridge_width 0.5)
			(island_removal_mode 0)
		)
		(polygon
			(pts
				(xy 197.954646 -288.875216) (xy 199.453246 -288.875216) (xy 199.453246 -289.395154) (xy 197.954646 -289.395154)
			)
		)
	)
	(zone
		(layer "In2.Cu")
		(hatch none 0.5)
		(connect_pads
			(clearance 0)
		)
		(min_thickness 0.25)
		(keepout
			(tracks not_allowed)
			(vias allowed)
			(pads allowed)
			(copperpour not_allowed)
			(footprints allowed)
		)
		(placement
			(enabled no)
			(sheetname "")
		)
		(fill
			(thermal_gap 0.5)
			(thermal_bridge_width 0.5)
			(island_removal_mode 0)
		)
		(polygon
			(pts
				(xy 415.718752 -242.125246) (xy 417.217352 -242.125246) (xy 417.217352 -242.645184) (xy 415.718752 -242.645184)
			)
		)
	)
	(zone
		(layer "In2.Cu")
		(hatch none 0.5)
		(connect_pads
			(clearance 0)
		)
		(min_thickness 0.25)
		(keepout
			(tracks not_allowed)
			(vias allowed)
			(pads allowed)
			(copperpour not_allowed)
			(footprints allowed)
		)
		(placement
			(enabled no)
			(sheetname "")
		)
		(fill
			(thermal_gap 0.5)
			(thermal_bridge_width 0.5)
			(island_removal_mode 0)
		)
		(polygon
			(pts
				(xy 20.95881 -252.325124) (xy 22.45741 -252.325124) (xy 22.45741 -252.845062) (xy 20.95881 -252.845062)
			)
		)
	)
	(zone
		(layer "In2.Cu")
		(hatch none 0.5)
		(connect_pads
			(clearance 0)
		)
		(min_thickness 0.25)
		(keepout
			(tracks not_allowed)
			(vias allowed)
			(pads allowed)
			(copperpour not_allowed)
			(footprints allowed)
		)
		(placement
			(enabled no)
			(sheetname "")
		)
		(fill
			(thermal_gap 0.5)
			(thermal_bridge_width 0.5)
			(island_removal_mode 0)
		)
		(polygon
			(pts
				(xy 193.854578 -241.275108) (xy 195.353178 -241.275108) (xy 195.353178 -241.795046) (xy 193.854578 -241.795046)
			)
		)
	)
	(zone
		(layer "In2.Cu")
		(hatch none 0.5)
		(connect_pads
			(clearance 0)
		)
		(min_thickness 0.25)
		(keepout
			(tracks not_allowed)
			(vias allowed)
			(pads allowed)
			(copperpour not_allowed)
			(footprints allowed)
		)
		(placement
			(enabled no)
			(sheetname "")
		)
		(fill
			(thermal_gap 0.5)
			(thermal_bridge_width 0.5)
			(island_removal_mode 0)
		)
		(polygon
			(pts
				(xy 186.310778 -246.375174) (xy 187.809378 -246.375174) (xy 187.809378 -246.895112) (xy 186.310778 -246.895112)
			)
		)
	)
	(zone
		(layer "In2.Cu")
		(hatch none 0.5)
		(connect_pads
			(clearance 0)
		)
		(min_thickness 0.25)
		(keepout
			(tracks not_allowed)
			(vias allowed)
			(pads allowed)
			(copperpour not_allowed)
			(footprints allowed)
		)
		(placement
			(enabled no)
			(sheetname "")
		)
		(fill
			(thermal_gap 0.5)
			(thermal_bridge_width 0.5)
			(island_removal_mode 0)
		)
		(polygon
			(pts
				(xy 175.322738 -210.67522) (xy 176.821338 -210.67522) (xy 176.821338 -211.195158) (xy 175.322738 -211.195158)
			)
		)
	)
	(zone
		(layer "In2.Cu")
		(hatch none 0.5)
		(connect_pads
			(clearance 0)
		)
		(min_thickness 0.25)
		(keepout
			(tracks not_allowed)
			(vias allowed)
			(pads allowed)
			(copperpour not_allowed)
			(footprints allowed)
		)
		(placement
			(enabled no)
			(sheetname "")
		)
		(fill
			(thermal_gap 0.5)
			(thermal_bridge_width 0.5)
			(island_removal_mode 0)
		)
		(polygon
			(pts
				(xy 291.530786 -217.475308) (xy 293.029386 -217.475308) (xy 293.029386 -217.995246) (xy 291.530786 -217.995246)
			)
		)
	)
	(zone
		(layer "In2.Cu")
		(hatch none 0.5)
		(connect_pads
			(clearance 0)
		)
		(min_thickness 0.25)
		(keepout
			(tracks not_allowed)
			(vias allowed)
			(pads allowed)
			(copperpour not_allowed)
			(footprints allowed)
		)
		(placement
			(enabled no)
			(sheetname "")
		)
		(fill
			(thermal_gap 0.5)
			(thermal_bridge_width 0.5)
			(island_removal_mode 0)
		)
		(polygon
			(pts
				(xy 302.518826 -235.325158) (xy 304.017426 -235.325158) (xy 304.017426 -235.845096) (xy 302.518826 -235.845096)
			)
		)
	)
	(zone
		(layer "In2.Cu")
		(hatch none 0.5)
		(connect_pads
			(clearance 0)
		)
		(min_thickness 0.25)
		(keepout
			(tracks not_allowed)
			(vias allowed)
			(pads allowed)
			(copperpour not_allowed)
			(footprints allowed)
		)
		(placement
			(enabled no)
			(sheetname "")
		)
		(fill
			(thermal_gap 0.5)
			(thermal_bridge_width 0.5)
			(island_removal_mode 0)
		)
		(polygon
			(pts
				(xy 54.578758 -282.075128) (xy 56.077358 -282.075128) (xy 56.077358 -282.595066) (xy 54.578758 -282.595066)
			)
		)
	)
	(zone
		(layer "In2.Cu")
		(hatch none 0.5)
		(connect_pads
			(clearance 0)
		)
		(min_thickness 0.25)
		(keepout
			(tracks not_allowed)
			(vias allowed)
			(pads allowed)
			(copperpour not_allowed)
			(footprints allowed)
		)
		(placement
			(enabled no)
			(sheetname "")
		)
		(fill
			(thermal_gap 0.5)
			(thermal_bridge_width 0.5)
			(island_removal_mode 0)
		)
		(polygon
			(pts
				(xy 279.886664 -265.075162) (xy 281.385264 -265.075162) (xy 281.385264 -265.5951) (xy 279.886664 -265.5951)
			)
		)
	)
	(zone
		(layer "In2.Cu")
		(hatch none 0.5)
		(connect_pads
			(clearance 0)
		)
		(min_thickness 0.25)
		(keepout
			(tracks not_allowed)
			(vias allowed)
			(pads allowed)
			(copperpour not_allowed)
			(footprints allowed)
		)
		(placement
			(enabled no)
			(sheetname "")
		)
		(fill
			(thermal_gap 0.5)
			(thermal_bridge_width 0.5)
			(island_removal_mode 0)
		)
		(polygon
			(pts
				(xy 16.858742 -316.075314) (xy 18.357342 -316.075314) (xy 18.357342 -316.595252) (xy 16.858742 -316.595252)
			)
		)
	)
	(zone
		(layer "In2.Cu")
		(hatch none 0.5)
		(connect_pads
			(clearance 0)
		)
		(min_thickness 0.25)
		(keepout
			(tracks not_allowed)
			(vias allowed)
			(pads allowed)
			(copperpour not_allowed)
			(footprints allowed)
		)
		(placement
			(enabled no)
			(sheetname "")
		)
		(fill
			(thermal_gap 0.5)
			(thermal_bridge_width 0.5)
			(island_removal_mode 0)
		)
		(polygon
			(pts
				(xy 272.342864 -233.625136) (xy 273.841464 -233.625136) (xy 273.841464 -234.145074) (xy 272.342864 -234.145074)
			)
		)
	)
	(zone
		(layer "In2.Cu")
		(hatch none 0.5)
		(connect_pads
			(clearance 0)
		)
		(min_thickness 0.25)
		(keepout
			(tracks allowed)
			(vias allowed)
			(pads allowed)
			(copperpour allowed)
			(footprints allowed)
		)
		(placement
			(enabled no)
			(sheetname "")
		)
		(fill
			(thermal_gap 0.5)
			(thermal_bridge_width 0.5)
			(island_removal_mode 0)
		)
		(polygon
			(pts
				(xy 399.896838 -172.622972) (xy 399.896838 -173.400212) (xy 399.660618 -173.400212) (xy 399.660618 -172.622972)
			)
		)
	)
	(zone
		(layer "In2.Cu")
		(hatch none 0.5)
		(connect_pads
			(clearance 0)
		)
		(min_thickness 0.25)
		(keepout
			(tracks not_allowed)
			(vias allowed)
			(pads allowed)
			(copperpour not_allowed)
			(footprints allowed)
		)
		(placement
			(enabled no)
			(sheetname "")
		)
		(fill
			(thermal_gap 0.5)
			(thermal_bridge_width 0.5)
			(island_removal_mode 0)
		)
		(polygon
			(pts
				(xy 415.718752 -204.72527) (xy 417.217352 -204.72527) (xy 417.217352 -205.245208) (xy 415.718752 -205.245208)
			)
		)
	)
	(zone
		(layer "In2.Cu")
		(hatch none 0.5)
		(connect_pads
			(clearance 0)
		)
		(min_thickness 0.25)
		(keepout
			(tracks allowed)
			(vias allowed)
			(pads allowed)
			(copperpour allowed)
			(footprints allowed)
		)
		(placement
			(enabled no)
			(sheetname "")
		)
		(fill
			(thermal_gap 0.5)
			(thermal_bridge_width 0.5)
			(island_removal_mode 0)
		)
		(polygon
			(pts
				(xy 336.48777 -338.111592) (xy 336.48777 -337.489292) (xy 337.03895 -337.489292) (xy 337.03895 -338.111592)
			)
		)
	)
	(zone
		(layer "In2.Cu")
		(hatch none 0.5)
		(connect_pads
			(clearance 0)
		)
		(min_thickness 0.25)
		(keepout
			(tracks not_allowed)
			(vias allowed)
			(pads allowed)
			(copperpour not_allowed)
			(footprints allowed)
		)
		(placement
			(enabled no)
			(sheetname "")
		)
		(fill
			(thermal_gap 0.5)
			(thermal_bridge_width 0.5)
			(island_removal_mode 0)
		)
		(polygon
			(pts
				(xy 279.886664 -238.725202) (xy 281.385264 -238.725202) (xy 281.385264 -239.24514) (xy 279.886664 -239.24514)
			)
		)
	)
	(zone
		(layer "In2.Cu")
		(hatch none 0.5)
		(connect_pads
			(clearance 0)
		)
		(min_thickness 0.25)
		(keepout
			(tracks not_allowed)
			(vias allowed)
			(pads allowed)
			(copperpour not_allowed)
			(footprints allowed)
		)
		(placement
			(enabled no)
			(sheetname "")
		)
		(fill
			(thermal_gap 0.5)
			(thermal_bridge_width 0.5)
			(island_removal_mode 0)
		)
		(polygon
			(pts
				(xy 423.262806 -231.07523) (xy 424.761406 -231.07523) (xy 424.761406 -231.595168) (xy 423.262806 -231.595168)
			)
		)
	)
	(zone
		(layer "In2.Cu")
		(hatch none 0.5)
		(connect_pads
			(clearance 0)
		)
		(min_thickness 0.25)
		(keepout
			(tracks not_allowed)
			(vias allowed)
			(pads allowed)
			(copperpour not_allowed)
			(footprints allowed)
		)
		(placement
			(enabled no)
			(sheetname "")
		)
		(fill
			(thermal_gap 0.5)
			(thermal_bridge_width 0.5)
			(island_removal_mode 0)
		)
		(polygon
			(pts
				(xy 291.530786 -219.17533) (xy 293.029386 -219.17533) (xy 293.029386 -219.695268) (xy 291.530786 -219.695268)
			)
		)
	)
	(zone
		(layer "In2.Cu")
		(hatch none 0.5)
		(connect_pads
			(clearance 0)
		)
		(min_thickness 0.25)
		(keepout
			(tracks not_allowed)
			(vias allowed)
			(pads allowed)
			(copperpour not_allowed)
			(footprints allowed)
		)
		(placement
			(enabled no)
			(sheetname "")
		)
		(fill
			(thermal_gap 0.5)
			(thermal_bridge_width 0.5)
			(island_removal_mode 0)
		)
		(polygon
			(pts
				(xy 419.162738 -244.675152) (xy 420.661338 -244.675152) (xy 420.661338 -245.19509) (xy 419.162738 -245.19509)
			)
		)
	)
	(zone
		(layer "In2.Cu")
		(hatch none 0.5)
		(connect_pads
			(clearance 0)
		)
		(min_thickness 0.25)
		(keepout
			(tracks not_allowed)
			(vias allowed)
			(pads allowed)
			(copperpour not_allowed)
			(footprints allowed)
		)
		(placement
			(enabled no)
			(sheetname "")
		)
		(fill
			(thermal_gap 0.5)
			(thermal_bridge_width 0.5)
			(island_removal_mode 0)
		)
		(polygon
			(pts
				(xy 51.134772 -293.975282) (xy 52.633372 -293.975282) (xy 52.633372 -294.49522) (xy 51.134772 -294.49522)
			)
		)
	)
	(zone
		(layer "In2.Cu")
		(hatch none 0.5)
		(connect_pads
			(clearance 0)
		)
		(min_thickness 0.25)
		(keepout
			(tracks not_allowed)
			(vias allowed)
			(pads allowed)
			(copperpour not_allowed)
			(footprints allowed)
		)
		(placement
			(enabled no)
			(sheetname "")
		)
		(fill
			(thermal_gap 0.5)
			(thermal_bridge_width 0.5)
			(island_removal_mode 0)
		)
		(polygon
			(pts
				(xy 190.410846 -271.87525) (xy 191.909446 -271.87525) (xy 191.909446 -272.395188) (xy 190.410846 -272.395188)
			)
		)
	)
	(zone
		(layer "In2.Cu")
		(hatch none 0.5)
		(connect_pads
			(clearance 0)
		)
		(min_thickness 0.25)
		(keepout
			(tracks not_allowed)
			(vias allowed)
			(pads allowed)
			(copperpour not_allowed)
			(footprints allowed)
		)
		(placement
			(enabled no)
			(sheetname "")
		)
		(fill
			(thermal_gap 0.5)
			(thermal_bridge_width 0.5)
			(island_removal_mode 0)
		)
		(polygon
			(pts
				(xy 438.350914 -237.875318) (xy 439.849514 -237.875318) (xy 439.849514 -238.395256) (xy 438.350914 -238.395256)
			)
		)
	)
	(zone
		(layer "In2.Cu")
		(hatch none 0.5)
		(connect_pads
			(clearance 0)
		)
		(min_thickness 0.25)
		(keepout
			(tracks not_allowed)
			(vias allowed)
			(pads allowed)
			(copperpour not_allowed)
			(footprints allowed)
		)
		(placement
			(enabled no)
			(sheetname "")
		)
		(fill
			(thermal_gap 0.5)
			(thermal_bridge_width 0.5)
			(island_removal_mode 0)
		)
		(polygon
			(pts
				(xy 449.3387 -280.375106) (xy 450.8373 -280.375106) (xy 450.8373 -280.895044) (xy 449.3387 -280.895044)
			)
		)
	)
	(zone
		(layer "In2.Cu")
		(hatch none 0.5)
		(connect_pads
			(clearance 0)
		)
		(min_thickness 0.25)
		(keepout
			(tracks allowed)
			(vias allowed)
			(pads allowed)
			(copperpour allowed)
			(footprints allowed)
		)
		(placement
			(enabled no)
			(sheetname "")
		)
		(fill
			(thermal_gap 0.5)
			(thermal_bridge_width 0.5)
			(island_removal_mode 0)
		)
		(polygon
			(pts
				(xy 60.00369 -350.486472) (xy 60.00369 -351.238312) (xy 59.84621 -351.238312) (xy 59.84621 -350.486472)
			)
		)
	)
	(zone
		(layer "In2.Cu")
		(hatch none 0.5)
		(connect_pads
			(clearance 0)
		)
		(min_thickness 0.25)
		(keepout
			(tracks not_allowed)
			(vias allowed)
			(pads allowed)
			(copperpour not_allowed)
			(footprints allowed)
		)
		(placement
			(enabled no)
			(sheetname "")
		)
		(fill
			(thermal_gap 0.5)
			(thermal_bridge_width 0.5)
			(island_removal_mode 0)
		)
		(polygon
			(pts
				(xy 419.162738 -237.02518) (xy 420.661338 -237.02518) (xy 420.661338 -237.545118) (xy 419.162738 -237.545118)
			)
		)
	)
	(zone
		(layer "In2.Cu")
		(hatch none 0.5)
		(connect_pads
			(clearance 0)
		)
		(min_thickness 0.25)
		(keepout
			(tracks not_allowed)
			(vias allowed)
			(pads allowed)
			(copperpour not_allowed)
			(footprints allowed)
		)
		(placement
			(enabled no)
			(sheetname "")
		)
		(fill
			(thermal_gap 0.5)
			(thermal_bridge_width 0.5)
			(island_removal_mode 0)
		)
		(polygon
			(pts
				(xy 167.778684 -243.825268) (xy 169.277284 -243.825268) (xy 169.277284 -244.345206) (xy 167.778684 -244.345206)
			)
		)
	)
	(zone
		(layer "In2.Cu")
		(hatch none 0.5)
		(connect_pads
			(clearance 0)
		)
		(min_thickness 0.25)
		(keepout
			(tracks allowed)
			(vias allowed)
			(pads allowed)
			(copperpour allowed)
			(footprints allowed)
		)
		(placement
			(enabled no)
			(sheetname "")
		)
		(fill
			(thermal_gap 0.5)
			(thermal_bridge_width 0.5)
			(island_removal_mode 0)
		)
		(polygon
			(pts
				(xy 91.83497 -335.944972) (xy 91.83497 -336.762852) (xy 91.70289 -336.762852) (xy 91.70289 -335.944972)
			)
		)
	)
	(zone
		(layer "In2.Cu")
		(hatch none 0.5)
		(connect_pads
			(clearance 0)
		)
		(min_thickness 0.25)
		(keepout
			(tracks not_allowed)
			(vias allowed)
			(pads allowed)
			(copperpour not_allowed)
			(footprints allowed)
		)
		(placement
			(enabled no)
			(sheetname "")
		)
		(fill
			(thermal_gap 0.5)
			(thermal_bridge_width 0.5)
			(island_removal_mode 0)
		)
		(polygon
			(pts
				(xy 434.250846 -239.57534) (xy 435.749446 -239.57534) (xy 435.749446 -240.095278) (xy 434.250846 -240.095278)
			)
		)
	)
	(zone
		(layer "In2.Cu")
		(hatch none 0.5)
		(connect_pads
			(clearance 0)
		)
		(min_thickness 0.25)
		(keepout
			(tracks not_allowed)
			(vias allowed)
			(pads allowed)
			(copperpour not_allowed)
			(footprints allowed)
		)
		(placement
			(enabled no)
			(sheetname "")
		)
		(fill
			(thermal_gap 0.5)
			(thermal_bridge_width 0.5)
			(island_removal_mode 0)
		)
		(polygon
			(pts
				(xy 20.95881 -287.175194) (xy 22.45741 -287.175194) (xy 22.45741 -287.695132) (xy 20.95881 -287.695132)
			)
		)
	)
	(zone
		(layer "In2.Cu")
		(hatch none 0.5)
		(connect_pads
			(clearance 0)
		)
		(min_thickness 0.25)
		(keepout
			(tracks not_allowed)
			(vias allowed)
			(pads allowed)
			(copperpour not_allowed)
			(footprints allowed)
		)
		(placement
			(enabled no)
			(sheetname "")
		)
		(fill
			(thermal_gap 0.5)
			(thermal_bridge_width 0.5)
			(island_removal_mode 0)
		)
		(polygon
			(pts
				(xy 283.986732 -248.925334) (xy 285.485332 -248.925334) (xy 285.485332 -249.445272) (xy 283.986732 -249.445272)
			)
		)
	)
	(zone
		(layer "In2.Cu")
		(hatch none 0.5)
		(connect_pads
			(clearance 0)
		)
		(min_thickness 0.25)
		(keepout
			(tracks not_allowed)
			(vias allowed)
			(pads allowed)
			(copperpour not_allowed)
			(footprints allowed)
		)
		(placement
			(enabled no)
			(sheetname "")
		)
		(fill
			(thermal_gap 0.5)
			(thermal_bridge_width 0.5)
			(island_removal_mode 0)
		)
		(polygon
			(pts
				(xy 12.445492 -16.036036) (xy 12.445492 -14.609318) (xy 13.106146 -14.609318) (xy 13.106146 -16.036036)
			)
		)
	)
	(zone
		(layer "In2.Cu")
		(hatch none 0.5)
		(connect_pads
			(clearance 0)
		)
		(min_thickness 0.25)
		(keepout
			(tracks not_allowed)
			(vias allowed)
			(pads allowed)
			(copperpour not_allowed)
			(footprints allowed)
		)
		(placement
			(enabled no)
			(sheetname "")
		)
		(fill
			(thermal_gap 0.5)
			(thermal_bridge_width 0.5)
			(island_removal_mode 0)
		)
		(polygon
			(pts
				(xy 283.986732 -219.17533) (xy 285.485332 -219.17533) (xy 285.485332 -219.695268) (xy 283.986732 -219.695268)
			)
		)
	)
	(zone
		(layer "In2.Cu")
		(hatch none 0.5)
		(connect_pads
			(clearance 0)
		)
		(min_thickness 0.25)
		(keepout
			(tracks not_allowed)
			(vias allowed)
			(pads allowed)
			(copperpour not_allowed)
			(footprints allowed)
		)
		(placement
			(enabled no)
			(sheetname "")
		)
		(fill
			(thermal_gap 0.5)
			(thermal_bridge_width 0.5)
			(island_removal_mode 0)
		)
		(polygon
			(pts
				(xy 20.95881 -232.775252) (xy 22.45741 -232.775252) (xy 22.45741 -233.29519) (xy 20.95881 -233.29519)
			)
		)
	)
	(zone
		(layer "In2.Cu")
		(hatch none 0.5)
		(connect_pads
			(clearance 0)
		)
		(min_thickness 0.25)
		(keepout
			(tracks not_allowed)
			(vias allowed)
			(pads allowed)
			(copperpour not_allowed)
			(footprints allowed)
		)
		(placement
			(enabled no)
			(sheetname "")
		)
		(fill
			(thermal_gap 0.5)
			(thermal_bridge_width 0.5)
			(island_removal_mode 0)
		)
		(polygon
			(pts
				(xy 445.894968 -229.375208) (xy 447.393568 -229.375208) (xy 447.393568 -229.895146) (xy 445.894968 -229.895146)
			)
		)
	)
	(zone
		(layer "In2.Cu")
		(hatch none 0.5)
		(connect_pads
			(clearance 0)
		)
		(min_thickness 0.25)
		(keepout
			(tracks not_allowed)
			(vias allowed)
			(pads allowed)
			(copperpour not_allowed)
			(footprints allowed)
		)
		(placement
			(enabled no)
			(sheetname "")
		)
		(fill
			(thermal_gap 0.5)
			(thermal_bridge_width 0.5)
			(island_removal_mode 0)
		)
		(polygon
			(pts
				(xy 16.858742 -207.275176) (xy 18.357342 -207.275176) (xy 18.357342 -207.795114) (xy 16.858742 -207.795114)
			)
		)
	)
	(zone
		(layer "In2.Cu")
		(hatch none 0.5)
		(connect_pads
			(clearance 0)
		)
		(min_thickness 0.25)
		(keepout
			(tracks not_allowed)
			(vias allowed)
			(pads allowed)
			(copperpour not_allowed)
			(footprints allowed)
		)
		(placement
			(enabled no)
			(sheetname "")
		)
		(fill
			(thermal_gap 0.5)
			(thermal_bridge_width 0.5)
			(island_removal_mode 0)
		)
		(polygon
			(pts
				(xy 268.898878 -240.425224) (xy 270.397478 -240.425224) (xy 270.397478 -240.945162) (xy 268.898878 -240.945162)
			)
		)
	)
	(zone
		(layer "In2.Cu")
		(hatch none 0.5)
		(connect_pads
			(clearance 0)
		)
		(min_thickness 0.25)
		(keepout
			(tracks not_allowed)
			(vias allowed)
			(pads allowed)
			(copperpour not_allowed)
			(footprints allowed)
		)
		(placement
			(enabled no)
			(sheetname "")
		)
		(fill
			(thermal_gap 0.5)
			(thermal_bridge_width 0.5)
			(island_removal_mode 0)
		)
		(polygon
			(pts
				(xy 268.898878 -292.27526) (xy 270.397478 -292.27526) (xy 270.397478 -292.795198) (xy 268.898878 -292.795198)
			)
		)
	)
	(zone
		(layer "In2.Cu")
		(hatch none 0.5)
		(connect_pads
			(clearance 0)
		)
		(min_thickness 0.25)
		(keepout
			(tracks not_allowed)
			(vias allowed)
			(pads allowed)
			(copperpour not_allowed)
			(footprints allowed)
		)
		(placement
			(enabled no)
			(sheetname "")
		)
		(fill
			(thermal_gap 0.5)
			(thermal_bridge_width 0.5)
			(island_removal_mode 0)
		)
		(polygon
			(pts
				(xy 175.322738 -212.375242) (xy 176.821338 -212.375242) (xy 176.821338 -212.89518) (xy 175.322738 -212.89518)
			)
		)
	)
	(zone
		(layer "In2.Cu")
		(hatch none 0.5)
		(connect_pads
			(clearance 0)
		)
		(min_thickness 0.25)
		(keepout
			(tracks not_allowed)
			(vias allowed)
			(pads allowed)
			(copperpour not_allowed)
			(footprints allowed)
		)
		(placement
			(enabled no)
			(sheetname "")
		)
		(fill
			(thermal_gap 0.5)
			(thermal_bridge_width 0.5)
			(island_removal_mode 0)
		)
		(polygon
			(pts
				(xy 415.718752 -271.87525) (xy 417.217352 -271.87525) (xy 417.217352 -272.395188) (xy 415.718752 -272.395188)
			)
		)
	)
	(zone
		(layer "In2.Cu")
		(hatch none 0.5)
		(connect_pads
			(clearance 0)
		)
		(min_thickness 0.25)
		(keepout
			(tracks not_allowed)
			(vias allowed)
			(pads allowed)
			(copperpour not_allowed)
			(footprints allowed)
		)
		(placement
			(enabled no)
			(sheetname "")
		)
		(fill
			(thermal_gap 0.5)
			(thermal_bridge_width 0.5)
			(island_removal_mode 0)
		)
		(polygon
			(pts
				(xy 291.530786 -206.425292) (xy 293.029386 -206.425292) (xy 293.029386 -206.94523) (xy 291.530786 -206.94523)
			)
		)
	)
	(zone
		(layer "In2.Cu")
		(hatch none 0.5)
		(connect_pads
			(clearance 0)
		)
		(min_thickness 0.25)
		(keepout
			(tracks not_allowed)
			(vias allowed)
			(pads allowed)
			(copperpour not_allowed)
			(footprints allowed)
		)
		(placement
			(enabled no)
			(sheetname "")
		)
		(fill
			(thermal_gap 0.5)
			(thermal_bridge_width 0.5)
			(island_removal_mode 0)
		)
		(polygon
			(pts
				(xy 276.442932 -214.075264) (xy 277.941532 -214.075264) (xy 277.941532 -214.595202) (xy 276.442932 -214.595202)
			)
		)
	)
	(zone
		(layer "In2.Cu")
		(hatch none 0.5)
		(connect_pads
			(clearance 0)
		)
		(min_thickness 0.25)
		(keepout
			(tracks not_allowed)
			(vias allowed)
			(pads allowed)
			(copperpour not_allowed)
			(footprints allowed)
		)
		(placement
			(enabled no)
			(sheetname "")
		)
		(fill
			(thermal_gap 0.5)
			(thermal_bridge_width 0.5)
			(island_removal_mode 0)
		)
		(polygon
			(pts
				(xy 283.986732 -264.225278) (xy 285.485332 -264.225278) (xy 285.485332 -264.745216) (xy 283.986732 -264.745216)
			)
		)
	)
	(zone
		(layer "In2.Cu")
		(hatch none 0.5)
		(connect_pads
			(clearance 0)
		)
		(min_thickness 0.25)
		(keepout
			(tracks not_allowed)
			(vias allowed)
			(pads allowed)
			(copperpour not_allowed)
			(footprints allowed)
		)
		(placement
			(enabled no)
			(sheetname "")
		)
		(fill
			(thermal_gap 0.5)
			(thermal_bridge_width 0.5)
			(island_removal_mode 0)
		)
		(polygon
			(pts
				(xy 453.438768 -287.175194) (xy 454.937368 -287.175194) (xy 454.937368 -287.695132) (xy 453.438768 -287.695132)
			)
		)
	)
	(zone
		(layer "In2.Cu")
		(hatch none 0.5)
		(connect_pads
			(clearance 0)
		)
		(min_thickness 0.25)
		(keepout
			(tracks not_allowed)
			(vias allowed)
			(pads allowed)
			(copperpour not_allowed)
			(footprints allowed)
		)
		(placement
			(enabled no)
			(sheetname "")
		)
		(fill
			(thermal_gap 0.5)
			(thermal_bridge_width 0.5)
			(island_removal_mode 0)
		)
		(polygon
			(pts
				(xy 51.134772 -210.67522) (xy 52.633372 -210.67522) (xy 52.633372 -211.195158) (xy 51.134772 -211.195158)
			)
		)
	)
	(zone
		(layer "In2.Cu")
		(hatch none 0.5)
		(connect_pads
			(clearance 0)
		)
		(min_thickness 0.25)
		(keepout
			(tracks not_allowed)
			(vias allowed)
			(pads allowed)
			(copperpour not_allowed)
			(footprints allowed)
		)
		(placement
			(enabled no)
			(sheetname "")
		)
		(fill
			(thermal_gap 0.5)
			(thermal_bridge_width 0.5)
			(island_removal_mode 0)
		)
		(polygon
			(pts
				(xy 28.50261 -226.825302) (xy 30.00121 -226.825302) (xy 30.00121 -227.34524) (xy 28.50261 -227.34524)
			)
		)
	)
	(zone
		(layer "In2.Cu")
		(hatch none 0.5)
		(connect_pads
			(clearance 0)
		)
		(min_thickness 0.25)
		(keepout
			(tracks not_allowed)
			(vias allowed)
			(pads allowed)
			(copperpour not_allowed)
			(footprints allowed)
		)
		(placement
			(enabled no)
			(sheetname "")
		)
		(fill
			(thermal_gap 0.5)
			(thermal_bridge_width 0.5)
			(island_removal_mode 0)
		)
		(polygon
			(pts
				(xy 28.50261 -247.225312) (xy 30.00121 -247.225312) (xy 30.00121 -247.74525) (xy 28.50261 -247.74525)
			)
		)
	)
	(zone
		(layer "In2.Cu")
		(hatch none 0.5)
		(connect_pads
			(clearance 0)
		)
		(min_thickness 0.25)
		(keepout
			(tracks not_allowed)
			(vias allowed)
			(pads allowed)
			(copperpour not_allowed)
			(footprints allowed)
		)
		(placement
			(enabled no)
			(sheetname "")
		)
		(fill
			(thermal_gap 0.5)
			(thermal_bridge_width 0.5)
			(island_removal_mode 0)
		)
		(polygon
			(pts
				(xy 434.250846 -274.425156) (xy 435.749446 -274.425156) (xy 435.749446 -274.945094) (xy 434.250846 -274.945094)
			)
		)
	)
	(zone
		(layer "In2.Cu")
		(hatch none 0.5)
		(connect_pads
			(clearance 0)
		)
		(min_thickness 0.25)
		(keepout
			(tracks not_allowed)
			(vias allowed)
			(pads allowed)
			(copperpour not_allowed)
			(footprints allowed)
		)
		(placement
			(enabled no)
			(sheetname "")
		)
		(fill
			(thermal_gap 0.5)
			(thermal_bridge_width 0.5)
			(island_removal_mode 0)
		)
		(polygon
			(pts
				(xy 294.974772 -291.425122) (xy 296.473372 -291.425122) (xy 296.473372 -291.94506) (xy 294.974772 -291.94506)
			)
		)
	)
	(zone
		(layer "In2.Cu")
		(hatch none 0.5)
		(connect_pads
			(clearance 0)
		)
		(min_thickness 0.25)
		(keepout
			(tracks not_allowed)
			(vias allowed)
			(pads allowed)
			(copperpour not_allowed)
			(footprints allowed)
		)
		(placement
			(enabled no)
			(sheetname "")
		)
		(fill
			(thermal_gap 0.5)
			(thermal_bridge_width 0.5)
			(island_removal_mode 0)
		)
		(polygon
			(pts
				(xy 197.954646 -226.825302) (xy 199.453246 -226.825302) (xy 199.453246 -227.34524) (xy 197.954646 -227.34524)
			)
		)
	)
	(zone
		(layer "In2.Cu")
		(hatch none 0.5)
		(connect_pads
			(clearance 0)
		)
		(min_thickness 0.25)
		(keepout
			(tracks not_allowed)
			(vias allowed)
			(pads allowed)
			(copperpour not_allowed)
			(footprints allowed)
		)
		(placement
			(enabled no)
			(sheetname "")
		)
		(fill
			(thermal_gap 0.5)
			(thermal_bridge_width 0.5)
			(island_removal_mode 0)
		)
		(polygon
			(pts
				(xy 58.678826 -293.975282) (xy 60.177426 -293.975282) (xy 60.177426 -294.49522) (xy 58.678826 -294.49522)
			)
		)
	)
	(zone
		(layer "In2.Cu")
		(hatch none 0.5)
		(connect_pads
			(clearance 0)
		)
		(min_thickness 0.25)
		(keepout
			(tracks not_allowed)
			(vias allowed)
			(pads allowed)
			(copperpour not_allowed)
			(footprints allowed)
		)
		(placement
			(enabled no)
			(sheetname "")
		)
		(fill
			(thermal_gap 0.5)
			(thermal_bridge_width 0.5)
			(island_removal_mode 0)
		)
		(polygon
			(pts
				(xy 47.034704 -304.17516) (xy 48.533304 -304.17516) (xy 48.533304 -304.695098) (xy 47.034704 -304.695098)
			)
		)
	)
	(zone
		(layer "In2.Cu")
		(hatch none 0.5)
		(connect_pads
			(clearance 0)
		)
		(min_thickness 0.25)
		(keepout
			(tracks not_allowed)
			(vias allowed)
			(pads allowed)
			(copperpour not_allowed)
			(footprints allowed)
		)
		(placement
			(enabled no)
			(sheetname "")
		)
		(fill
			(thermal_gap 0.5)
			(thermal_bridge_width 0.5)
			(island_removal_mode 0)
		)
		(polygon
			(pts
				(xy 283.986732 -284.625288) (xy 285.485332 -284.625288) (xy 285.485332 -285.145226) (xy 283.986732 -285.145226)
			)
		)
	)
	(zone
		(layer "In2.Cu")
		(hatch none 0.5)
		(connect_pads
			(clearance 0)
		)
		(min_thickness 0.25)
		(keepout
			(tracks not_allowed)
			(vias allowed)
			(pads allowed)
			(copperpour not_allowed)
			(footprints allowed)
		)
		(placement
			(enabled no)
			(sheetname "")
		)
		(fill
			(thermal_gap 0.5)
			(thermal_bridge_width 0.5)
			(island_removal_mode 0)
		)
		(polygon
			(pts
				(xy 51.134772 -198.77532) (xy 52.633372 -198.77532) (xy 52.633372 -199.295258) (xy 51.134772 -199.295258)
			)
		)
	)
	(zone
		(layer "In2.Cu")
		(hatch none 0.5)
		(connect_pads
			(clearance 0)
		)
		(min_thickness 0.25)
		(keepout
			(tracks not_allowed)
			(vias allowed)
			(pads allowed)
			(copperpour not_allowed)
			(footprints allowed)
		)
		(placement
			(enabled no)
			(sheetname "")
		)
		(fill
			(thermal_gap 0.5)
			(thermal_bridge_width 0.5)
			(island_removal_mode 0)
		)
		(polygon
			(pts
				(xy 441.7949 -222.57512) (xy 443.2935 -222.57512) (xy 443.2935 -223.095058) (xy 441.7949 -223.095058)
			)
		)
	)
	(zone
		(layer "In2.Cu")
		(hatch none 0.5)
		(connect_pads
			(clearance 0)
		)
		(min_thickness 0.25)
		(keepout
			(tracks not_allowed)
			(vias allowed)
			(pads allowed)
			(copperpour not_allowed)
			(footprints allowed)
		)
		(placement
			(enabled no)
			(sheetname "")
		)
		(fill
			(thermal_gap 0.5)
			(thermal_bridge_width 0.5)
			(island_removal_mode 0)
		)
		(polygon
			(pts
				(xy 16.858742 -291.425122) (xy 18.357342 -291.425122) (xy 18.357342 -291.94506) (xy 16.858742 -291.94506)
			)
		)
	)
	(zone
		(layer "In2.Cu")
		(hatch none 0.5)
		(connect_pads
			(clearance 0)
		)
		(min_thickness 0.25)
		(keepout
			(tracks not_allowed)
			(vias allowed)
			(pads allowed)
			(copperpour not_allowed)
			(footprints allowed)
		)
		(placement
			(enabled no)
			(sheetname "")
		)
		(fill
			(thermal_gap 0.5)
			(thermal_bridge_width 0.5)
			(island_removal_mode 0)
		)
		(polygon
			(pts
				(xy 201.398632 -225.975164) (xy 202.897232 -225.975164) (xy 202.897232 -226.495102) (xy 201.398632 -226.495102)
			)
		)
	)
	(zone
		(layer "In2.Cu")
		(hatch none 0.5)
		(connect_pads
			(clearance 0)
		)
		(min_thickness 0.25)
		(keepout
			(tracks not_allowed)
			(vias allowed)
			(pads allowed)
			(copperpour not_allowed)
			(footprints allowed)
		)
		(placement
			(enabled no)
			(sheetname "")
		)
		(fill
			(thermal_gap 0.5)
			(thermal_bridge_width 0.5)
			(island_removal_mode 0)
		)
		(polygon
			(pts
				(xy 193.854578 -230.225346) (xy 195.353178 -230.225346) (xy 195.353178 -230.745284) (xy 193.854578 -230.745284)
			)
		)
	)
	(zone
		(layer "In2.Cu")
		(hatch none 0.5)
		(connect_pads
			(clearance 0)
		)
		(min_thickness 0.25)
		(keepout
			(tracks not_allowed)
			(vias allowed)
			(pads allowed)
			(copperpour not_allowed)
			(footprints allowed)
		)
		(placement
			(enabled no)
			(sheetname "")
		)
		(fill
			(thermal_gap 0.5)
			(thermal_bridge_width 0.5)
			(island_removal_mode 0)
		)
		(polygon
			(pts
				(xy 186.310778 -211.525104) (xy 187.809378 -211.525104) (xy 187.809378 -212.045042) (xy 186.310778 -212.045042)
			)
		)
	)
	(zone
		(layer "In2.Cu")
		(hatch none 0.5)
		(connect_pads
			(clearance 0)
		)
		(min_thickness 0.25)
		(keepout
			(tracks not_allowed)
			(vias allowed)
			(pads allowed)
			(copperpour not_allowed)
			(footprints allowed)
		)
		(placement
			(enabled no)
			(sheetname "")
		)
		(fill
			(thermal_gap 0.5)
			(thermal_bridge_width 0.5)
			(island_removal_mode 0)
		)
		(polygon
			(pts
				(xy 24.402542 -294.825166) (xy 25.901142 -294.825166) (xy 25.901142 -295.345104) (xy 24.402542 -295.345104)
			)
		)
	)
	(zone
		(layer "In2.Cu")
		(hatch none 0.5)
		(connect_pads
			(clearance 0)
		)
		(min_thickness 0.25)
		(keepout
			(tracks not_allowed)
			(vias allowed)
			(pads allowed)
			(copperpour not_allowed)
			(footprints allowed)
		)
		(placement
			(enabled no)
			(sheetname "")
		)
		(fill
			(thermal_gap 0.5)
			(thermal_bridge_width 0.5)
			(island_removal_mode 0)
		)
		(polygon
			(pts
				(xy 438.350914 -223.425258) (xy 439.849514 -223.425258) (xy 439.849514 -223.945196) (xy 438.350914 -223.945196)
			)
		)
	)
	(zone
		(layer "In2.Cu")
		(hatch none 0.5)
		(connect_pads
			(clearance 0)
		)
		(min_thickness 0.25)
		(keepout
			(tracks not_allowed)
			(vias allowed)
			(pads allowed)
			(copperpour not_allowed)
			(footprints allowed)
		)
		(placement
			(enabled no)
			(sheetname "")
		)
		(fill
			(thermal_gap 0.5)
			(thermal_bridge_width 0.5)
			(island_removal_mode 0)
		)
		(polygon
			(pts
				(xy 287.430718 -294.825166) (xy 288.929318 -294.825166) (xy 288.929318 -295.345104) (xy 287.430718 -295.345104)
			)
		)
	)
	(zone
		(layer "In2.Cu")
		(hatch none 0.5)
		(connect_pads
			(clearance 0)
		)
		(min_thickness 0.25)
		(keepout
			(tracks not_allowed)
			(vias allowed)
			(pads allowed)
			(copperpour not_allowed)
			(footprints allowed)
		)
		(placement
			(enabled no)
			(sheetname "")
		)
		(fill
			(thermal_gap 0.5)
			(thermal_bridge_width 0.5)
			(island_removal_mode 0)
		)
		(polygon
			(pts
				(xy 51.134772 -301.625254) (xy 52.633372 -301.625254) (xy 52.633372 -302.145192) (xy 51.134772 -302.145192)
			)
		)
	)
	(zone
		(layer "In2.Cu")
		(hatch none 0.5)
		(connect_pads
			(clearance 0)
		)
		(min_thickness 0.25)
		(keepout
			(tracks not_allowed)
			(vias allowed)
			(pads allowed)
			(copperpour not_allowed)
			(footprints allowed)
		)
		(placement
			(enabled no)
			(sheetname "")
		)
		(fill
			(thermal_gap 0.5)
			(thermal_bridge_width 0.5)
			(island_removal_mode 0)
		)
		(polygon
			(pts
				(xy 171.22267 -265.075162) (xy 172.72127 -265.075162) (xy 172.72127 -265.5951) (xy 171.22267 -265.5951)
			)
		)
	)
	(zone
		(layer "In2.Cu")
		(hatch none 0.5)
		(connect_pads
			(clearance 0)
		)
		(min_thickness 0.25)
		(keepout
			(tracks not_allowed)
			(vias allowed)
			(pads allowed)
			(copperpour not_allowed)
			(footprints allowed)
		)
		(placement
			(enabled no)
			(sheetname "")
		)
		(fill
			(thermal_gap 0.5)
			(thermal_bridge_width 0.5)
			(island_removal_mode 0)
		)
		(polygon
			(pts
				(xy 294.974772 -246.375174) (xy 296.473372 -246.375174) (xy 296.473372 -246.895112) (xy 294.974772 -246.895112)
			)
		)
	)
	(zone
		(layer "In2.Cu")
		(hatch none 0.5)
		(connect_pads
			(clearance 0)
		)
		(min_thickness 0.25)
		(keepout
			(tracks not_allowed)
			(vias allowed)
			(pads allowed)
			(copperpour not_allowed)
			(footprints allowed)
		)
		(placement
			(enabled no)
			(sheetname "")
		)
		(fill
			(thermal_gap 0.5)
			(thermal_bridge_width 0.5)
			(island_removal_mode 0)
		)
		(polygon
			(pts
				(xy 272.342864 -254.025146) (xy 273.841464 -254.025146) (xy 273.841464 -254.545084) (xy 272.342864 -254.545084)
			)
		)
	)
	(zone
		(layer "In2.Cu")
		(hatch none 0.5)
		(connect_pads
			(clearance 0)
		)
		(min_thickness 0.25)
		(keepout
			(tracks not_allowed)
			(vias allowed)
			(pads allowed)
			(copperpour not_allowed)
			(footprints allowed)
		)
		(placement
			(enabled no)
			(sheetname "")
		)
		(fill
			(thermal_gap 0.5)
			(thermal_bridge_width 0.5)
			(island_removal_mode 0)
		)
		(polygon
			(pts
				(xy 24.402542 -272.725134) (xy 25.901142 -272.725134) (xy 25.901142 -273.245072) (xy 24.402542 -273.245072)
			)
		)
	)
	(zone
		(layer "In2.Cu")
		(hatch none 0.5)
		(connect_pads
			(clearance 0)
		)
		(min_thickness 0.25)
		(keepout
			(tracks not_allowed)
			(vias allowed)
			(pads allowed)
			(copperpour not_allowed)
			(footprints allowed)
		)
		(placement
			(enabled no)
			(sheetname "")
		)
		(fill
			(thermal_gap 0.5)
			(thermal_bridge_width 0.5)
			(island_removal_mode 0)
		)
		(polygon
			(pts
				(xy 28.50261 -307.575204) (xy 30.00121 -307.575204) (xy 30.00121 -308.095142) (xy 28.50261 -308.095142)
			)
		)
	)
	(zone
		(layer "In2.Cu")
		(hatch none 0.5)
		(connect_pads
			(clearance 0)
		)
		(min_thickness 0.25)
		(keepout
			(tracks not_allowed)
			(vias allowed)
			(pads allowed)
			(copperpour not_allowed)
			(footprints allowed)
		)
		(placement
			(enabled no)
			(sheetname "")
		)
		(fill
			(thermal_gap 0.5)
			(thermal_bridge_width 0.5)
			(island_removal_mode 0)
		)
		(polygon
			(pts
				(xy 306.618894 -279.525222) (xy 308.117494 -279.525222) (xy 308.117494 -280.04516) (xy 306.618894 -280.04516)
			)
		)
	)
	(zone
		(layer "In2.Cu")
		(hatch none 0.5)
		(connect_pads
			(clearance 0)
		)
		(min_thickness 0.25)
		(keepout
			(tracks not_allowed)
			(vias allowed)
			(pads allowed)
			(copperpour not_allowed)
			(footprints allowed)
		)
		(placement
			(enabled no)
			(sheetname "")
		)
		(fill
			(thermal_gap 0.5)
			(thermal_bridge_width 0.5)
			(island_removal_mode 0)
		)
		(polygon
			(pts
				(xy 291.530786 -229.375208) (xy 293.029386 -229.375208) (xy 293.029386 -229.895146) (xy 291.530786 -229.895146)
			)
		)
	)
	(zone
		(layer "In2.Cu")
		(hatch none 0.5)
		(connect_pads
			(clearance 0)
		)
		(min_thickness 0.25)
		(keepout
			(tracks not_allowed)
			(vias allowed)
			(pads allowed)
			(copperpour not_allowed)
			(footprints allowed)
		)
		(placement
			(enabled no)
			(sheetname "")
		)
		(fill
			(thermal_gap 0.5)
			(thermal_bridge_width 0.5)
			(island_removal_mode 0)
		)
		(polygon
			(pts
				(xy 272.342864 -210.67522) (xy 273.841464 -210.67522) (xy 273.841464 -211.195158) (xy 272.342864 -211.195158)
			)
		)
	)
	(zone
		(layer "In2.Cu")
		(hatch none 0.5)
		(connect_pads
			(clearance 0)
		)
		(min_thickness 0.25)
		(keepout
			(tracks not_allowed)
			(vias allowed)
			(pads allowed)
			(copperpour not_allowed)
			(footprints allowed)
		)
		(placement
			(enabled no)
			(sheetname "")
		)
		(fill
			(thermal_gap 0.5)
			(thermal_bridge_width 0.5)
			(island_removal_mode 0)
		)
		(polygon
			(pts
				(xy 453.438768 -240.425224) (xy 454.937368 -240.425224) (xy 454.937368 -240.945162) (xy 453.438768 -240.945162)
			)
		)
	)
	(zone
		(layer "In2.Cu")
		(hatch none 0.5)
		(connect_pads
			(clearance 0)
		)
		(min_thickness 0.25)
		(keepout
			(tracks not_allowed)
			(vias allowed)
			(pads allowed)
			(copperpour not_allowed)
			(footprints allowed)
		)
		(placement
			(enabled no)
			(sheetname "")
		)
		(fill
			(thermal_gap 0.5)
			(thermal_bridge_width 0.5)
			(island_removal_mode 0)
		)
		(polygon
			(pts
				(xy 144.113504 -31.97733)
				(arc
					(start 144.113504 -32.117538)
					(mid 144.142713 -32.18742)
					(end 144.212818 -32.21609)
				)
				(arc
					(start 144.514062 -32.21609)
					(mid 144.584167 -32.18742)
					(end 144.613376 -32.117538)
				)
				(xy 144.613376 -31.97733) (xy 144.553432 -31.97733)
				(arc
					(start 144.553432 -31.408116)
					(mid 144.596931 -31.371747)
					(end 144.613376 -31.317438)
				)
				(arc
					(start 144.613376 -31.057342)
					(mid 144.597057 -31.00295)
					(end 144.553432 -30.966664)
				)
				(xy 144.553432 -30.39745) (xy 144.613376 -30.39745)
				(arc
					(start 144.613376 -30.257242)
					(mid 144.584167 -30.18736)
					(end 144.514062 -30.15869)
				)
				(arc
					(start 144.212818 -30.15869)
					(mid 144.142713 -30.18736)
					(end 144.113504 -30.257242)
				)
				(xy 144.113504 -30.39745) (xy 144.173448 -30.39745)
				(arc
					(start 144.173448 -30.966664)
					(mid 144.129949 -31.003033)
					(end 144.113504 -31.057342)
				)
				(arc
					(start 144.113504 -31.317438)
					(mid 144.129823 -31.37183)
					(end 144.173448 -31.408116)
				)
				(xy 144.173448 -31.97733)
			)
		)
	)
	(zone
		(layer "In2.Cu")
		(hatch none 0.5)
		(connect_pads
			(clearance 0)
		)
		(min_thickness 0.25)
		(keepout
			(tracks not_allowed)
			(vias allowed)
			(pads allowed)
			(copperpour not_allowed)
			(footprints allowed)
		)
		(placement
			(enabled no)
			(sheetname "")
		)
		(fill
			(thermal_gap 0.5)
			(thermal_bridge_width 0.5)
			(island_removal_mode 0)
		)
		(polygon
			(pts
				(xy 423.262806 -307.575204) (xy 424.761406 -307.575204) (xy 424.761406 -308.095142) (xy 423.262806 -308.095142)
			)
		)
	)
	(zone
		(layer "In2.Cu")
		(hatch none 0.5)
		(connect_pads
			(clearance 0)
		)
		(min_thickness 0.25)
		(keepout
			(tracks not_allowed)
			(vias allowed)
			(pads allowed)
			(copperpour not_allowed)
			(footprints allowed)
		)
		(placement
			(enabled no)
			(sheetname "")
		)
		(fill
			(thermal_gap 0.5)
			(thermal_bridge_width 0.5)
			(island_removal_mode 0)
		)
		(polygon
			(pts
				(xy 299.07484 -313.525154) (xy 300.57344 -313.525154) (xy 300.57344 -314.045092) (xy 299.07484 -314.045092)
			)
		)
	)
	(zone
		(layer "In2.Cu")
		(hatch none 0.5)
		(connect_pads
			(clearance 0)
		)
		(min_thickness 0.25)
		(keepout
			(tracks not_allowed)
			(vias allowed)
			(pads allowed)
			(copperpour not_allowed)
			(footprints allowed)
		)
		(placement
			(enabled no)
			(sheetname "")
		)
		(fill
			(thermal_gap 0.5)
			(thermal_bridge_width 0.5)
			(island_removal_mode 0)
		)
		(polygon
			(pts
				(xy 175.322738 -279.525222) (xy 176.821338 -279.525222) (xy 176.821338 -280.04516) (xy 175.322738 -280.04516)
			)
		)
	)
	(zone
		(layer "In2.Cu")
		(hatch none 0.5)
		(connect_pads
			(clearance 0)
		)
		(min_thickness 0.25)
		(keepout
			(tracks not_allowed)
			(vias allowed)
			(pads allowed)
			(copperpour not_allowed)
			(footprints allowed)
		)
		(placement
			(enabled no)
			(sheetname "")
		)
		(fill
			(thermal_gap 0.5)
			(thermal_bridge_width 0.5)
			(island_removal_mode 0)
		)
		(polygon
			(pts
				(xy 441.7949 -220.025214) (xy 443.2935 -220.025214) (xy 443.2935 -220.545152) (xy 441.7949 -220.545152)
			)
		)
	)
	(zone
		(layer "In2.Cu")
		(hatch none 0.5)
		(connect_pads
			(clearance 0)
		)
		(min_thickness 0.25)
		(keepout
			(tracks not_allowed)
			(vias allowed)
			(pads allowed)
			(copperpour not_allowed)
			(footprints allowed)
		)
		(placement
			(enabled no)
			(sheetname "")
		)
		(fill
			(thermal_gap 0.5)
			(thermal_bridge_width 0.5)
			(island_removal_mode 0)
		)
		(polygon
			(pts
				(xy 54.578758 -300.775116) (xy 56.077358 -300.775116) (xy 56.077358 -301.295054) (xy 54.578758 -301.295054)
			)
		)
	)
	(zone
		(layer "In2.Cu")
		(hatch none 0.5)
		(connect_pads
			(clearance 0)
		)
		(min_thickness 0.25)
		(keepout
			(tracks not_allowed)
			(vias allowed)
			(pads allowed)
			(copperpour not_allowed)
			(footprints allowed)
		)
		(placement
			(enabled no)
			(sheetname "")
		)
		(fill
			(thermal_gap 0.5)
			(thermal_bridge_width 0.5)
			(island_removal_mode 0)
		)
		(polygon
			(pts
				(xy 193.854578 -263.37514) (xy 195.353178 -263.37514) (xy 195.353178 -263.895078) (xy 193.854578 -263.895078)
			)
		)
	)
	(zone
		(layer "In2.Cu")
		(hatch none 0.5)
		(connect_pads
			(clearance 0)
		)
		(min_thickness 0.25)
		(keepout
			(tracks not_allowed)
			(vias allowed)
			(pads allowed)
			(copperpour not_allowed)
			(footprints allowed)
		)
		(placement
			(enabled no)
			(sheetname "")
		)
		(fill
			(thermal_gap 0.5)
			(thermal_bridge_width 0.5)
			(island_removal_mode 0)
		)
		(polygon
			(pts
				(xy 441.7949 -305.025298) (xy 443.2935 -305.025298) (xy 443.2935 -305.545236) (xy 441.7949 -305.545236)
			)
		)
	)
	(zone
		(layer "In2.Cu")
		(hatch none 0.5)
		(connect_pads
			(clearance 0)
		)
		(min_thickness 0.25)
		(keepout
			(tracks not_allowed)
			(vias allowed)
			(pads allowed)
			(copperpour not_allowed)
			(footprints allowed)
		)
		(placement
			(enabled no)
			(sheetname "")
		)
		(fill
			(thermal_gap 0.5)
			(thermal_bridge_width 0.5)
			(island_removal_mode 0)
		)
		(polygon
			(pts
				(xy 426.706792 -297.375326) (xy 428.205392 -297.375326) (xy 428.205392 -297.895264) (xy 426.706792 -297.895264)
			)
		)
	)
	(zone
		(layer "In2.Cu")
		(hatch none 0.5)
		(connect_pads
			(clearance 0)
		)
		(min_thickness 0.25)
		(keepout
			(tracks not_allowed)
			(vias allowed)
			(pads allowed)
			(copperpour not_allowed)
			(footprints allowed)
		)
		(placement
			(enabled no)
			(sheetname "")
		)
		(fill
			(thermal_gap 0.5)
			(thermal_bridge_width 0.5)
			(island_removal_mode 0)
		)
		(polygon
			(pts
				(xy 445.894968 -277.8252) (xy 447.393568 -277.8252) (xy 447.393568 -278.345138) (xy 445.894968 -278.345138)
			)
		)
	)
	(zone
		(layer "In2.Cu")
		(hatch none 0.5)
		(connect_pads
			(clearance 0)
		)
		(min_thickness 0.25)
		(keepout
			(tracks not_allowed)
			(vias allowed)
			(pads allowed)
			(copperpour not_allowed)
			(footprints allowed)
		)
		(placement
			(enabled no)
			(sheetname "")
		)
		(fill
			(thermal_gap 0.5)
			(thermal_bridge_width 0.5)
			(island_removal_mode 0)
		)
		(polygon
			(pts
				(xy 20.95881 -310.975248) (xy 22.45741 -310.975248) (xy 22.45741 -311.495186) (xy 20.95881 -311.495186)
			)
		)
	)
	(zone
		(layer "In2.Cu")
		(hatch none 0.5)
		(connect_pads
			(clearance 0)
		)
		(min_thickness 0.25)
		(keepout
			(tracks not_allowed)
			(vias allowed)
			(pads allowed)
			(copperpour not_allowed)
			(footprints allowed)
		)
		(placement
			(enabled no)
			(sheetname "")
		)
		(fill
			(thermal_gap 0.5)
			(thermal_bridge_width 0.5)
			(island_removal_mode 0)
		)
		(polygon
			(pts
				(xy 167.778684 -231.07523) (xy 169.277284 -231.07523) (xy 169.277284 -231.595168) (xy 167.778684 -231.595168)
			)
		)
	)
	(zone
		(layer "In2.Cu")
		(hatch none 0.5)
		(connect_pads
			(clearance 0)
		)
		(min_thickness 0.25)
		(keepout
			(tracks not_allowed)
			(vias allowed)
			(pads allowed)
			(copperpour not_allowed)
			(footprints allowed)
		)
		(placement
			(enabled no)
			(sheetname "")
		)
		(fill
			(thermal_gap 0.5)
			(thermal_bridge_width 0.5)
			(island_removal_mode 0)
		)
		(polygon
			(pts
				(xy 47.034704 -224.275142) (xy 48.533304 -224.275142) (xy 48.533304 -224.79508) (xy 47.034704 -224.79508)
			)
		)
	)
	(zone
		(layer "In2.Cu")
		(hatch none 0.5)
		(connect_pads
			(clearance 0)
		)
		(min_thickness 0.25)
		(keepout
			(tracks not_allowed)
			(vias allowed)
			(pads allowed)
			(copperpour not_allowed)
			(footprints allowed)
		)
		(placement
			(enabled no)
			(sheetname "")
		)
		(fill
			(thermal_gap 0.5)
			(thermal_bridge_width 0.5)
			(island_removal_mode 0)
		)
		(polygon
			(pts
				(xy 419.162738 -220.875098) (xy 420.661338 -220.875098) (xy 420.661338 -221.395036) (xy 419.162738 -221.395036)
			)
		)
	)
	(zone
		(layer "In2.Cu")
		(hatch none 0.5)
		(connect_pads
			(clearance 0)
		)
		(min_thickness 0.25)
		(keepout
			(tracks not_allowed)
			(vias allowed)
			(pads allowed)
			(copperpour not_allowed)
			(footprints allowed)
		)
		(placement
			(enabled no)
			(sheetname "")
		)
		(fill
			(thermal_gap 0.5)
			(thermal_bridge_width 0.5)
			(island_removal_mode 0)
		)
		(polygon
			(pts
				(xy 306.618894 -282.925266) (xy 308.117494 -282.925266) (xy 308.117494 -283.445204) (xy 306.618894 -283.445204)
			)
		)
	)
	(zone
		(layer "In2.Cu")
		(hatch none 0.5)
		(connect_pads
			(clearance 0)
		)
		(min_thickness 0.25)
		(keepout
			(tracks not_allowed)
			(vias allowed)
			(pads allowed)
			(copperpour not_allowed)
			(footprints allowed)
		)
		(placement
			(enabled no)
			(sheetname "")
		)
		(fill
			(thermal_gap 0.5)
			(thermal_bridge_width 0.5)
			(island_removal_mode 0)
		)
		(polygon
			(pts
				(xy 186.310778 -201.325226) (xy 187.809378 -201.325226) (xy 187.809378 -201.845164) (xy 186.310778 -201.845164)
			)
		)
	)
	(zone
		(layer "In2.Cu")
		(hatch none 0.5)
		(connect_pads
			(clearance 0)
		)
		(min_thickness 0.25)
		(keepout
			(tracks not_allowed)
			(vias allowed)
			(pads allowed)
			(copperpour not_allowed)
			(footprints allowed)
		)
		(placement
			(enabled no)
			(sheetname "")
		)
		(fill
			(thermal_gap 0.5)
			(thermal_bridge_width 0.5)
			(island_removal_mode 0)
		)
		(polygon
			(pts
				(xy 197.954646 -240.425224) (xy 199.453246 -240.425224) (xy 199.453246 -240.945162) (xy 197.954646 -240.945162)
			)
		)
	)
	(zone
		(layer "In2.Cu")
		(hatch none 0.5)
		(connect_pads
			(clearance 0)
		)
		(min_thickness 0.25)
		(keepout
			(tracks not_allowed)
			(vias allowed)
			(pads allowed)
			(copperpour not_allowed)
			(footprints allowed)
		)
		(placement
			(enabled no)
			(sheetname "")
		)
		(fill
			(thermal_gap 0.5)
			(thermal_bridge_width 0.5)
			(island_removal_mode 0)
		)
		(polygon
			(pts
				(xy 54.578758 -316.075314) (xy 56.077358 -316.075314) (xy 56.077358 -316.595252) (xy 54.578758 -316.595252)
			)
		)
	)
	(zone
		(layer "In2.Cu")
		(hatch none 0.5)
		(connect_pads
			(clearance 0)
		)
		(min_thickness 0.25)
		(keepout
			(tracks not_allowed)
			(vias allowed)
			(pads allowed)
			(copperpour not_allowed)
			(footprints allowed)
		)
		(placement
			(enabled no)
			(sheetname "")
		)
		(fill
			(thermal_gap 0.5)
			(thermal_bridge_width 0.5)
			(island_removal_mode 0)
		)
		(polygon
			(pts
				(xy 434.250846 -231.925114) (xy 435.749446 -231.925114) (xy 435.749446 -232.445052) (xy 434.250846 -232.445052)
			)
		)
	)
	(zone
		(layer "In2.Cu")
		(hatch none 0.5)
		(connect_pads
			(clearance 0)
		)
		(min_thickness 0.25)
		(keepout
			(tracks not_allowed)
			(vias allowed)
			(pads allowed)
			(copperpour not_allowed)
			(footprints allowed)
		)
		(placement
			(enabled no)
			(sheetname "")
		)
		(fill
			(thermal_gap 0.5)
			(thermal_bridge_width 0.5)
			(island_removal_mode 0)
		)
		(polygon
			(pts
				(xy 287.430718 -233.625136) (xy 288.929318 -233.625136) (xy 288.929318 -234.145074) (xy 287.430718 -234.145074)
			)
		)
	)
	(zone
		(layer "In2.Cu")
		(hatch none 0.5)
		(connect_pads
			(clearance 0)
		)
		(min_thickness 0.25)
		(keepout
			(tracks not_allowed)
			(vias allowed)
			(pads allowed)
			(copperpour not_allowed)
			(footprints allowed)
		)
		(placement
			(enabled no)
			(sheetname "")
		)
		(fill
			(thermal_gap 0.5)
			(thermal_bridge_width 0.5)
			(island_removal_mode 0)
		)
		(polygon
			(pts
				(xy 449.3387 -201.325226) (xy 450.8373 -201.325226) (xy 450.8373 -201.845164) (xy 449.3387 -201.845164)
			)
		)
	)
	(zone
		(layer "In2.Cu")
		(hatch none 0.5)
		(connect_pads
			(clearance 0)
		)
		(min_thickness 0.25)
		(keepout
			(tracks not_allowed)
			(vias allowed)
			(pads allowed)
			(copperpour not_allowed)
			(footprints allowed)
		)
		(placement
			(enabled no)
			(sheetname "")
		)
		(fill
			(thermal_gap 0.5)
			(thermal_bridge_width 0.5)
			(island_removal_mode 0)
		)
		(polygon
			(pts
				(xy 441.7949 -268.475206) (xy 443.2935 -268.475206) (xy 443.2935 -268.995144) (xy 441.7949 -268.995144)
			)
		)
	)
	(zone
		(layer "In2.Cu")
		(hatch none 0.5)
		(connect_pads
			(clearance 0)
		)
		(min_thickness 0.25)
		(keepout
			(tracks not_allowed)
			(vias allowed)
			(pads allowed)
			(copperpour not_allowed)
			(footprints allowed)
		)
		(placement
			(enabled no)
			(sheetname "")
		)
		(fill
			(thermal_gap 0.5)
			(thermal_bridge_width 0.5)
			(island_removal_mode 0)
		)
		(polygon
			(pts
				(xy 294.974772 -268.475206) (xy 296.473372 -268.475206) (xy 296.473372 -268.995144) (xy 294.974772 -268.995144)
			)
		)
	)
	(zone
		(layer "In2.Cu")
		(hatch none 0.5)
		(connect_pads
			(clearance 0)
		)
		(min_thickness 0.25)
		(keepout
			(tracks not_allowed)
			(vias allowed)
			(pads allowed)
			(copperpour not_allowed)
			(footprints allowed)
		)
		(placement
			(enabled no)
			(sheetname "")
		)
		(fill
			(thermal_gap 0.5)
			(thermal_bridge_width 0.5)
			(island_removal_mode 0)
		)
		(polygon
			(pts
				(xy 163.678616 -216.62517) (xy 165.177216 -216.62517) (xy 165.177216 -217.145108) (xy 163.678616 -217.145108)
			)
		)
	)
	(zone
		(layer "In2.Cu")
		(hatch none 0.5)
		(connect_pads
			(clearance 0)
		)
		(min_thickness 0.25)
		(keepout
			(tracks not_allowed)
			(vias allowed)
			(pads allowed)
			(copperpour not_allowed)
			(footprints allowed)
		)
		(placement
			(enabled no)
			(sheetname "")
		)
		(fill
			(thermal_gap 0.5)
			(thermal_bridge_width 0.5)
			(island_removal_mode 0)
		)
		(polygon
			(pts
				(xy 268.898878 -276.125178) (xy 270.397478 -276.125178) (xy 270.397478 -276.645116) (xy 268.898878 -276.645116)
			)
		)
	)
	(zone
		(layer "In2.Cu")
		(hatch none 0.5)
		(connect_pads
			(clearance 0)
		)
		(min_thickness 0.25)
		(keepout
			(tracks not_allowed)
			(vias allowed)
			(pads allowed)
			(copperpour not_allowed)
			(footprints allowed)
		)
		(placement
			(enabled no)
			(sheetname "")
		)
		(fill
			(thermal_gap 0.5)
			(thermal_bridge_width 0.5)
			(island_removal_mode 0)
		)
		(polygon
			(pts
				(xy 299.07484 -200.475342) (xy 300.57344 -200.475342) (xy 300.57344 -200.99528) (xy 299.07484 -200.99528)
			)
		)
	)
	(zone
		(layer "In2.Cu")
		(hatch none 0.5)
		(connect_pads
			(clearance 0)
		)
		(min_thickness 0.25)
		(keepout
			(tracks not_allowed)
			(vias allowed)
			(pads allowed)
			(copperpour not_allowed)
			(footprints allowed)
		)
		(placement
			(enabled no)
			(sheetname "")
		)
		(fill
			(thermal_gap 0.5)
			(thermal_bridge_width 0.5)
			(island_removal_mode 0)
		)
		(polygon
			(pts
				(xy 31.946596 -210.67522) (xy 33.445196 -210.67522) (xy 33.445196 -211.195158) (xy 31.946596 -211.195158)
			)
		)
	)
	(zone
		(layer "In2.Cu")
		(hatch none 0.5)
		(connect_pads
			(clearance 0)
		)
		(min_thickness 0.25)
		(keepout
			(tracks not_allowed)
			(vias allowed)
			(pads allowed)
			(copperpour not_allowed)
			(footprints allowed)
		)
		(placement
			(enabled no)
			(sheetname "")
		)
		(fill
			(thermal_gap 0.5)
			(thermal_bridge_width 0.5)
			(island_removal_mode 0)
		)
		(polygon
			(pts
				(xy 20.95881 -294.825166) (xy 22.45741 -294.825166) (xy 22.45741 -295.345104) (xy 20.95881 -295.345104)
			)
		)
	)
	(zone
		(layer "In2.Cu")
		(hatch none 0.5)
		(connect_pads
			(clearance 0)
		)
		(min_thickness 0.25)
		(keepout
			(tracks not_allowed)
			(vias allowed)
			(pads allowed)
			(copperpour not_allowed)
			(footprints allowed)
		)
		(placement
			(enabled no)
			(sheetname "")
		)
		(fill
			(thermal_gap 0.5)
			(thermal_bridge_width 0.5)
			(island_removal_mode 0)
		)
		(polygon
			(pts
				(xy 441.7949 -283.77515) (xy 443.2935 -283.77515) (xy 443.2935 -284.295088) (xy 441.7949 -284.295088)
			)
		)
	)
	(zone
		(layer "In2.Cu")
		(hatch none 0.5)
		(connect_pads
			(clearance 0)
		)
		(min_thickness 0.25)
		(keepout
			(tracks not_allowed)
			(vias allowed)
			(pads allowed)
			(copperpour not_allowed)
			(footprints allowed)
		)
		(placement
			(enabled no)
			(sheetname "")
		)
		(fill
			(thermal_gap 0.5)
			(thermal_bridge_width 0.5)
			(island_removal_mode 0)
		)
		(polygon
			(pts
				(xy 51.134772 -275.275294) (xy 52.633372 -275.275294) (xy 52.633372 -275.795232) (xy 51.134772 -275.795232)
			)
		)
	)
	(zone
		(layer "In2.Cu")
		(hatch none 0.5)
		(connect_pads
			(clearance 0)
		)
		(min_thickness 0.25)
		(keepout
			(tracks not_allowed)
			(vias allowed)
			(pads allowed)
			(copperpour not_allowed)
			(footprints allowed)
		)
		(placement
			(enabled no)
			(sheetname "")
		)
		(fill
			(thermal_gap 0.5)
			(thermal_bridge_width 0.5)
			(island_removal_mode 0)
		)
		(polygon
			(pts
				(xy 441.7949 -310.12511) (xy 443.2935 -310.12511) (xy 443.2935 -310.645048) (xy 441.7949 -310.645048)
			)
		)
	)
	(zone
		(layer "In2.Cu")
		(hatch none 0.5)
		(connect_pads
			(clearance 0)
		)
		(min_thickness 0.25)
		(keepout
			(tracks not_allowed)
			(vias allowed)
			(pads allowed)
			(copperpour not_allowed)
			(footprints allowed)
		)
		(placement
			(enabled no)
			(sheetname "")
		)
		(fill
			(thermal_gap 0.5)
			(thermal_bridge_width 0.5)
			(island_removal_mode 0)
		)
		(polygon
			(pts
				(xy 193.854578 -305.025298) (xy 195.353178 -305.025298) (xy 195.353178 -305.545236) (xy 193.854578 -305.545236)
			)
		)
	)
	(zone
		(layer "In2.Cu")
		(hatch none 0.5)
		(connect_pads
			(clearance 0)
		)
		(min_thickness 0.25)
		(keepout
			(tracks not_allowed)
			(vias allowed)
			(pads allowed)
			(copperpour not_allowed)
			(footprints allowed)
		)
		(placement
			(enabled no)
			(sheetname "")
		)
		(fill
			(thermal_gap 0.5)
			(thermal_bridge_width 0.5)
			(island_removal_mode 0)
		)
		(polygon
			(pts
				(xy 438.350914 -217.475308) (xy 439.849514 -217.475308) (xy 439.849514 -217.995246) (xy 438.350914 -217.995246)
			)
		)
	)
	(zone
		(layer "In2.Cu")
		(hatch none 0.5)
		(connect_pads
			(clearance 0)
		)
		(min_thickness 0.25)
		(keepout
			(tracks not_allowed)
			(vias allowed)
			(pads allowed)
			(copperpour not_allowed)
			(footprints allowed)
		)
		(placement
			(enabled no)
			(sheetname "")
		)
		(fill
			(thermal_gap 0.5)
			(thermal_bridge_width 0.5)
			(island_removal_mode 0)
		)
		(polygon
			(pts
				(xy 302.518826 -291.425122) (xy 304.017426 -291.425122) (xy 304.017426 -291.94506) (xy 302.518826 -291.94506)
			)
		)
	)
	(zone
		(layer "In2.Cu")
		(hatch none 0.5)
		(connect_pads
			(clearance 0)
		)
		(min_thickness 0.25)
		(keepout
			(tracks not_allowed)
			(vias allowed)
			(pads allowed)
			(copperpour not_allowed)
			(footprints allowed)
		)
		(placement
			(enabled no)
			(sheetname "")
		)
		(fill
			(thermal_gap 0.5)
			(thermal_bridge_width 0.5)
			(island_removal_mode 0)
		)
		(polygon
			(pts
				(arc
					(start 339.118194 -381.824484)
					(mid 339.138118 -381.83372)
					(end 339.15985 -381.83693)
				)
				(arc
					(start 339.354414 -381.83693)
					(mid 339.408296 -381.814612)
					(end 339.430614 -381.76073)
				)
				(arc
					(start 339.430614 -381.07493)
					(mid 339.408296 -381.021048)
					(end 339.354414 -380.99873)
				)
				(arc
					(start 339.15985 -380.99873)
					(mid 339.138106 -381.001898)
					(end 339.118194 -381.011176)
				)
				(arc
					(start 338.82203 -381.203962)
					(mid 338.780346 -381.216184)
					(end 338.738718 -381.203708)
				)
				(arc
					(start 338.445094 -381.011176)
					(mid 338.42517 -381.00194)
					(end 338.403438 -380.99873)
				)
				(arc
					(start 338.208874 -380.99873)
					(mid 338.154992 -381.021048)
					(end 338.132674 -381.07493)
				)
				(arc
					(start 338.132674 -381.76073)
					(mid 338.154992 -381.814612)
					(end 338.208874 -381.83693)
				)
				(arc
					(start 338.404708 -381.83693)
					(mid 338.426452 -381.833762)
					(end 338.446364 -381.824484)
				)
				(arc
					(start 338.739988 -381.631952)
					(mid 338.781644 -381.61955)
					(end 338.8233 -381.631952)
				)
			)
		)
	)
	(zone
		(layer "In2.Cu")
		(hatch none 0.5)
		(connect_pads
			(clearance 0)
		)
		(min_thickness 0.25)
		(keepout
			(tracks not_allowed)
			(vias allowed)
			(pads allowed)
			(copperpour not_allowed)
			(footprints allowed)
		)
		(placement
			(enabled no)
			(sheetname "")
		)
		(fill
			(thermal_gap 0.5)
			(thermal_bridge_width 0.5)
			(island_removal_mode 0)
		)
		(polygon
			(pts
				(xy 171.22267 -225.975164) (xy 172.72127 -225.975164) (xy 172.72127 -226.495102) (xy 171.22267 -226.495102)
			)
		)
	)
	(zone
		(layer "In2.Cu")
		(hatch none 0.5)
		(connect_pads
			(clearance 0)
		)
		(min_thickness 0.25)
		(keepout
			(tracks not_allowed)
			(vias allowed)
			(pads allowed)
			(copperpour not_allowed)
			(footprints allowed)
		)
		(placement
			(enabled no)
			(sheetname "")
		)
		(fill
			(thermal_gap 0.5)
			(thermal_bridge_width 0.5)
			(island_removal_mode 0)
		)
		(polygon
			(pts
				(xy 411.618684 -222.57512) (xy 413.117284 -222.57512) (xy 413.117284 -223.095058) (xy 411.618684 -223.095058)
			)
		)
	)
	(zone
		(layer "In2.Cu")
		(hatch none 0.5)
		(connect_pads
			(clearance 0)
		)
		(min_thickness 0.25)
		(keepout
			(tracks not_allowed)
			(vias allowed)
			(pads allowed)
			(copperpour not_allowed)
			(footprints allowed)
		)
		(placement
			(enabled no)
			(sheetname "")
		)
		(fill
			(thermal_gap 0.5)
			(thermal_bridge_width 0.5)
			(island_removal_mode 0)
		)
		(polygon
			(pts
				(xy 163.678616 -241.275108) (xy 165.177216 -241.275108) (xy 165.177216 -241.795046) (xy 163.678616 -241.795046)
			)
		)
	)
	(zone
		(layer "In2.Cu")
		(hatch none 0.5)
		(connect_pads
			(clearance 0)
		)
		(min_thickness 0.25)
		(keepout
			(tracks not_allowed)
			(vias allowed)
			(pads allowed)
			(copperpour not_allowed)
			(footprints allowed)
		)
		(placement
			(enabled no)
			(sheetname "")
		)
		(fill
			(thermal_gap 0.5)
			(thermal_bridge_width 0.5)
			(island_removal_mode 0)
		)
		(polygon
			(pts
				(xy 186.310778 -227.675186) (xy 187.809378 -227.675186) (xy 187.809378 -228.195124) (xy 186.310778 -228.195124)
			)
		)
	)
	(zone
		(layer "In2.Cu")
		(hatch none 0.5)
		(connect_pads
			(clearance 0)
		)
		(min_thickness 0.25)
		(keepout
			(tracks not_allowed)
			(vias allowed)
			(pads allowed)
			(copperpour not_allowed)
			(footprints allowed)
		)
		(placement
			(enabled no)
			(sheetname "")
		)
		(fill
			(thermal_gap 0.5)
			(thermal_bridge_width 0.5)
			(island_removal_mode 0)
		)
		(polygon
			(pts
				(xy 276.442932 -260.825234) (xy 277.941532 -260.825234) (xy 277.941532 -261.345172) (xy 276.442932 -261.345172)
			)
		)
	)
	(zone
		(layer "In2.Cu")
		(hatch none 0.5)
		(connect_pads
			(clearance 0)
		)
		(min_thickness 0.25)
		(keepout
			(tracks not_allowed)
			(vias allowed)
			(pads allowed)
			(copperpour not_allowed)
			(footprints allowed)
		)
		(placement
			(enabled no)
			(sheetname "")
		)
		(fill
			(thermal_gap 0.5)
			(thermal_bridge_width 0.5)
			(island_removal_mode 0)
		)
		(polygon
			(pts
				(xy 16.858742 -235.325158) (xy 18.357342 -235.325158) (xy 18.357342 -235.845096) (xy 16.858742 -235.845096)
			)
		)
	)
	(zone
		(layer "In2.Cu")
		(hatch none 0.5)
		(connect_pads
			(clearance 0)
		)
		(min_thickness 0.25)
		(keepout
			(tracks not_allowed)
			(vias allowed)
			(pads allowed)
			(copperpour not_allowed)
			(footprints allowed)
		)
		(placement
			(enabled no)
			(sheetname "")
		)
		(fill
			(thermal_gap 0.5)
			(thermal_bridge_width 0.5)
			(island_removal_mode 0)
		)
		(polygon
			(pts
				(xy 426.706792 -239.57534) (xy 428.205392 -239.57534) (xy 428.205392 -240.095278) (xy 426.706792 -240.095278)
			)
		)
	)
	(zone
		(layer "In2.Cu")
		(hatch none 0.5)
		(connect_pads
			(clearance 0)
		)
		(min_thickness 0.25)
		(keepout
			(tracks not_allowed)
			(vias allowed)
			(pads allowed)
			(copperpour not_allowed)
			(footprints allowed)
		)
		(placement
			(enabled no)
			(sheetname "")
		)
		(fill
			(thermal_gap 0.5)
			(thermal_bridge_width 0.5)
			(island_removal_mode 0)
		)
		(polygon
			(pts
				(xy 430.80686 -200.475342) (xy 432.30546 -200.475342) (xy 432.30546 -200.99528) (xy 430.80686 -200.99528)
			)
		)
	)
	(zone
		(layer "In2.Cu")
		(hatch none 0.5)
		(connect_pads
			(clearance 0)
		)
		(min_thickness 0.25)
		(keepout
			(tracks not_allowed)
			(vias allowed)
			(pads allowed)
			(copperpour not_allowed)
			(footprints allowed)
		)
		(placement
			(enabled no)
			(sheetname "")
		)
		(fill
			(thermal_gap 0.5)
			(thermal_bridge_width 0.5)
			(island_removal_mode 0)
		)
		(polygon
			(pts
				(xy 291.530786 -282.925266) (xy 293.029386 -282.925266) (xy 293.029386 -283.445204) (xy 291.530786 -283.445204)
			)
		)
	)
	(zone
		(layer "In2.Cu")
		(hatch none 0.5)
		(connect_pads
			(clearance 0)
		)
		(min_thickness 0.25)
		(keepout
			(tracks not_allowed)
			(vias allowed)
			(pads allowed)
			(copperpour not_allowed)
			(footprints allowed)
		)
		(placement
			(enabled no)
			(sheetname "")
		)
		(fill
			(thermal_gap 0.5)
			(thermal_bridge_width 0.5)
			(island_removal_mode 0)
		)
		(polygon
			(pts
				(xy 291.530786 -279.525222) (xy 293.029386 -279.525222) (xy 293.029386 -280.04516) (xy 291.530786 -280.04516)
			)
		)
	)
	(zone
		(layer "In2.Cu")
		(hatch none 0.5)
		(connect_pads
			(clearance 0)
		)
		(min_thickness 0.25)
		(keepout
			(tracks not_allowed)
			(vias allowed)
			(pads allowed)
			(copperpour not_allowed)
			(footprints allowed)
		)
		(placement
			(enabled no)
			(sheetname "")
		)
		(fill
			(thermal_gap 0.5)
			(thermal_bridge_width 0.5)
			(island_removal_mode 0)
		)
		(polygon
			(pts
				(xy 453.438768 -214.075264) (xy 454.937368 -214.075264) (xy 454.937368 -214.595202) (xy 453.438768 -214.595202)
			)
		)
	)
	(zone
		(layer "In2.Cu")
		(hatch none 0.5)
		(connect_pads
			(clearance 0)
		)
		(min_thickness 0.25)
		(keepout
			(tracks not_allowed)
			(vias allowed)
			(pads allowed)
			(copperpour not_allowed)
			(footprints allowed)
		)
		(placement
			(enabled no)
			(sheetname "")
		)
		(fill
			(thermal_gap 0.5)
			(thermal_bridge_width 0.5)
			(island_removal_mode 0)
		)
		(polygon
			(pts
				(xy 276.442932 -316.925198) (xy 277.941532 -316.925198) (xy 277.941532 -317.445136) (xy 276.442932 -317.445136)
			)
		)
	)
	(zone
		(layer "In2.Cu")
		(hatch none 0.5)
		(connect_pads
			(clearance 0)
		)
		(min_thickness 0.25)
		(keepout
			(tracks not_allowed)
			(vias allowed)
			(pads allowed)
			(copperpour not_allowed)
			(footprints allowed)
		)
		(placement
			(enabled no)
			(sheetname "")
		)
		(fill
			(thermal_gap 0.5)
			(thermal_bridge_width 0.5)
			(island_removal_mode 0)
		)
		(polygon
			(pts
				(xy 193.854578 -311.825132) (xy 195.353178 -311.825132) (xy 195.353178 -312.34507) (xy 193.854578 -312.34507)
			)
		)
	)
	(zone
		(layer "In2.Cu")
		(hatch none 0.5)
		(connect_pads
			(clearance 0)
		)
		(min_thickness 0.25)
		(keepout
			(tracks not_allowed)
			(vias allowed)
			(pads allowed)
			(copperpour not_allowed)
			(footprints allowed)
		)
		(placement
			(enabled no)
			(sheetname "")
		)
		(fill
			(thermal_gap 0.5)
			(thermal_bridge_width 0.5)
			(island_removal_mode 0)
		)
		(polygon
			(pts
				(xy 58.678826 -287.175194) (xy 60.177426 -287.175194) (xy 60.177426 -287.695132) (xy 58.678826 -287.695132)
			)
		)
	)
	(zone
		(layer "In2.Cu")
		(hatch none 0.5)
		(connect_pads
			(clearance 0)
		)
		(min_thickness 0.25)
		(keepout
			(tracks not_allowed)
			(vias allowed)
			(pads allowed)
			(copperpour not_allowed)
			(footprints allowed)
		)
		(placement
			(enabled no)
			(sheetname "")
		)
		(fill
			(thermal_gap 0.5)
			(thermal_bridge_width 0.5)
			(island_removal_mode 0)
		)
		(polygon
			(pts
				(xy 268.898878 -312.67527) (xy 270.397478 -312.67527) (xy 270.397478 -313.195208) (xy 268.898878 -313.195208)
			)
		)
	)
	(zone
		(layer "In2.Cu")
		(hatch none 0.5)
		(connect_pads
			(clearance 0)
		)
		(min_thickness 0.25)
		(keepout
			(tracks not_allowed)
			(vias allowed)
			(pads allowed)
			(copperpour not_allowed)
			(footprints allowed)
		)
		(placement
			(enabled no)
			(sheetname "")
		)
		(fill
			(thermal_gap 0.5)
			(thermal_bridge_width 0.5)
			(island_removal_mode 0)
		)
		(polygon
			(pts
				(xy 441.7949 -242.97513) (xy 443.2935 -242.97513) (xy 443.2935 -243.495068) (xy 441.7949 -243.495068)
			)
		)
	)
	(zone
		(layer "In2.Cu")
		(hatch none 0.5)
		(connect_pads
			(clearance 0)
		)
		(min_thickness 0.25)
		(keepout
			(tracks not_allowed)
			(vias allowed)
			(pads allowed)
			(copperpour not_allowed)
			(footprints allowed)
		)
		(placement
			(enabled no)
			(sheetname "")
		)
		(fill
			(thermal_gap 0.5)
			(thermal_bridge_width 0.5)
			(island_removal_mode 0)
		)
		(polygon
			(pts
				(xy 268.898878 -307.575204) (xy 270.397478 -307.575204) (xy 270.397478 -308.095142) (xy 268.898878 -308.095142)
			)
		)
	)
	(zone
		(layer "In2.Cu")
		(hatch none 0.5)
		(connect_pads
			(clearance 0)
		)
		(min_thickness 0.25)
		(keepout
			(tracks not_allowed)
			(vias allowed)
			(pads allowed)
			(copperpour not_allowed)
			(footprints allowed)
		)
		(placement
			(enabled no)
			(sheetname "")
		)
		(fill
			(thermal_gap 0.5)
			(thermal_bridge_width 0.5)
			(island_removal_mode 0)
		)
		(polygon
			(pts
				(xy 415.718752 -305.875182) (xy 417.217352 -305.875182) (xy 417.217352 -306.39512) (xy 415.718752 -306.39512)
			)
		)
	)
	(zone
		(layer "In2.Cu")
		(hatch none 0.5)
		(connect_pads
			(clearance 0)
		)
		(min_thickness 0.25)
		(keepout
			(tracks not_allowed)
			(vias allowed)
			(pads allowed)
			(copperpour not_allowed)
			(footprints allowed)
		)
		(placement
			(enabled no)
			(sheetname "")
		)
		(fill
			(thermal_gap 0.5)
			(thermal_bridge_width 0.5)
			(island_removal_mode 0)
		)
		(polygon
			(pts
				(xy 430.80686 -260.825234) (xy 432.30546 -260.825234) (xy 432.30546 -261.345172) (xy 430.80686 -261.345172)
			)
		)
	)
	(zone
		(layer "In2.Cu")
		(hatch none 0.5)
		(connect_pads
			(clearance 0)
		)
		(min_thickness 0.25)
		(keepout
			(tracks not_allowed)
			(vias allowed)
			(pads allowed)
			(copperpour not_allowed)
			(footprints allowed)
		)
		(placement
			(enabled no)
			(sheetname "")
		)
		(fill
			(thermal_gap 0.5)
			(thermal_bridge_width 0.5)
			(island_removal_mode 0)
		)
		(polygon
			(pts
				(xy 47.034704 -285.475172) (xy 48.533304 -285.475172) (xy 48.533304 -285.99511) (xy 47.034704 -285.99511)
			)
		)
	)
	(zone
		(layer "In2.Cu")
		(hatch none 0.5)
		(connect_pads
			(clearance 0)
		)
		(min_thickness 0.25)
		(keepout
			(tracks not_allowed)
			(vias allowed)
			(pads allowed)
			(copperpour not_allowed)
			(footprints allowed)
		)
		(placement
			(enabled no)
			(sheetname "")
		)
		(fill
			(thermal_gap 0.5)
			(thermal_bridge_width 0.5)
			(island_removal_mode 0)
		)
		(polygon
			(pts
				(xy 197.954646 -198.77532) (xy 199.453246 -198.77532) (xy 199.453246 -199.295258) (xy 197.954646 -199.295258)
			)
		)
	)
	(zone
		(layer "In2.Cu")
		(hatch none 0.5)
		(connect_pads
			(clearance 0)
		)
		(min_thickness 0.25)
		(keepout
			(tracks not_allowed)
			(vias allowed)
			(pads allowed)
			(copperpour not_allowed)
			(footprints allowed)
		)
		(placement
			(enabled no)
			(sheetname "")
		)
		(fill
			(thermal_gap 0.5)
			(thermal_bridge_width 0.5)
			(island_removal_mode 0)
		)
		(polygon
			(pts
				(xy 283.986732 -313.525154) (xy 285.485332 -313.525154) (xy 285.485332 -314.045092) (xy 283.986732 -314.045092)
			)
		)
	)
	(zone
		(layer "In2.Cu")
		(hatch none 0.5)
		(connect_pads
			(clearance 0)
		)
		(min_thickness 0.25)
		(keepout
			(tracks not_allowed)
			(vias allowed)
			(pads allowed)
			(copperpour not_allowed)
			(footprints allowed)
		)
		(placement
			(enabled no)
			(sheetname "")
		)
		(fill
			(thermal_gap 0.5)
			(thermal_bridge_width 0.5)
			(island_removal_mode 0)
		)
		(polygon
			(pts
				(xy 31.946596 -266.775184) (xy 33.445196 -266.775184) (xy 33.445196 -267.295122) (xy 31.946596 -267.295122)
			)
		)
	)
	(zone
		(layer "In2.Cu")
		(hatch none 0.5)
		(connect_pads
			(clearance 0)
		)
		(min_thickness 0.25)
		(keepout
			(tracks not_allowed)
			(vias allowed)
			(pads allowed)
			(copperpour not_allowed)
			(footprints allowed)
		)
		(placement
			(enabled no)
			(sheetname "")
		)
		(fill
			(thermal_gap 0.5)
			(thermal_bridge_width 0.5)
			(island_removal_mode 0)
		)
		(polygon
			(pts
				(xy 163.678616 -300.775116) (xy 165.177216 -300.775116) (xy 165.177216 -301.295054) (xy 163.678616 -301.295054)
			)
		)
	)
	(zone
		(layer "In2.Cu")
		(hatch none 0.5)
		(connect_pads
			(clearance 0)
		)
		(min_thickness 0.25)
		(keepout
			(tracks not_allowed)
			(vias allowed)
			(pads allowed)
			(copperpour not_allowed)
			(footprints allowed)
		)
		(placement
			(enabled no)
			(sheetname "")
		)
		(fill
			(thermal_gap 0.5)
			(thermal_bridge_width 0.5)
			(island_removal_mode 0)
		)
		(polygon
			(pts
				(xy 419.162738 -222.57512) (xy 420.661338 -222.57512) (xy 420.661338 -223.095058) (xy 419.162738 -223.095058)
			)
		)
	)
	(zone
		(layer "In2.Cu")
		(hatch none 0.5)
		(connect_pads
			(clearance 0)
		)
		(min_thickness 0.25)
		(keepout
			(tracks not_allowed)
			(vias allowed)
			(pads allowed)
			(copperpour not_allowed)
			(footprints allowed)
		)
		(placement
			(enabled no)
			(sheetname "")
		)
		(fill
			(thermal_gap 0.5)
			(thermal_bridge_width 0.5)
			(island_removal_mode 0)
		)
		(polygon
			(pts
				(xy 438.350914 -234.475274) (xy 439.849514 -234.475274) (xy 439.849514 -234.995212) (xy 438.350914 -234.995212)
			)
		)
	)
	(zone
		(layer "In2.Cu")
		(hatch none 0.5)
		(connect_pads
			(clearance 0)
		)
		(min_thickness 0.25)
		(keepout
			(tracks not_allowed)
			(vias allowed)
			(pads allowed)
			(copperpour not_allowed)
			(footprints allowed)
		)
		(placement
			(enabled no)
			(sheetname "")
		)
		(fill
			(thermal_gap 0.5)
			(thermal_bridge_width 0.5)
			(island_removal_mode 0)
		)
		(polygon
			(pts
				(xy 272.342864 -308.425342) (xy 273.841464 -308.425342) (xy 273.841464 -308.94528) (xy 272.342864 -308.94528)
			)
		)
	)
	(zone
		(layer "In2.Cu")
		(hatch none 0.5)
		(connect_pads
			(clearance 0)
		)
		(min_thickness 0.25)
		(keepout
			(tracks not_allowed)
			(vias allowed)
			(pads allowed)
			(copperpour not_allowed)
			(footprints allowed)
		)
		(placement
			(enabled no)
			(sheetname "")
		)
		(fill
			(thermal_gap 0.5)
			(thermal_bridge_width 0.5)
			(island_removal_mode 0)
		)
		(polygon
			(pts
				(xy 291.530786 -285.475172) (xy 293.029386 -285.475172) (xy 293.029386 -285.99511) (xy 291.530786 -285.99511)
			)
		)
	)
	(zone
		(layer "In2.Cu")
		(hatch none 0.5)
		(connect_pads
			(clearance 0)
		)
		(min_thickness 0.25)
		(keepout
			(tracks not_allowed)
			(vias allowed)
			(pads allowed)
			(copperpour not_allowed)
			(footprints allowed)
		)
		(placement
			(enabled no)
			(sheetname "")
		)
		(fill
			(thermal_gap 0.5)
			(thermal_bridge_width 0.5)
			(island_removal_mode 0)
		)
		(polygon
			(pts
				(xy 287.430718 -213.225126) (xy 288.929318 -213.225126) (xy 288.929318 -213.745064) (xy 287.430718 -213.745064)
			)
		)
	)
	(zone
		(layer "In2.Cu")
		(hatch none 0.5)
		(connect_pads
			(clearance 0)
		)
		(min_thickness 0.25)
		(keepout
			(tracks not_allowed)
			(vias allowed)
			(pads allowed)
			(copperpour not_allowed)
			(footprints allowed)
		)
		(placement
			(enabled no)
			(sheetname "")
		)
		(fill
			(thermal_gap 0.5)
			(thermal_bridge_width 0.5)
			(island_removal_mode 0)
		)
		(polygon
			(pts
				(xy 430.80686 -273.575272) (xy 432.30546 -273.575272) (xy 432.30546 -274.09521) (xy 430.80686 -274.09521)
			)
		)
	)
	(zone
		(layer "In2.Cu")
		(hatch none 0.5)
		(connect_pads
			(clearance 0)
		)
		(min_thickness 0.25)
		(keepout
			(tracks not_allowed)
			(vias allowed)
			(pads allowed)
			(copperpour not_allowed)
			(footprints allowed)
		)
		(placement
			(enabled no)
			(sheetname "")
		)
		(fill
			(thermal_gap 0.5)
			(thermal_bridge_width 0.5)
			(island_removal_mode 0)
		)
		(polygon
			(pts
				(xy 190.410846 -252.325124) (xy 191.909446 -252.325124) (xy 191.909446 -252.845062) (xy 190.410846 -252.845062)
			)
		)
	)
	(zone
		(layer "In2.Cu")
		(hatch none 0.5)
		(connect_pads
			(clearance 0)
		)
		(min_thickness 0.25)
		(keepout
			(tracks not_allowed)
			(vias allowed)
			(pads allowed)
			(copperpour not_allowed)
			(footprints allowed)
		)
		(placement
			(enabled no)
			(sheetname "")
		)
		(fill
			(thermal_gap 0.5)
			(thermal_bridge_width 0.5)
			(island_removal_mode 0)
		)
		(polygon
			(pts
				(xy 197.954646 -260.825234) (xy 199.453246 -260.825234) (xy 199.453246 -261.345172) (xy 197.954646 -261.345172)
			)
		)
	)
	(zone
		(layer "In2.Cu")
		(hatch none 0.5)
		(connect_pads
			(clearance 0)
		)
		(min_thickness 0.25)
		(keepout
			(tracks not_allowed)
			(vias allowed)
			(pads allowed)
			(copperpour not_allowed)
			(footprints allowed)
		)
		(placement
			(enabled no)
			(sheetname "")
		)
		(fill
			(thermal_gap 0.5)
			(thermal_bridge_width 0.5)
			(island_removal_mode 0)
		)
		(polygon
			(pts
				(xy 190.410846 -299.925232) (xy 191.909446 -299.925232) (xy 191.909446 -300.44517) (xy 190.410846 -300.44517)
			)
		)
	)
	(zone
		(layer "In2.Cu")
		(hatch none 0.5)
		(connect_pads
			(clearance 0)
		)
		(min_thickness 0.25)
		(keepout
			(tracks not_allowed)
			(vias allowed)
			(pads allowed)
			(copperpour not_allowed)
			(footprints allowed)
		)
		(placement
			(enabled no)
			(sheetname "")
		)
		(fill
			(thermal_gap 0.5)
			(thermal_bridge_width 0.5)
			(island_removal_mode 0)
		)
		(polygon
			(pts
				(xy 197.954646 -201.325226) (xy 199.453246 -201.325226) (xy 199.453246 -201.845164) (xy 197.954646 -201.845164)
			)
		)
	)
	(zone
		(layer "In2.Cu")
		(hatch none 0.5)
		(connect_pads
			(clearance 0)
		)
		(min_thickness 0.25)
		(keepout
			(tracks not_allowed)
			(vias allowed)
			(pads allowed)
			(copperpour not_allowed)
			(footprints allowed)
		)
		(placement
			(enabled no)
			(sheetname "")
		)
		(fill
			(thermal_gap 0.5)
			(thermal_bridge_width 0.5)
			(island_removal_mode 0)
		)
		(polygon
			(pts
				(xy 283.986732 -242.125246) (xy 285.485332 -242.125246) (xy 285.485332 -242.645184) (xy 283.986732 -242.645184)
			)
		)
	)
	(zone
		(layer "In2.Cu")
		(hatch none 0.5)
		(connect_pads
			(clearance 0)
		)
		(min_thickness 0.25)
		(keepout
			(tracks not_allowed)
			(vias allowed)
			(pads allowed)
			(copperpour not_allowed)
			(footprints allowed)
		)
		(placement
			(enabled no)
			(sheetname "")
		)
		(fill
			(thermal_gap 0.5)
			(thermal_bridge_width 0.5)
			(island_removal_mode 0)
		)
		(polygon
			(pts
				(xy 287.430718 -274.425156) (xy 288.929318 -274.425156) (xy 288.929318 -274.945094) (xy 287.430718 -274.945094)
			)
		)
	)
	(zone
		(layer "In2.Cu")
		(hatch none 0.5)
		(connect_pads
			(clearance 0)
		)
		(min_thickness 0.25)
		(keepout
			(tracks not_allowed)
			(vias allowed)
			(pads allowed)
			(copperpour not_allowed)
			(footprints allowed)
		)
		(placement
			(enabled no)
			(sheetname "")
		)
		(fill
			(thermal_gap 0.5)
			(thermal_bridge_width 0.5)
			(island_removal_mode 0)
		)
		(polygon
			(pts
				(xy 426.706792 -237.02518) (xy 428.205392 -237.02518) (xy 428.205392 -237.545118) (xy 426.706792 -237.545118)
			)
		)
	)
	(zone
		(layer "In2.Cu")
		(hatch none 0.5)
		(connect_pads
			(clearance 0)
		)
		(min_thickness 0.25)
		(keepout
			(tracks not_allowed)
			(vias allowed)
			(pads allowed)
			(copperpour not_allowed)
			(footprints allowed)
		)
		(placement
			(enabled no)
			(sheetname "")
		)
		(fill
			(thermal_gap 0.5)
			(thermal_bridge_width 0.5)
			(island_removal_mode 0)
		)
		(polygon
			(pts
				(xy 28.50261 -316.925198) (xy 30.00121 -316.925198) (xy 30.00121 -317.445136) (xy 28.50261 -317.445136)
			)
		)
	)
	(zone
		(layer "In2.Cu")
		(hatch none 0.5)
		(connect_pads
			(clearance 0)
		)
		(min_thickness 0.25)
		(keepout
			(tracks not_allowed)
			(vias allowed)
			(pads allowed)
			(copperpour not_allowed)
			(footprints allowed)
		)
		(placement
			(enabled no)
			(sheetname "")
		)
		(fill
			(thermal_gap 0.5)
			(thermal_bridge_width 0.5)
			(island_removal_mode 0)
		)
		(polygon
			(pts
				(xy 434.250846 -272.725134) (xy 435.749446 -272.725134) (xy 435.749446 -273.245072) (xy 434.250846 -273.245072)
			)
		)
	)
	(zone
		(layer "In2.Cu")
		(hatch none 0.5)
		(connect_pads
			(clearance 0)
		)
		(min_thickness 0.25)
		(keepout
			(tracks not_allowed)
			(vias allowed)
			(pads allowed)
			(copperpour not_allowed)
			(footprints allowed)
		)
		(placement
			(enabled no)
			(sheetname "")
		)
		(fill
			(thermal_gap 0.5)
			(thermal_bridge_width 0.5)
			(island_removal_mode 0)
		)
		(polygon
			(pts
				(xy 299.07484 -210.67522) (xy 300.57344 -210.67522) (xy 300.57344 -211.195158) (xy 299.07484 -211.195158)
			)
		)
	)
	(zone
		(layer "In2.Cu")
		(hatch none 0.5)
		(connect_pads
			(clearance 0)
		)
		(min_thickness 0.25)
		(keepout
			(tracks not_allowed)
			(vias allowed)
			(pads allowed)
			(copperpour not_allowed)
			(footprints allowed)
		)
		(placement
			(enabled no)
			(sheetname "")
		)
		(fill
			(thermal_gap 0.5)
			(thermal_bridge_width 0.5)
			(island_removal_mode 0)
		)
		(polygon
			(pts
				(xy 411.618684 -274.425156) (xy 413.117284 -274.425156) (xy 413.117284 -274.945094) (xy 411.618684 -274.945094)
			)
		)
	)
	(zone
		(layer "In2.Cu")
		(hatch none 0.5)
		(connect_pads
			(clearance 0)
		)
		(min_thickness 0.25)
		(keepout
			(tracks not_allowed)
			(vias allowed)
			(pads allowed)
			(copperpour not_allowed)
			(footprints allowed)
		)
		(placement
			(enabled no)
			(sheetname "")
		)
		(fill
			(thermal_gap 0.5)
			(thermal_bridge_width 0.5)
			(island_removal_mode 0)
		)
		(polygon
			(pts
				(xy 193.854578 -233.625136) (xy 195.353178 -233.625136) (xy 195.353178 -234.145074) (xy 193.854578 -234.145074)
			)
		)
	)
	(zone
		(layer "In2.Cu")
		(hatch none 0.5)
		(connect_pads
			(clearance 0)
		)
		(min_thickness 0.25)
		(keepout
			(tracks not_allowed)
			(vias allowed)
			(pads allowed)
			(copperpour not_allowed)
			(footprints allowed)
		)
		(placement
			(enabled no)
			(sheetname "")
		)
		(fill
			(thermal_gap 0.5)
			(thermal_bridge_width 0.5)
			(island_removal_mode 0)
		)
		(polygon
			(pts
				(xy 171.22267 -288.025332) (xy 172.72127 -288.025332) (xy 172.72127 -288.54527) (xy 171.22267 -288.54527)
			)
		)
	)
	(zone
		(layer "In2.Cu")
		(hatch none 0.5)
		(connect_pads
			(clearance 0)
		)
		(min_thickness 0.25)
		(keepout
			(tracks not_allowed)
			(vias allowed)
			(pads allowed)
			(copperpour not_allowed)
			(footprints allowed)
		)
		(placement
			(enabled no)
			(sheetname "")
		)
		(fill
			(thermal_gap 0.5)
			(thermal_bridge_width 0.5)
			(island_removal_mode 0)
		)
		(polygon
			(pts
				(xy 419.162738 -214.925148) (xy 420.661338 -214.925148) (xy 420.661338 -215.445086) (xy 419.162738 -215.445086)
			)
		)
	)
	(zone
		(layer "In2.Cu")
		(hatch none 0.5)
		(connect_pads
			(clearance 0)
		)
		(min_thickness 0.25)
		(keepout
			(tracks not_allowed)
			(vias allowed)
			(pads allowed)
			(copperpour not_allowed)
			(footprints allowed)
		)
		(placement
			(enabled no)
			(sheetname "")
		)
		(fill
			(thermal_gap 0.5)
			(thermal_bridge_width 0.5)
			(island_removal_mode 0)
		)
		(polygon
			(pts
				(xy 415.718752 -234.475274) (xy 417.217352 -234.475274) (xy 417.217352 -234.995212) (xy 415.718752 -234.995212)
			)
		)
	)
	(zone
		(layer "In2.Cu")
		(hatch none 0.5)
		(connect_pads
			(clearance 0)
		)
		(min_thickness 0.25)
		(keepout
			(tracks not_allowed)
			(vias allowed)
			(pads allowed)
			(copperpour not_allowed)
			(footprints allowed)
		)
		(placement
			(enabled no)
			(sheetname "")
		)
		(fill
			(thermal_gap 0.5)
			(thermal_bridge_width 0.5)
			(island_removal_mode 0)
		)
		(polygon
			(pts
				(xy 283.986732 -252.325124) (xy 285.485332 -252.325124) (xy 285.485332 -252.845062) (xy 283.986732 -252.845062)
			)
		)
	)
	(zone
		(layer "In2.Cu")
		(hatch none 0.5)
		(connect_pads
			(clearance 0)
		)
		(min_thickness 0.25)
		(keepout
			(tracks not_allowed)
			(vias allowed)
			(pads allowed)
			(copperpour not_allowed)
			(footprints allowed)
		)
		(placement
			(enabled no)
			(sheetname "")
		)
		(fill
			(thermal_gap 0.5)
			(thermal_bridge_width 0.5)
			(island_removal_mode 0)
		)
		(polygon
			(pts
				(xy 201.398632 -300.775116) (xy 202.897232 -300.775116) (xy 202.897232 -301.295054) (xy 201.398632 -301.295054)
			)
		)
	)
	(zone
		(layer "In2.Cu")
		(hatch none 0.5)
		(connect_pads
			(clearance 0)
		)
		(min_thickness 0.25)
		(keepout
			(tracks not_allowed)
			(vias allowed)
			(pads allowed)
			(copperpour not_allowed)
			(footprints allowed)
		)
		(placement
			(enabled no)
			(sheetname "")
		)
		(fill
			(thermal_gap 0.5)
			(thermal_bridge_width 0.5)
			(island_removal_mode 0)
		)
		(polygon
			(pts
				(xy 299.07484 -203.025248) (xy 300.57344 -203.025248) (xy 300.57344 -203.545186) (xy 299.07484 -203.545186)
			)
		)
	)
	(zone
		(layer "In2.Cu")
		(hatch none 0.5)
		(connect_pads
			(clearance 0)
		)
		(min_thickness 0.25)
		(keepout
			(tracks not_allowed)
			(vias allowed)
			(pads allowed)
			(copperpour not_allowed)
			(footprints allowed)
		)
		(placement
			(enabled no)
			(sheetname "")
		)
		(fill
			(thermal_gap 0.5)
			(thermal_bridge_width 0.5)
			(island_removal_mode 0)
		)
		(polygon
			(pts
				(xy 163.678616 -276.975316) (xy 165.177216 -276.975316) (xy 165.177216 -277.495254) (xy 163.678616 -277.495254)
			)
		)
	)
	(zone
		(layer "In2.Cu")
		(hatch none 0.5)
		(connect_pads
			(clearance 0)
		)
		(min_thickness 0.25)
		(keepout
			(tracks not_allowed)
			(vias allowed)
			(pads allowed)
			(copperpour not_allowed)
			(footprints allowed)
		)
		(placement
			(enabled no)
			(sheetname "")
		)
		(fill
			(thermal_gap 0.5)
			(thermal_bridge_width 0.5)
			(island_removal_mode 0)
		)
		(polygon
			(pts
				(xy 36.046664 -284.625288) (xy 37.545264 -284.625288) (xy 37.545264 -285.145226) (xy 36.046664 -285.145226)
			)
		)
	)
	(zone
		(layer "In2.Cu")
		(hatch none 0.5)
		(connect_pads
			(clearance 0)
		)
		(min_thickness 0.25)
		(keepout
			(tracks not_allowed)
			(vias allowed)
			(pads allowed)
			(copperpour not_allowed)
			(footprints allowed)
		)
		(placement
			(enabled no)
			(sheetname "")
		)
		(fill
			(thermal_gap 0.5)
			(thermal_bridge_width 0.5)
			(island_removal_mode 0)
		)
		(polygon
			(pts
				(xy 449.3387 -238.725202) (xy 450.8373 -238.725202) (xy 450.8373 -239.24514) (xy 449.3387 -239.24514)
			)
		)
	)
	(zone
		(layer "In2.Cu")
		(hatch none 0.5)
		(connect_pads
			(clearance 0)
		)
		(min_thickness 0.25)
		(keepout
			(tracks not_allowed)
			(vias allowed)
			(pads allowed)
			(copperpour not_allowed)
			(footprints allowed)
		)
		(placement
			(enabled no)
			(sheetname "")
		)
		(fill
			(thermal_gap 0.5)
			(thermal_bridge_width 0.5)
			(island_removal_mode 0)
		)
		(polygon
			(pts
				(xy 28.50261 -204.72527) (xy 30.00121 -204.72527) (xy 30.00121 -205.245208) (xy 28.50261 -205.245208)
			)
		)
	)
	(zone
		(layer "In2.Cu")
		(hatch none 0.5)
		(connect_pads
			(clearance 0)
		)
		(min_thickness 0.25)
		(keepout
			(tracks not_allowed)
			(vias allowed)
			(pads allowed)
			(copperpour not_allowed)
			(footprints allowed)
		)
		(placement
			(enabled no)
			(sheetname "")
		)
		(fill
			(thermal_gap 0.5)
			(thermal_bridge_width 0.5)
			(island_removal_mode 0)
		)
		(polygon
			(pts
				(xy 197.954646 -293.975282) (xy 199.453246 -293.975282) (xy 199.453246 -294.49522) (xy 197.954646 -294.49522)
			)
		)
	)
	(zone
		(layer "In2.Cu")
		(hatch none 0.5)
		(connect_pads
			(clearance 0)
		)
		(min_thickness 0.25)
		(keepout
			(tracks allowed)
			(vias allowed)
			(pads allowed)
			(copperpour allowed)
			(footprints allowed)
		)
		(placement
			(enabled no)
			(sheetname "")
		)
		(fill
			(thermal_gap 0.5)
			(thermal_bridge_width 0.5)
			(island_removal_mode 0)
		)
		(polygon
			(pts
				(xy 67.406012 -338.222082) (xy 67.406012 -337.599782) (xy 67.957192 -337.599782) (xy 67.957192 -338.222082)
			)
		)
	)
	(zone
		(layer "In2.Cu")
		(hatch none 0.5)
		(connect_pads
			(clearance 0)
		)
		(min_thickness 0.25)
		(keepout
			(tracks not_allowed)
			(vias allowed)
			(pads allowed)
			(copperpour not_allowed)
			(footprints allowed)
		)
		(placement
			(enabled no)
			(sheetname "")
		)
		(fill
			(thermal_gap 0.5)
			(thermal_bridge_width 0.5)
			(island_removal_mode 0)
		)
		(polygon
			(pts
				(xy 16.858742 -197.925182) (xy 18.357342 -197.925182) (xy 18.357342 -198.44512) (xy 16.858742 -198.44512)
			)
		)
	)
	(zone
		(layer "In2.Cu")
		(hatch none 0.5)
		(connect_pads
			(clearance 0)
		)
		(min_thickness 0.25)
		(keepout
			(tracks not_allowed)
			(vias allowed)
			(pads allowed)
			(copperpour not_allowed)
			(footprints allowed)
		)
		(placement
			(enabled no)
			(sheetname "")
		)
		(fill
			(thermal_gap 0.5)
			(thermal_bridge_width 0.5)
			(island_removal_mode 0)
		)
		(polygon
			(pts
				(xy 163.678616 -266.775184) (xy 165.177216 -266.775184) (xy 165.177216 -267.295122) (xy 163.678616 -267.295122)
			)
		)
	)
	(zone
		(layer "In2.Cu")
		(hatch none 0.5)
		(connect_pads
			(clearance 0)
		)
		(min_thickness 0.25)
		(keepout
			(tracks not_allowed)
			(vias allowed)
			(pads allowed)
			(copperpour not_allowed)
			(footprints allowed)
		)
		(placement
			(enabled no)
			(sheetname "")
		)
		(fill
			(thermal_gap 0.5)
			(thermal_bridge_width 0.5)
			(island_removal_mode 0)
		)
		(polygon
			(pts
				(xy 51.134772 -309.275226) (xy 52.633372 -309.275226) (xy 52.633372 -309.795164) (xy 51.134772 -309.795164)
			)
		)
	)
	(zone
		(layer "In2.Cu")
		(hatch none 0.5)
		(connect_pads
			(clearance 0)
		)
		(min_thickness 0.25)
		(keepout
			(tracks not_allowed)
			(vias allowed)
			(pads allowed)
			(copperpour not_allowed)
			(footprints allowed)
		)
		(placement
			(enabled no)
			(sheetname "")
		)
		(fill
			(thermal_gap 0.5)
			(thermal_bridge_width 0.5)
			(island_removal_mode 0)
		)
		(polygon
			(pts
				(xy 20.95881 -229.375208) (xy 22.45741 -229.375208) (xy 22.45741 -229.895146) (xy 20.95881 -229.895146)
			)
		)
	)
	(zone
		(layer "In2.Cu")
		(hatch none 0.5)
		(connect_pads
			(clearance 0)
		)
		(min_thickness 0.25)
		(keepout
			(tracks not_allowed)
			(vias allowed)
			(pads allowed)
			(copperpour not_allowed)
			(footprints allowed)
		)
		(placement
			(enabled no)
			(sheetname "")
		)
		(fill
			(thermal_gap 0.5)
			(thermal_bridge_width 0.5)
			(island_removal_mode 0)
		)
		(polygon
			(pts
				(xy 423.262806 -316.925198) (xy 424.761406 -316.925198) (xy 424.761406 -317.445136) (xy 423.262806 -317.445136)
			)
		)
	)
	(zone
		(layer "In2.Cu")
		(hatch none 0.5)
		(connect_pads
			(clearance 0)
		)
		(min_thickness 0.25)
		(keepout
			(tracks not_allowed)
			(vias allowed)
			(pads allowed)
			(copperpour not_allowed)
			(footprints allowed)
		)
		(placement
			(enabled no)
			(sheetname "")
		)
		(fill
			(thermal_gap 0.5)
			(thermal_bridge_width 0.5)
			(island_removal_mode 0)
		)
		(polygon
			(pts
				(xy 190.410846 -214.075264) (xy 191.909446 -214.075264) (xy 191.909446 -214.595202) (xy 190.410846 -214.595202)
			)
		)
	)
	(zone
		(layer "In2.Cu")
		(hatch none 0.5)
		(connect_pads
			(clearance 0)
		)
		(min_thickness 0.25)
		(keepout
			(tracks allowed)
			(vias allowed)
			(pads allowed)
			(copperpour allowed)
			(footprints allowed)
		)
		(placement
			(enabled no)
			(sheetname "")
		)
		(fill
			(thermal_gap 0.5)
			(thermal_bridge_width 0.5)
			(island_removal_mode 0)
		)
		(polygon
			(pts
				(xy 86.690962 -180.899562) (xy 86.690962 -180.353208) (xy 87.243412 -180.353208) (xy 87.243412 -180.899562)
			)
		)
	)
	(zone
		(layer "In2.Cu")
		(hatch none 0.5)
		(connect_pads
			(clearance 0)
		)
		(min_thickness 0.25)
		(keepout
			(tracks not_allowed)
			(vias allowed)
			(pads allowed)
			(copperpour not_allowed)
			(footprints allowed)
		)
		(placement
			(enabled no)
			(sheetname "")
		)
		(fill
			(thermal_gap 0.5)
			(thermal_bridge_width 0.5)
			(island_removal_mode 0)
		)
		(polygon
			(pts
				(xy 47.034704 -205.575154) (xy 48.533304 -205.575154) (xy 48.533304 -206.095092) (xy 47.034704 -206.095092)
			)
		)
	)
	(zone
		(layer "In2.Cu")
		(hatch none 0.5)
		(connect_pads
			(clearance 0)
		)
		(min_thickness 0.25)
		(keepout
			(tracks not_allowed)
			(vias allowed)
			(pads allowed)
			(copperpour not_allowed)
			(footprints allowed)
		)
		(placement
			(enabled no)
			(sheetname "")
		)
		(fill
			(thermal_gap 0.5)
			(thermal_bridge_width 0.5)
			(island_removal_mode 0)
		)
		(polygon
			(pts
				(xy 272.342864 -238.725202) (xy 273.841464 -238.725202) (xy 273.841464 -239.24514) (xy 272.342864 -239.24514)
			)
		)
	)
	(zone
		(layer "In2.Cu")
		(hatch none 0.5)
		(connect_pads
			(clearance 0)
		)
		(min_thickness 0.25)
		(keepout
			(tracks not_allowed)
			(vias allowed)
			(pads allowed)
			(copperpour not_allowed)
			(footprints allowed)
		)
		(placement
			(enabled no)
			(sheetname "")
		)
		(fill
			(thermal_gap 0.5)
			(thermal_bridge_width 0.5)
			(island_removal_mode 0)
		)
		(polygon
			(pts
				(xy 54.578758 -235.325158) (xy 56.077358 -235.325158) (xy 56.077358 -235.845096) (xy 54.578758 -235.845096)
			)
		)
	)
	(zone
		(layer "In2.Cu")
		(hatch none 0.5)
		(connect_pads
			(clearance 0)
		)
		(min_thickness 0.25)
		(keepout
			(tracks not_allowed)
			(vias allowed)
			(pads allowed)
			(copperpour not_allowed)
			(footprints allowed)
		)
		(placement
			(enabled no)
			(sheetname "")
		)
		(fill
			(thermal_gap 0.5)
			(thermal_bridge_width 0.5)
			(island_removal_mode 0)
		)
		(polygon
			(pts
				(xy 276.442932 -315.225176) (xy 277.941532 -315.225176) (xy 277.941532 -315.745114) (xy 276.442932 -315.745114)
			)
		)
	)
	(zone
		(layer "In2.Cu")
		(hatch none 0.5)
		(connect_pads
			(clearance 0)
		)
		(min_thickness 0.25)
		(keepout
			(tracks not_allowed)
			(vias allowed)
			(pads allowed)
			(copperpour not_allowed)
			(footprints allowed)
		)
		(placement
			(enabled no)
			(sheetname "")
		)
		(fill
			(thermal_gap 0.5)
			(thermal_bridge_width 0.5)
			(island_removal_mode 0)
		)
		(polygon
			(pts
				(xy 411.618684 -305.025298) (xy 413.117284 -305.025298) (xy 413.117284 -305.545236) (xy 411.618684 -305.545236)
			)
		)
	)
	(zone
		(layer "In2.Cu")
		(hatch none 0.5)
		(connect_pads
			(clearance 0)
		)
		(min_thickness 0.25)
		(keepout
			(tracks not_allowed)
			(vias allowed)
			(pads allowed)
			(copperpour not_allowed)
			(footprints allowed)
		)
		(placement
			(enabled no)
			(sheetname "")
		)
		(fill
			(thermal_gap 0.5)
			(thermal_bridge_width 0.5)
			(island_removal_mode 0)
		)
		(polygon
			(pts
				(xy 426.706792 -274.425156) (xy 428.205392 -274.425156) (xy 428.205392 -274.945094) (xy 426.706792 -274.945094)
			)
		)
	)
	(zone
		(layer "In2.Cu")
		(hatch none 0.5)
		(connect_pads
			(clearance 0)
		)
		(min_thickness 0.25)
		(keepout
			(tracks not_allowed)
			(vias allowed)
			(pads allowed)
			(copperpour not_allowed)
			(footprints allowed)
		)
		(placement
			(enabled no)
			(sheetname "")
		)
		(fill
			(thermal_gap 0.5)
			(thermal_bridge_width 0.5)
			(island_removal_mode 0)
		)
		(polygon
			(pts
				(xy 302.518826 -208.975198) (xy 304.017426 -208.975198) (xy 304.017426 -209.495136) (xy 302.518826 -209.495136)
			)
		)
	)
	(zone
		(layer "In2.Cu")
		(hatch none 0.5)
		(connect_pads
			(clearance 0)
		)
		(min_thickness 0.25)
		(keepout
			(tracks not_allowed)
			(vias allowed)
			(pads allowed)
			(copperpour not_allowed)
			(footprints allowed)
		)
		(placement
			(enabled no)
			(sheetname "")
		)
		(fill
			(thermal_gap 0.5)
			(thermal_bridge_width 0.5)
			(island_removal_mode 0)
		)
		(polygon
			(pts
				(xy 167.778684 -260.825234) (xy 169.277284 -260.825234) (xy 169.277284 -261.345172) (xy 167.778684 -261.345172)
			)
		)
	)
	(zone
		(layer "In2.Cu")
		(hatch none 0.5)
		(connect_pads
			(clearance 0)
		)
		(min_thickness 0.25)
		(keepout
			(tracks allowed)
			(vias allowed)
			(pads allowed)
			(copperpour allowed)
			(footprints allowed)
		)
		(placement
			(enabled no)
			(sheetname "")
		)
		(fill
			(thermal_gap 0.5)
			(thermal_bridge_width 0.5)
			(island_removal_mode 0)
		)
		(polygon
			(pts
				(xy 46.279054 -360.717592) (xy 45.776134 -360.717592) (xy 45.532294 -360.473752) (xy 45.532294 -358.921812)
				(xy 44.978574 -358.368092) (xy 44.978574 -355.342952) (xy 44.003214 -354.367592) (xy 17.450054 -354.367592)
				(xy 13.609574 -350.527112) (xy 13.609574 -343.270332) (xy 16.804894 -340.075012) (xy 16.804894 -333.277972)
				(xy 17.925034 -332.157832) (xy 18.981674 -332.157832) (xy 19.151854 -332.328012) (xy 19.151854 -332.658212)
				(xy 18.730214 -333.079852) (xy 18.189194 -333.079852) (xy 17.594834 -333.674212) (xy 17.594834 -340.458552)
				(xy 14.323314 -343.730072) (xy 14.323314 -350.118172) (xy 17.754854 -353.549712) (xy 44.280074 -353.549712)
				(xy 45.717714 -354.987352) (xy 45.717714 -357.943912) (xy 46.299374 -358.525572) (xy 46.299374 -360.252772)
				(xy 46.279054 -360.273092)
			)
		)
	)
	(zone
		(layer "In2.Cu")
		(hatch none 0.5)
		(connect_pads
			(clearance 0)
		)
		(min_thickness 0.25)
		(keepout
			(tracks not_allowed)
			(vias allowed)
			(pads allowed)
			(copperpour not_allowed)
			(footprints allowed)
		)
		(placement
			(enabled no)
			(sheetname "")
		)
		(fill
			(thermal_gap 0.5)
			(thermal_bridge_width 0.5)
			(island_removal_mode 0)
		)
		(polygon
			(pts
				(xy 302.518826 -210.67522) (xy 304.017426 -210.67522) (xy 304.017426 -211.195158) (xy 302.518826 -211.195158)
			)
		)
	)
	(zone
		(layer "In2.Cu")
		(hatch none 0.5)
		(connect_pads
			(clearance 0)
		)
		(min_thickness 0.25)
		(keepout
			(tracks not_allowed)
			(vias allowed)
			(pads allowed)
			(copperpour not_allowed)
			(footprints allowed)
		)
		(placement
			(enabled no)
			(sheetname "")
		)
		(fill
			(thermal_gap 0.5)
			(thermal_bridge_width 0.5)
			(island_removal_mode 0)
		)
		(polygon
			(pts
				(xy 24.402542 -203.875132) (xy 25.901142 -203.875132) (xy 25.901142 -204.39507) (xy 24.402542 -204.39507)
			)
		)
	)
	(zone
		(layer "In2.Cu")
		(hatch none 0.5)
		(connect_pads
			(clearance 0)
		)
		(min_thickness 0.25)
		(keepout
			(tracks not_allowed)
			(vias allowed)
			(pads allowed)
			(copperpour not_allowed)
			(footprints allowed)
		)
		(placement
			(enabled no)
			(sheetname "")
		)
		(fill
			(thermal_gap 0.5)
			(thermal_bridge_width 0.5)
			(island_removal_mode 0)
		)
		(polygon
			(pts
				(xy 283.986732 -217.475308) (xy 285.485332 -217.475308) (xy 285.485332 -217.995246) (xy 283.986732 -217.995246)
			)
		)
	)
	(zone
		(layer "In2.Cu")
		(hatch none 0.5)
		(connect_pads
			(clearance 0)
		)
		(min_thickness 0.25)
		(keepout
			(tracks not_allowed)
			(vias allowed)
			(pads allowed)
			(copperpour not_allowed)
			(footprints allowed)
		)
		(placement
			(enabled no)
			(sheetname "")
		)
		(fill
			(thermal_gap 0.5)
			(thermal_bridge_width 0.5)
			(island_removal_mode 0)
		)
		(polygon
			(pts
				(xy 287.430718 -302.475138) (xy 288.929318 -302.475138) (xy 288.929318 -302.995076) (xy 287.430718 -302.995076)
			)
		)
	)
	(zone
		(layer "In2.Cu")
		(hatch none 0.5)
		(connect_pads
			(clearance 0)
		)
		(min_thickness 0.25)
		(keepout
			(tracks not_allowed)
			(vias allowed)
			(pads allowed)
			(copperpour not_allowed)
			(footprints allowed)
		)
		(placement
			(enabled no)
			(sheetname "")
		)
		(fill
			(thermal_gap 0.5)
			(thermal_bridge_width 0.5)
			(island_removal_mode 0)
		)
		(polygon
			(pts
				(xy 24.402542 -300.775116) (xy 25.901142 -300.775116) (xy 25.901142 -301.295054) (xy 24.402542 -301.295054)
			)
		)
	)
	(zone
		(layer "In2.Cu")
		(hatch none 0.5)
		(connect_pads
			(clearance 0)
		)
		(min_thickness 0.25)
		(keepout
			(tracks not_allowed)
			(vias allowed)
			(pads allowed)
			(copperpour not_allowed)
			(footprints allowed)
		)
		(placement
			(enabled no)
			(sheetname "")
		)
		(fill
			(thermal_gap 0.5)
			(thermal_bridge_width 0.5)
			(island_removal_mode 0)
		)
		(polygon
			(pts
				(xy 190.410846 -305.875182) (xy 191.909446 -305.875182) (xy 191.909446 -306.39512) (xy 190.410846 -306.39512)
			)
		)
	)
	(zone
		(layer "In2.Cu")
		(hatch none 0.5)
		(connect_pads
			(clearance 0)
		)
		(min_thickness 0.25)
		(keepout
			(tracks not_allowed)
			(vias allowed)
			(pads allowed)
			(copperpour not_allowed)
			(footprints allowed)
		)
		(placement
			(enabled no)
			(sheetname "")
		)
		(fill
			(thermal_gap 0.5)
			(thermal_bridge_width 0.5)
			(island_removal_mode 0)
		)
		(polygon
			(pts
				(xy 51.134772 -276.125178) (xy 52.633372 -276.125178) (xy 52.633372 -276.645116) (xy 51.134772 -276.645116)
			)
		)
	)
	(zone
		(layer "In2.Cu")
		(hatch none 0.5)
		(connect_pads
			(clearance 0)
		)
		(min_thickness 0.25)
		(keepout
			(tracks not_allowed)
			(vias allowed)
			(pads allowed)
			(copperpour not_allowed)
			(footprints allowed)
		)
		(placement
			(enabled no)
			(sheetname "")
		)
		(fill
			(thermal_gap 0.5)
			(thermal_bridge_width 0.5)
			(island_removal_mode 0)
		)
		(polygon
			(pts
				(xy 279.886664 -224.275142) (xy 281.385264 -224.275142) (xy 281.385264 -224.79508) (xy 279.886664 -224.79508)
			)
		)
	)
	(zone
		(layer "In2.Cu")
		(hatch none 0.5)
		(connect_pads
			(clearance 0)
		)
		(min_thickness 0.25)
		(keepout
			(tracks not_allowed)
			(vias allowed)
			(pads allowed)
			(copperpour not_allowed)
			(footprints allowed)
		)
		(placement
			(enabled no)
			(sheetname "")
		)
		(fill
			(thermal_gap 0.5)
			(thermal_bridge_width 0.5)
			(island_removal_mode 0)
		)
		(polygon
			(pts
				(xy 58.678826 -270.175228) (xy 60.177426 -270.175228) (xy 60.177426 -270.695166) (xy 58.678826 -270.695166)
			)
		)
	)
	(zone
		(layer "In2.Cu")
		(hatch none 0.5)
		(connect_pads
			(clearance 0)
		)
		(min_thickness 0.25)
		(keepout
			(tracks not_allowed)
			(vias allowed)
			(pads allowed)
			(copperpour not_allowed)
			(footprints allowed)
		)
		(placement
			(enabled no)
			(sheetname "")
		)
		(fill
			(thermal_gap 0.5)
			(thermal_bridge_width 0.5)
			(island_removal_mode 0)
		)
		(polygon
			(pts
				(xy 272.342864 -230.225346) (xy 273.841464 -230.225346) (xy 273.841464 -230.745284) (xy 272.342864 -230.745284)
			)
		)
	)
	(zone
		(layer "In2.Cu")
		(hatch none 0.5)
		(connect_pads
			(clearance 0)
		)
		(min_thickness 0.25)
		(keepout
			(tracks not_allowed)
			(vias allowed)
			(pads allowed)
			(copperpour not_allowed)
			(footprints allowed)
		)
		(placement
			(enabled no)
			(sheetname "")
		)
		(fill
			(thermal_gap 0.5)
			(thermal_bridge_width 0.5)
			(island_removal_mode 0)
		)
		(polygon
			(pts
				(xy 423.262806 -225.12528) (xy 424.761406 -225.12528) (xy 424.761406 -225.645218) (xy 423.262806 -225.645218)
			)
		)
	)
	(zone
		(layer "In2.Cu")
		(hatch none 0.5)
		(connect_pads
			(clearance 0)
		)
		(min_thickness 0.25)
		(keepout
			(tracks not_allowed)
			(vias allowed)
			(pads allowed)
			(copperpour not_allowed)
			(footprints allowed)
		)
		(placement
			(enabled no)
			(sheetname "")
		)
		(fill
			(thermal_gap 0.5)
			(thermal_bridge_width 0.5)
			(island_removal_mode 0)
		)
		(polygon
			(pts
				(xy 190.410846 -201.325226) (xy 191.909446 -201.325226) (xy 191.909446 -201.845164) (xy 190.410846 -201.845164)
			)
		)
	)
	(zone
		(layer "In2.Cu")
		(hatch none 0.5)
		(connect_pads
			(clearance 0)
		)
		(min_thickness 0.25)
		(keepout
			(tracks not_allowed)
			(vias allowed)
			(pads allowed)
			(copperpour not_allowed)
			(footprints allowed)
		)
		(placement
			(enabled no)
			(sheetname "")
		)
		(fill
			(thermal_gap 0.5)
			(thermal_bridge_width 0.5)
			(island_removal_mode 0)
		)
		(polygon
			(pts
				(xy 272.342864 -306.72532) (xy 273.841464 -306.72532) (xy 273.841464 -307.245258) (xy 272.342864 -307.245258)
			)
		)
	)
	(zone
		(layer "In2.Cu")
		(hatch none 0.5)
		(connect_pads
			(clearance 0)
		)
		(min_thickness 0.25)
		(keepout
			(tracks not_allowed)
			(vias allowed)
			(pads allowed)
			(copperpour not_allowed)
			(footprints allowed)
		)
		(placement
			(enabled no)
			(sheetname "")
		)
		(fill
			(thermal_gap 0.5)
			(thermal_bridge_width 0.5)
			(island_removal_mode 0)
		)
		(polygon
			(pts
				(xy 268.898878 -277.8252) (xy 270.397478 -277.8252) (xy 270.397478 -278.345138) (xy 268.898878 -278.345138)
			)
		)
	)
	(zone
		(layer "In2.Cu")
		(hatch none 0.5)
		(connect_pads
			(clearance 0)
		)
		(min_thickness 0.25)
		(keepout
			(tracks allowed)
			(vias allowed)
			(pads allowed)
			(copperpour allowed)
			(footprints allowed)
		)
		(placement
			(enabled no)
			(sheetname "")
		)
		(fill
			(thermal_gap 0.5)
			(thermal_bridge_width 0.5)
			(island_removal_mode 0)
		)
		(polygon
			(pts
				(xy 98.32721 -337.786218) (xy 98.32721 -337.163918) (xy 98.87839 -337.163918) (xy 98.87839 -337.786218)
			)
		)
	)
	(zone
		(layer "In2.Cu")
		(hatch none 0.5)
		(connect_pads
			(clearance 0)
		)
		(min_thickness 0.25)
		(keepout
			(tracks allowed)
			(vias allowed)
			(pads allowed)
			(copperpour allowed)
			(footprints allowed)
		)
		(placement
			(enabled no)
			(sheetname "")
		)
		(fill
			(thermal_gap 0.5)
			(thermal_bridge_width 0.5)
			(island_removal_mode 0)
		)
		(polygon
			(pts
				(xy 165.241732 -370.180108) (xy 163.950396 -370.180108) (xy 157.777688 -364.0074) (xy 157.777688 -334.33639)
				(arc
					(start 157.704028 -334.26273)
					(mid 157.517319 -333.900522)
					(end 157.75178 -333.567278)
				)
				(xy 158.587948 -332.73111) (xy 158.587948 -326.743568) (xy 156.978604 -325.134224)
				(arc
					(start 156.978604 -325.133208)
					(mid 156.778623 -324.783894)
					(end 156.978604 -324.434454)
				)
				(xy 157.01264 -324.400418) (xy 157.32379 -324.400418) (xy 159.36722 -326.443848) (xy 159.36722 -326.82307)
				(xy 159.36722 -333.03083) (xy 158.540196 -333.857854) (xy 158.540196 -363.690916) (xy 164.266372 -369.417092)
				(xy 165.241732 -369.417092)
			)
		)
	)
	(zone
		(layer "In2.Cu")
		(hatch none 0.5)
		(connect_pads
			(clearance 0)
		)
		(min_thickness 0.25)
		(keepout
			(tracks not_allowed)
			(vias allowed)
			(pads allowed)
			(copperpour not_allowed)
			(footprints allowed)
		)
		(placement
			(enabled no)
			(sheetname "")
		)
		(fill
			(thermal_gap 0.5)
			(thermal_bridge_width 0.5)
			(island_removal_mode 0)
		)
		(polygon
			(pts
				(xy 291.530786 -281.225244) (xy 293.029386 -281.225244) (xy 293.029386 -281.745182) (xy 291.530786 -281.745182)
			)
		)
	)
	(zone
		(layer "In2.Cu")
		(hatch none 0.5)
		(connect_pads
			(clearance 0)
		)
		(min_thickness 0.25)
		(keepout
			(tracks not_allowed)
			(vias allowed)
			(pads allowed)
			(copperpour not_allowed)
			(footprints allowed)
		)
		(placement
			(enabled no)
			(sheetname "")
		)
		(fill
			(thermal_gap 0.5)
			(thermal_bridge_width 0.5)
			(island_removal_mode 0)
		)
		(polygon
			(pts
				(xy 47.034704 -246.375174) (xy 48.533304 -246.375174) (xy 48.533304 -246.895112) (xy 47.034704 -246.895112)
			)
		)
	)
	(zone
		(layer "In2.Cu")
		(hatch none 0.5)
		(connect_pads
			(clearance 0)
		)
		(min_thickness 0.25)
		(keepout
			(tracks not_allowed)
			(vias allowed)
			(pads allowed)
			(copperpour not_allowed)
			(footprints allowed)
		)
		(placement
			(enabled no)
			(sheetname "")
		)
		(fill
			(thermal_gap 0.5)
			(thermal_bridge_width 0.5)
			(island_removal_mode 0)
		)
		(polygon
			(pts
				(xy 299.07484 -293.975282) (xy 300.57344 -293.975282) (xy 300.57344 -294.49522) (xy 299.07484 -294.49522)
			)
		)
	)
	(zone
		(layer "In2.Cu")
		(hatch none 0.5)
		(connect_pads
			(clearance 0)
		)
		(min_thickness 0.25)
		(keepout
			(tracks not_allowed)
			(vias allowed)
			(pads allowed)
			(copperpour not_allowed)
			(footprints allowed)
		)
		(placement
			(enabled no)
			(sheetname "")
		)
		(fill
			(thermal_gap 0.5)
			(thermal_bridge_width 0.5)
			(island_removal_mode 0)
		)
		(polygon
			(pts
				(xy 51.134772 -226.825302) (xy 52.633372 -226.825302) (xy 52.633372 -227.34524) (xy 51.134772 -227.34524)
			)
		)
	)
	(zone
		(layer "In2.Cu")
		(hatch none 0.5)
		(connect_pads
			(clearance 0)
		)
		(min_thickness 0.25)
		(keepout
			(tracks not_allowed)
			(vias allowed)
			(pads allowed)
			(copperpour not_allowed)
			(footprints allowed)
		)
		(placement
			(enabled no)
			(sheetname "")
		)
		(fill
			(thermal_gap 0.5)
			(thermal_bridge_width 0.5)
			(island_removal_mode 0)
		)
		(polygon
			(pts
				(xy 51.134772 -269.325344) (xy 52.633372 -269.325344) (xy 52.633372 -269.845282) (xy 51.134772 -269.845282)
			)
		)
	)
	(zone
		(layer "In2.Cu")
		(hatch none 0.5)
		(connect_pads
			(clearance 0)
		)
		(min_thickness 0.25)
		(keepout
			(tracks not_allowed)
			(vias allowed)
			(pads allowed)
			(copperpour not_allowed)
			(footprints allowed)
		)
		(placement
			(enabled no)
			(sheetname "")
		)
		(fill
			(thermal_gap 0.5)
			(thermal_bridge_width 0.5)
			(island_removal_mode 0)
		)
		(polygon
			(pts
				(xy 163.678616 -261.675118) (xy 165.177216 -261.675118) (xy 165.177216 -262.195056) (xy 163.678616 -262.195056)
			)
		)
	)
	(zone
		(layer "In2.Cu")
		(hatch none 0.5)
		(connect_pads
			(clearance 0)
		)
		(min_thickness 0.25)
		(keepout
			(tracks not_allowed)
			(vias allowed)
			(pads allowed)
			(copperpour not_allowed)
			(footprints allowed)
		)
		(placement
			(enabled no)
			(sheetname "")
		)
		(fill
			(thermal_gap 0.5)
			(thermal_bridge_width 0.5)
			(island_removal_mode 0)
		)
		(polygon
			(pts
				(xy 272.342864 -224.275142) (xy 273.841464 -224.275142) (xy 273.841464 -224.79508) (xy 272.342864 -224.79508)
			)
		)
	)
	(zone
		(layer "In2.Cu")
		(hatch none 0.5)
		(connect_pads
			(clearance 0)
		)
		(min_thickness 0.25)
		(keepout
			(tracks not_allowed)
			(vias allowed)
			(pads allowed)
			(copperpour not_allowed)
			(footprints allowed)
		)
		(placement
			(enabled no)
			(sheetname "")
		)
		(fill
			(thermal_gap 0.5)
			(thermal_bridge_width 0.5)
			(island_removal_mode 0)
		)
		(polygon
			(pts
				(arc
					(start 427.46168 -11.91768)
					(mid 427.439362 -11.971562)
					(end 427.38548 -11.99388)
				)
				(arc
					(start 426.348906 -11.99388)
					(mid 426.295024 -11.971562)
					(end 426.272706 -11.91768)
				)
				(arc
					(start 426.272706 -10.51814)
					(mid 426.295024 -10.464258)
					(end 426.348906 -10.44194)
				)
				(arc
					(start 427.38548 -10.44194)
					(mid 427.439362 -10.464258)
					(end 427.46168 -10.51814)
				)
			)
		)
	)
	(zone
		(layer "In2.Cu")
		(hatch none 0.5)
		(connect_pads
			(clearance 0)
		)
		(min_thickness 0.25)
		(keepout
			(tracks not_allowed)
			(vias allowed)
			(pads allowed)
			(copperpour not_allowed)
			(footprints allowed)
		)
		(placement
			(enabled no)
			(sheetname "")
		)
		(fill
			(thermal_gap 0.5)
			(thermal_bridge_width 0.5)
			(island_removal_mode 0)
		)
		(polygon
			(pts
				(xy 419.162738 -274.425156) (xy 420.661338 -274.425156) (xy 420.661338 -274.945094) (xy 419.162738 -274.945094)
			)
		)
	)
	(zone
		(layer "In2.Cu")
		(hatch none 0.5)
		(connect_pads
			(clearance 0)
		)
		(min_thickness 0.25)
		(keepout
			(tracks not_allowed)
			(vias allowed)
			(pads allowed)
			(copperpour not_allowed)
			(footprints allowed)
		)
		(placement
			(enabled no)
			(sheetname "")
		)
		(fill
			(thermal_gap 0.5)
			(thermal_bridge_width 0.5)
			(island_removal_mode 0)
		)
		(polygon
			(pts
				(xy 430.80686 -250.625102) (xy 432.30546 -250.625102) (xy 432.30546 -251.14504) (xy 430.80686 -251.14504)
			)
		)
	)
	(zone
		(layer "In2.Cu")
		(hatch none 0.5)
		(connect_pads
			(clearance 0)
		)
		(min_thickness 0.25)
		(keepout
			(tracks not_allowed)
			(vias allowed)
			(pads allowed)
			(copperpour not_allowed)
			(footprints allowed)
		)
		(placement
			(enabled no)
			(sheetname "")
		)
		(fill
			(thermal_gap 0.5)
			(thermal_bridge_width 0.5)
			(island_removal_mode 0)
		)
		(polygon
			(pts
				(xy 306.618894 -214.075264) (xy 308.117494 -214.075264) (xy 308.117494 -214.595202) (xy 306.618894 -214.595202)
			)
		)
	)
	(zone
		(layer "In2.Cu")
		(hatch none 0.5)
		(connect_pads
			(clearance 0)
		)
		(min_thickness 0.25)
		(keepout
			(tracks not_allowed)
			(vias allowed)
			(pads allowed)
			(copperpour not_allowed)
			(footprints allowed)
		)
		(placement
			(enabled no)
			(sheetname "")
		)
		(fill
			(thermal_gap 0.5)
			(thermal_bridge_width 0.5)
			(island_removal_mode 0)
		)
		(polygon
			(pts
				(xy 16.858742 -211.525104) (xy 18.357342 -211.525104) (xy 18.357342 -212.045042) (xy 16.858742 -212.045042)
			)
		)
	)
	(zone
		(layer "In2.Cu")
		(hatch none 0.5)
		(connect_pads
			(clearance 0)
		)
		(min_thickness 0.25)
		(keepout
			(tracks not_allowed)
			(vias allowed)
			(pads allowed)
			(copperpour not_allowed)
			(footprints allowed)
		)
		(placement
			(enabled no)
			(sheetname "")
		)
		(fill
			(thermal_gap 0.5)
			(thermal_bridge_width 0.5)
			(island_removal_mode 0)
		)
		(polygon
			(pts
				(xy 276.442932 -313.525154) (xy 277.941532 -313.525154) (xy 277.941532 -314.045092) (xy 276.442932 -314.045092)
			)
		)
	)
	(zone
		(layer "In2.Cu")
		(hatch none 0.5)
		(connect_pads
			(clearance 0)
		)
		(min_thickness 0.25)
		(keepout
			(tracks not_allowed)
			(vias allowed)
			(pads allowed)
			(copperpour not_allowed)
			(footprints allowed)
		)
		(placement
			(enabled no)
			(sheetname "")
		)
		(fill
			(thermal_gap 0.5)
			(thermal_bridge_width 0.5)
			(island_removal_mode 0)
		)
		(polygon
			(pts
				(xy 193.854578 -197.925182) (xy 195.353178 -197.925182) (xy 195.353178 -198.44512) (xy 193.854578 -198.44512)
			)
		)
	)
	(zone
		(layer "In2.Cu")
		(hatch none 0.5)
		(connect_pads
			(clearance 0)
		)
		(min_thickness 0.25)
		(keepout
			(tracks not_allowed)
			(vias allowed)
			(pads allowed)
			(copperpour not_allowed)
			(footprints allowed)
		)
		(placement
			(enabled no)
			(sheetname "")
		)
		(fill
			(thermal_gap 0.5)
			(thermal_bridge_width 0.5)
			(island_removal_mode 0)
		)
		(polygon
			(pts
				(xy 54.578758 -220.875098) (xy 56.077358 -220.875098) (xy 56.077358 -221.395036) (xy 54.578758 -221.395036)
			)
		)
	)
	(zone
		(layer "In2.Cu")
		(hatch none 0.5)
		(connect_pads
			(clearance 0)
		)
		(min_thickness 0.25)
		(keepout
			(tracks not_allowed)
			(vias allowed)
			(pads allowed)
			(copperpour not_allowed)
			(footprints allowed)
		)
		(placement
			(enabled no)
			(sheetname "")
		)
		(fill
			(thermal_gap 0.5)
			(thermal_bridge_width 0.5)
			(island_removal_mode 0)
		)
		(polygon
			(pts
				(xy 453.438768 -292.27526) (xy 454.937368 -292.27526) (xy 454.937368 -292.795198) (xy 453.438768 -292.795198)
			)
		)
	)
	(zone
		(layer "In2.Cu")
		(hatch none 0.5)
		(connect_pads
			(clearance 0)
		)
		(min_thickness 0.25)
		(keepout
			(tracks not_allowed)
			(vias allowed)
			(pads allowed)
			(copperpour not_allowed)
			(footprints allowed)
		)
		(placement
			(enabled no)
			(sheetname "")
		)
		(fill
			(thermal_gap 0.5)
			(thermal_bridge_width 0.5)
			(island_removal_mode 0)
		)
		(polygon
			(pts
				(xy 24.402542 -276.125178) (xy 25.901142 -276.125178) (xy 25.901142 -276.645116) (xy 24.402542 -276.645116)
			)
		)
	)
	(zone
		(layer "In2.Cu")
		(hatch none 0.5)
		(connect_pads
			(clearance 0)
		)
		(min_thickness 0.25)
		(keepout
			(tracks not_allowed)
			(vias allowed)
			(pads allowed)
			(copperpour not_allowed)
			(footprints allowed)
		)
		(placement
			(enabled no)
			(sheetname "")
		)
		(fill
			(thermal_gap 0.5)
			(thermal_bridge_width 0.5)
			(island_removal_mode 0)
		)
		(polygon
			(pts
				(xy 163.678616 -222.57512) (xy 165.177216 -222.57512) (xy 165.177216 -223.095058) (xy 163.678616 -223.095058)
			)
		)
	)
	(zone
		(layer "In2.Cu")
		(hatch none 0.5)
		(connect_pads
			(clearance 0)
		)
		(min_thickness 0.25)
		(keepout
			(tracks not_allowed)
			(vias allowed)
			(pads allowed)
			(copperpour not_allowed)
			(footprints allowed)
		)
		(placement
			(enabled no)
			(sheetname "")
		)
		(fill
			(thermal_gap 0.5)
			(thermal_bridge_width 0.5)
			(island_removal_mode 0)
		)
		(polygon
			(pts
				(xy 445.894968 -214.075264) (xy 447.393568 -214.075264) (xy 447.393568 -214.595202) (xy 445.894968 -214.595202)
			)
		)
	)
	(zone
		(layer "In2.Cu")
		(hatch none 0.5)
		(connect_pads
			(clearance 0)
		)
		(min_thickness 0.25)
		(keepout
			(tracks not_allowed)
			(vias allowed)
			(pads allowed)
			(copperpour not_allowed)
			(footprints allowed)
		)
		(placement
			(enabled no)
			(sheetname "")
		)
		(fill
			(thermal_gap 0.5)
			(thermal_bridge_width 0.5)
			(island_removal_mode 0)
		)
		(polygon
			(pts
				(xy 186.310778 -248.075196) (xy 187.809378 -248.075196) (xy 187.809378 -248.595134) (xy 186.310778 -248.595134)
			)
		)
	)
	(zone
		(layer "In2.Cu")
		(hatch none 0.5)
		(connect_pads
			(clearance 0)
		)
		(min_thickness 0.25)
		(keepout
			(tracks not_allowed)
			(vias allowed)
			(pads allowed)
			(copperpour not_allowed)
			(footprints allowed)
		)
		(placement
			(enabled no)
			(sheetname "")
		)
		(fill
			(thermal_gap 0.5)
			(thermal_bridge_width 0.5)
			(island_removal_mode 0)
		)
		(polygon
			(pts
				(xy 438.350914 -316.925198) (xy 439.849514 -316.925198) (xy 439.849514 -317.445136) (xy 438.350914 -317.445136)
			)
		)
	)
	(zone
		(layer "In2.Cu")
		(hatch none 0.5)
		(connect_pads
			(clearance 0)
		)
		(min_thickness 0.25)
		(keepout
			(tracks not_allowed)
			(vias allowed)
			(pads allowed)
			(copperpour not_allowed)
			(footprints allowed)
		)
		(placement
			(enabled no)
			(sheetname "")
		)
		(fill
			(thermal_gap 0.5)
			(thermal_bridge_width 0.5)
			(island_removal_mode 0)
		)
		(polygon
			(pts
				(xy 302.518826 -254.025146) (xy 304.017426 -254.025146) (xy 304.017426 -254.545084) (xy 302.518826 -254.545084)
			)
		)
	)
	(zone
		(layer "In2.Cu")
		(hatch none 0.5)
		(connect_pads
			(clearance 0)
		)
		(min_thickness 0.25)
		(keepout
			(tracks not_allowed)
			(vias allowed)
			(pads allowed)
			(copperpour not_allowed)
			(footprints allowed)
		)
		(placement
			(enabled no)
			(sheetname "")
		)
		(fill
			(thermal_gap 0.5)
			(thermal_bridge_width 0.5)
			(island_removal_mode 0)
		)
		(polygon
			(pts
				(xy 272.342864 -242.97513) (xy 273.841464 -242.97513) (xy 273.841464 -243.495068) (xy 272.342864 -243.495068)
			)
		)
	)
	(zone
		(layer "In2.Cu")
		(hatch none 0.5)
		(connect_pads
			(clearance 0)
		)
		(min_thickness 0.25)
		(keepout
			(tracks not_allowed)
			(vias allowed)
			(pads allowed)
			(copperpour not_allowed)
			(footprints allowed)
		)
		(placement
			(enabled no)
			(sheetname "")
		)
		(fill
			(thermal_gap 0.5)
			(thermal_bridge_width 0.5)
			(island_removal_mode 0)
		)
		(polygon
			(pts
				(xy 411.618684 -302.475138) (xy 413.117284 -302.475138) (xy 413.117284 -302.995076) (xy 411.618684 -302.995076)
			)
		)
	)
	(zone
		(layer "In2.Cu")
		(hatch none 0.5)
		(connect_pads
			(clearance 0)
		)
		(min_thickness 0.25)
		(keepout
			(tracks not_allowed)
			(vias allowed)
			(pads allowed)
			(copperpour not_allowed)
			(footprints allowed)
		)
		(placement
			(enabled no)
			(sheetname "")
		)
		(fill
			(thermal_gap 0.5)
			(thermal_bridge_width 0.5)
			(island_removal_mode 0)
		)
		(polygon
			(pts
				(xy 171.22267 -254.025146) (xy 172.72127 -254.025146) (xy 172.72127 -254.545084) (xy 171.22267 -254.545084)
			)
		)
	)
	(zone
		(layer "In2.Cu")
		(hatch none 0.5)
		(connect_pads
			(clearance 0)
		)
		(min_thickness 0.25)
		(keepout
			(tracks allowed)
			(vias allowed)
			(pads allowed)
			(copperpour allowed)
			(footprints allowed)
		)
		(placement
			(enabled no)
			(sheetname "")
		)
		(fill
			(thermal_gap 0.5)
			(thermal_bridge_width 0.5)
			(island_removal_mode 0)
		)
		(polygon
			(pts
				(xy 186.352434 -354.433378) (xy 186.352434 -353.811078) (xy 186.903614 -353.811078) (xy 186.903614 -354.433378)
			)
		)
	)
	(zone
		(layer "In2.Cu")
		(hatch none 0.5)
		(connect_pads
			(clearance 0)
		)
		(min_thickness 0.25)
		(keepout
			(tracks not_allowed)
			(vias allowed)
			(pads allowed)
			(copperpour not_allowed)
			(footprints allowed)
		)
		(placement
			(enabled no)
			(sheetname "")
		)
		(fill
			(thermal_gap 0.5)
			(thermal_bridge_width 0.5)
			(island_removal_mode 0)
		)
		(polygon
			(pts
				(xy 430.80686 -288.875216) (xy 432.30546 -288.875216) (xy 432.30546 -289.395154) (xy 430.80686 -289.395154)
			)
		)
	)
	(zone
		(layer "In2.Cu")
		(hatch none 0.5)
		(connect_pads
			(clearance 0)
		)
		(min_thickness 0.25)
		(keepout
			(tracks allowed)
			(vias allowed)
			(pads allowed)
			(copperpour allowed)
			(footprints allowed)
		)
		(placement
			(enabled no)
			(sheetname "")
		)
		(fill
			(thermal_gap 0.5)
			(thermal_bridge_width 0.5)
			(island_removal_mode 0)
		)
		(polygon
			(pts
				(xy 48.61941 -350.595692) (xy 48.61941 -349.973392) (xy 49.17059 -349.973392) (xy 49.17059 -350.595692)
			)
		)
	)
	(zone
		(layer "In2.Cu")
		(hatch none 0.5)
		(connect_pads
			(clearance 0)
		)
		(min_thickness 0.25)
		(keepout
			(tracks not_allowed)
			(vias allowed)
			(pads allowed)
			(copperpour not_allowed)
			(footprints allowed)
		)
		(placement
			(enabled no)
			(sheetname "")
		)
		(fill
			(thermal_gap 0.5)
			(thermal_bridge_width 0.5)
			(island_removal_mode 0)
		)
		(polygon
			(pts
				(xy 426.706792 -220.025214) (xy 428.205392 -220.025214) (xy 428.205392 -220.545152) (xy 426.706792 -220.545152)
			)
		)
	)
	(zone
		(layer "In2.Cu")
		(hatch none 0.5)
		(connect_pads
			(clearance 0)
		)
		(min_thickness 0.25)
		(keepout
			(tracks not_allowed)
			(vias allowed)
			(pads allowed)
			(copperpour not_allowed)
			(footprints allowed)
		)
		(placement
			(enabled no)
			(sheetname "")
		)
		(fill
			(thermal_gap 0.5)
			(thermal_bridge_width 0.5)
			(island_removal_mode 0)
		)
		(polygon
			(pts
				(xy 291.530786 -287.175194) (xy 293.029386 -287.175194) (xy 293.029386 -287.695132) (xy 291.530786 -287.695132)
			)
		)
	)
	(zone
		(layer "In2.Cu")
		(hatch none 0.5)
		(connect_pads
			(clearance 0)
		)
		(min_thickness 0.25)
		(keepout
			(tracks not_allowed)
			(vias allowed)
			(pads allowed)
			(copperpour not_allowed)
			(footprints allowed)
		)
		(placement
			(enabled no)
			(sheetname "")
		)
		(fill
			(thermal_gap 0.5)
			(thermal_bridge_width 0.5)
			(island_removal_mode 0)
		)
		(polygon
			(pts
				(xy 24.402542 -227.675186) (xy 25.901142 -227.675186) (xy 25.901142 -228.195124) (xy 24.402542 -228.195124)
			)
		)
	)
	(zone
		(layer "In2.Cu")
		(hatch none 0.5)
		(connect_pads
			(clearance 0)
		)
		(min_thickness 0.25)
		(keepout
			(tracks not_allowed)
			(vias allowed)
			(pads allowed)
			(copperpour not_allowed)
			(footprints allowed)
		)
		(placement
			(enabled no)
			(sheetname "")
		)
		(fill
			(thermal_gap 0.5)
			(thermal_bridge_width 0.5)
			(island_removal_mode 0)
		)
		(polygon
			(pts
				(arc
					(start 426.272198 -7.672324)
					(mid 426.294516 -7.618442)
					(end 426.348398 -7.596124)
				)
				(arc
					(start 427.384972 -7.596124)
					(mid 427.438854 -7.618442)
					(end 427.461172 -7.672324)
				)
				(arc
					(start 427.461172 -9.071864)
					(mid 427.438854 -9.125746)
					(end 427.384972 -9.148064)
				)
				(arc
					(start 426.348398 -9.148064)
					(mid 426.294516 -9.125746)
					(end 426.272198 -9.071864)
				)
			)
		)
	)
	(zone
		(layer "In2.Cu")
		(hatch none 0.5)
		(connect_pads
			(clearance 0)
		)
		(min_thickness 0.25)
		(keepout
			(tracks not_allowed)
			(vias allowed)
			(pads allowed)
			(copperpour not_allowed)
			(footprints allowed)
		)
		(placement
			(enabled no)
			(sheetname "")
		)
		(fill
			(thermal_gap 0.5)
			(thermal_bridge_width 0.5)
			(island_removal_mode 0)
		)
		(polygon
			(pts
				(xy 190.410846 -277.8252) (xy 191.909446 -277.8252) (xy 191.909446 -278.345138) (xy 190.410846 -278.345138)
			)
		)
	)
	(zone
		(layer "In2.Cu")
		(hatch none 0.5)
		(connect_pads
			(clearance 0)
		)
		(min_thickness 0.25)
		(keepout
			(tracks not_allowed)
			(vias allowed)
			(pads allowed)
			(copperpour not_allowed)
			(footprints allowed)
		)
		(placement
			(enabled no)
			(sheetname "")
		)
		(fill
			(thermal_gap 0.5)
			(thermal_bridge_width 0.5)
			(island_removal_mode 0)
		)
		(polygon
			(pts
				(xy 31.946596 -225.975164) (xy 33.445196 -225.975164) (xy 33.445196 -226.495102) (xy 31.946596 -226.495102)
			)
		)
	)
	(zone
		(layer "In2.Cu")
		(hatch none 0.5)
		(connect_pads
			(clearance 0)
		)
		(min_thickness 0.25)
		(keepout
			(tracks not_allowed)
			(vias allowed)
			(pads allowed)
			(copperpour not_allowed)
			(footprints allowed)
		)
		(placement
			(enabled no)
			(sheetname "")
		)
		(fill
			(thermal_gap 0.5)
			(thermal_bridge_width 0.5)
			(island_removal_mode 0)
		)
		(polygon
			(pts
				(xy 302.518826 -216.62517) (xy 304.017426 -216.62517) (xy 304.017426 -217.145108) (xy 302.518826 -217.145108)
			)
		)
	)
	(zone
		(layer "In2.Cu")
		(hatch none 0.5)
		(connect_pads
			(clearance 0)
		)
		(min_thickness 0.25)
		(keepout
			(tracks not_allowed)
			(vias allowed)
			(pads allowed)
			(copperpour not_allowed)
			(footprints allowed)
		)
		(placement
			(enabled no)
			(sheetname "")
		)
		(fill
			(thermal_gap 0.5)
			(thermal_bridge_width 0.5)
			(island_removal_mode 0)
		)
		(polygon
			(pts
				(xy 36.046664 -217.475308) (xy 37.545264 -217.475308) (xy 37.545264 -217.995246) (xy 36.046664 -217.995246)
			)
		)
	)
	(zone
		(layer "In2.Cu")
		(hatch none 0.5)
		(connect_pads
			(clearance 0)
		)
		(min_thickness 0.25)
		(keepout
			(tracks not_allowed)
			(vias allowed)
			(pads allowed)
			(copperpour not_allowed)
			(footprints allowed)
		)
		(placement
			(enabled no)
			(sheetname "")
		)
		(fill
			(thermal_gap 0.5)
			(thermal_bridge_width 0.5)
			(island_removal_mode 0)
		)
		(polygon
			(pts
				(xy 268.898878 -201.325226) (xy 270.397478 -201.325226) (xy 270.397478 -201.845164) (xy 268.898878 -201.845164)
			)
		)
	)
	(zone
		(layer "In2.Cu")
		(hatch none 0.5)
		(connect_pads
			(clearance 0)
		)
		(min_thickness 0.25)
		(keepout
			(tracks not_allowed)
			(vias allowed)
			(pads allowed)
			(copperpour not_allowed)
			(footprints allowed)
		)
		(placement
			(enabled no)
			(sheetname "")
		)
		(fill
			(thermal_gap 0.5)
			(thermal_bridge_width 0.5)
			(island_removal_mode 0)
		)
		(polygon
			(pts
				(xy 419.162738 -289.725354) (xy 420.661338 -289.725354) (xy 420.661338 -290.245292) (xy 419.162738 -290.245292)
			)
		)
	)
	(zone
		(layer "In2.Cu")
		(hatch none 0.5)
		(connect_pads
			(clearance 0)
		)
		(min_thickness 0.25)
		(keepout
			(tracks not_allowed)
			(vias allowed)
			(pads allowed)
			(copperpour not_allowed)
			(footprints allowed)
		)
		(placement
			(enabled no)
			(sheetname "")
		)
		(fill
			(thermal_gap 0.5)
			(thermal_bridge_width 0.5)
			(island_removal_mode 0)
		)
		(polygon
			(pts
				(xy 190.410846 -313.525154) (xy 191.909446 -313.525154) (xy 191.909446 -314.045092) (xy 190.410846 -314.045092)
			)
		)
	)
	(zone
		(layer "In2.Cu")
		(hatch none 0.5)
		(connect_pads
			(clearance 0)
		)
		(min_thickness 0.25)
		(keepout
			(tracks not_allowed)
			(vias allowed)
			(pads allowed)
			(copperpour not_allowed)
			(footprints allowed)
		)
		(placement
			(enabled no)
			(sheetname "")
		)
		(fill
			(thermal_gap 0.5)
			(thermal_bridge_width 0.5)
			(island_removal_mode 0)
		)
		(polygon
			(pts
				(xy 20.95881 -284.625288) (xy 22.45741 -284.625288) (xy 22.45741 -285.145226) (xy 20.95881 -285.145226)
			)
		)
	)
	(zone
		(layer "In2.Cu")
		(hatch none 0.5)
		(connect_pads
			(clearance 0)
		)
		(min_thickness 0.25)
		(keepout
			(tracks not_allowed)
			(vias allowed)
			(pads allowed)
			(copperpour not_allowed)
			(footprints allowed)
		)
		(placement
			(enabled no)
			(sheetname "")
		)
		(fill
			(thermal_gap 0.5)
			(thermal_bridge_width 0.5)
			(island_removal_mode 0)
		)
		(polygon
			(pts
				(xy 291.530786 -201.325226) (xy 293.029386 -201.325226) (xy 293.029386 -201.845164) (xy 291.530786 -201.845164)
			)
		)
	)
	(zone
		(layer "In2.Cu")
		(hatch none 0.5)
		(connect_pads
			(clearance 0)
		)
		(min_thickness 0.25)
		(keepout
			(tracks not_allowed)
			(vias allowed)
			(pads allowed)
			(copperpour not_allowed)
			(footprints allowed)
		)
		(placement
			(enabled no)
			(sheetname "")
		)
		(fill
			(thermal_gap 0.5)
			(thermal_bridge_width 0.5)
			(island_removal_mode 0)
		)
		(polygon
			(pts
				(xy 441.7949 -285.475172) (xy 443.2935 -285.475172) (xy 443.2935 -285.99511) (xy 441.7949 -285.99511)
			)
		)
	)
	(zone
		(layer "In2.Cu")
		(hatch none 0.5)
		(connect_pads
			(clearance 0)
		)
		(min_thickness 0.25)
		(keepout
			(tracks not_allowed)
			(vias allowed)
			(pads allowed)
			(copperpour not_allowed)
			(footprints allowed)
		)
		(placement
			(enabled no)
			(sheetname "")
		)
		(fill
			(thermal_gap 0.5)
			(thermal_bridge_width 0.5)
			(island_removal_mode 0)
		)
		(polygon
			(pts
				(xy 193.854578 -218.325192) (xy 195.353178 -218.325192) (xy 195.353178 -218.84513) (xy 193.854578 -218.84513)
			)
		)
	)
	(zone
		(layer "In2.Cu")
		(hatch none 0.5)
		(connect_pads
			(clearance 0)
		)
		(min_thickness 0.25)
		(keepout
			(tracks not_allowed)
			(vias allowed)
			(pads allowed)
			(copperpour not_allowed)
			(footprints allowed)
		)
		(placement
			(enabled no)
			(sheetname "")
		)
		(fill
			(thermal_gap 0.5)
			(thermal_bridge_width 0.5)
			(island_removal_mode 0)
		)
		(polygon
			(pts
				(xy 186.310778 -202.17511) (xy 187.809378 -202.17511) (xy 187.809378 -202.695048) (xy 186.310778 -202.695048)
			)
		)
	)
	(zone
		(layer "In2.Cu")
		(hatch none 0.5)
		(connect_pads
			(clearance 0)
		)
		(min_thickness 0.25)
		(keepout
			(tracks not_allowed)
			(vias allowed)
			(pads allowed)
			(copperpour not_allowed)
			(footprints allowed)
		)
		(placement
			(enabled no)
			(sheetname "")
		)
		(fill
			(thermal_gap 0.5)
			(thermal_bridge_width 0.5)
			(island_removal_mode 0)
		)
		(polygon
			(pts
				(xy 299.07484 -242.125246) (xy 300.57344 -242.125246) (xy 300.57344 -242.645184) (xy 299.07484 -242.645184)
			)
		)
	)
	(zone
		(layer "In2.Cu")
		(hatch none 0.5)
		(connect_pads
			(clearance 0)
		)
		(min_thickness 0.25)
		(keepout
			(tracks allowed)
			(vias allowed)
			(pads allowed)
			(copperpour allowed)
			(footprints allowed)
		)
		(placement
			(enabled no)
			(sheetname "")
		)
		(fill
			(thermal_gap 0.5)
			(thermal_bridge_width 0.5)
			(island_removal_mode 0)
		)
		(polygon
			(pts
				(xy 42.183812 -349.943166) (xy 42.183812 -349.320866) (xy 42.734992 -349.320866) (xy 42.734992 -349.943166)
			)
		)
	)
	(zone
		(layer "In2.Cu")
		(hatch none 0.5)
		(connect_pads
			(clearance 0)
		)
		(min_thickness 0.25)
		(keepout
			(tracks not_allowed)
			(vias allowed)
			(pads allowed)
			(copperpour not_allowed)
			(footprints allowed)
		)
		(placement
			(enabled no)
			(sheetname "")
		)
		(fill
			(thermal_gap 0.5)
			(thermal_bridge_width 0.5)
			(island_removal_mode 0)
		)
		(polygon
			(pts
				(xy 51.134772 -288.875216) (xy 52.633372 -288.875216) (xy 52.633372 -289.395154) (xy 51.134772 -289.395154)
			)
		)
	)
	(zone
		(layer "In2.Cu")
		(hatch none 0.5)
		(connect_pads
			(clearance 0)
		)
		(min_thickness 0.25)
		(keepout
			(tracks not_allowed)
			(vias allowed)
			(pads allowed)
			(copperpour not_allowed)
			(footprints allowed)
		)
		(placement
			(enabled no)
			(sheetname "")
		)
		(fill
			(thermal_gap 0.5)
			(thermal_bridge_width 0.5)
			(island_removal_mode 0)
		)
		(polygon
			(pts
				(xy 276.442932 -228.525324) (xy 277.941532 -228.525324) (xy 277.941532 -229.045262) (xy 276.442932 -229.045262)
			)
		)
	)
	(zone
		(layer "In2.Cu")
		(hatch none 0.5)
		(connect_pads
			(clearance 0)
		)
		(min_thickness 0.25)
		(keepout
			(tracks not_allowed)
			(vias allowed)
			(pads allowed)
			(copperpour not_allowed)
			(footprints allowed)
		)
		(placement
			(enabled no)
			(sheetname "")
		)
		(fill
			(thermal_gap 0.5)
			(thermal_bridge_width 0.5)
			(island_removal_mode 0)
		)
		(polygon
			(pts
				(xy 163.678616 -211.525104) (xy 165.177216 -211.525104) (xy 165.177216 -212.045042) (xy 163.678616 -212.045042)
			)
		)
	)
	(zone
		(layer "In2.Cu")
		(hatch none 0.5)
		(connect_pads
			(clearance 0)
		)
		(min_thickness 0.25)
		(keepout
			(tracks not_allowed)
			(vias allowed)
			(pads allowed)
			(copperpour not_allowed)
			(footprints allowed)
		)
		(placement
			(enabled no)
			(sheetname "")
		)
		(fill
			(thermal_gap 0.5)
			(thermal_bridge_width 0.5)
			(island_removal_mode 0)
		)
		(polygon
			(pts
				(xy 197.954646 -316.925198) (xy 199.453246 -316.925198) (xy 199.453246 -317.445136) (xy 197.954646 -317.445136)
			)
		)
	)
	(zone
		(layer "In2.Cu")
		(hatch none 0.5)
		(connect_pads
			(clearance 0)
		)
		(min_thickness 0.25)
		(keepout
			(tracks not_allowed)
			(vias allowed)
			(pads allowed)
			(copperpour not_allowed)
			(footprints allowed)
		)
		(placement
			(enabled no)
			(sheetname "")
		)
		(fill
			(thermal_gap 0.5)
			(thermal_bridge_width 0.5)
			(island_removal_mode 0)
		)
		(polygon
			(pts
				(xy 20.95881 -282.925266) (xy 22.45741 -282.925266) (xy 22.45741 -283.445204) (xy 20.95881 -283.445204)
			)
		)
	)
	(zone
		(layer "In2.Cu")
		(hatch none 0.5)
		(connect_pads
			(clearance 0)
		)
		(min_thickness 0.25)
		(keepout
			(tracks not_allowed)
			(vias allowed)
			(pads allowed)
			(copperpour not_allowed)
			(footprints allowed)
		)
		(placement
			(enabled no)
			(sheetname "")
		)
		(fill
			(thermal_gap 0.5)
			(thermal_bridge_width 0.5)
			(island_removal_mode 0)
		)
		(polygon
			(pts
				(xy 302.518826 -253.175262) (xy 304.017426 -253.175262) (xy 304.017426 -253.6952) (xy 302.518826 -253.6952)
			)
		)
	)
	(zone
		(layer "In2.Cu")
		(hatch none 0.5)
		(connect_pads
			(clearance 0)
		)
		(min_thickness 0.25)
		(keepout
			(tracks not_allowed)
			(vias allowed)
			(pads allowed)
			(copperpour not_allowed)
			(footprints allowed)
		)
		(placement
			(enabled no)
			(sheetname "")
		)
		(fill
			(thermal_gap 0.5)
			(thermal_bridge_width 0.5)
			(island_removal_mode 0)
		)
		(polygon
			(pts
				(xy 276.442932 -200.475342) (xy 277.941532 -200.475342) (xy 277.941532 -200.99528) (xy 276.442932 -200.99528)
			)
		)
	)
	(zone
		(layer "In2.Cu")
		(hatch none 0.5)
		(connect_pads
			(clearance 0)
		)
		(min_thickness 0.25)
		(keepout
			(tracks not_allowed)
			(vias allowed)
			(pads allowed)
			(copperpour not_allowed)
			(footprints allowed)
		)
		(placement
			(enabled no)
			(sheetname "")
		)
		(fill
			(thermal_gap 0.5)
			(thermal_bridge_width 0.5)
			(island_removal_mode 0)
		)
		(polygon
			(pts
				(xy 294.974772 -288.025332) (xy 296.473372 -288.025332) (xy 296.473372 -288.54527) (xy 294.974772 -288.54527)
			)
		)
	)
	(zone
		(layer "In2.Cu")
		(hatch none 0.5)
		(connect_pads
			(clearance 0)
		)
		(min_thickness 0.25)
		(keepout
			(tracks not_allowed)
			(vias allowed)
			(pads allowed)
			(copperpour not_allowed)
			(footprints allowed)
		)
		(placement
			(enabled no)
			(sheetname "")
		)
		(fill
			(thermal_gap 0.5)
			(thermal_bridge_width 0.5)
			(island_removal_mode 0)
		)
		(polygon
			(pts
				(xy 415.718752 -240.425224) (xy 417.217352 -240.425224) (xy 417.217352 -240.945162) (xy 415.718752 -240.945162)
			)
		)
	)
	(zone
		(layer "In2.Cu")
		(hatch none 0.5)
		(connect_pads
			(clearance 0)
		)
		(min_thickness 0.25)
		(keepout
			(tracks not_allowed)
			(vias allowed)
			(pads allowed)
			(copperpour not_allowed)
			(footprints allowed)
		)
		(placement
			(enabled no)
			(sheetname "")
		)
		(fill
			(thermal_gap 0.5)
			(thermal_bridge_width 0.5)
			(island_removal_mode 0)
		)
		(polygon
			(pts
				(xy 163.678616 -214.925148) (xy 165.177216 -214.925148) (xy 165.177216 -215.445086) (xy 163.678616 -215.445086)
			)
		)
	)
	(zone
		(layer "In2.Cu")
		(hatch none 0.5)
		(connect_pads
			(clearance 0)
		)
		(min_thickness 0.25)
		(keepout
			(tracks not_allowed)
			(vias allowed)
			(pads allowed)
			(copperpour not_allowed)
			(footprints allowed)
		)
		(placement
			(enabled no)
			(sheetname "")
		)
		(fill
			(thermal_gap 0.5)
			(thermal_bridge_width 0.5)
			(island_removal_mode 0)
		)
		(polygon
			(pts
				(xy 24.402542 -238.725202) (xy 25.901142 -238.725202) (xy 25.901142 -239.24514) (xy 24.402542 -239.24514)
			)
		)
	)
	(zone
		(layer "In2.Cu")
		(hatch none 0.5)
		(connect_pads
			(clearance 0)
		)
		(min_thickness 0.25)
		(keepout
			(tracks not_allowed)
			(vias allowed)
			(pads allowed)
			(copperpour not_allowed)
			(footprints allowed)
		)
		(placement
			(enabled no)
			(sheetname "")
		)
		(fill
			(thermal_gap 0.5)
			(thermal_bridge_width 0.5)
			(island_removal_mode 0)
		)
		(polygon
			(pts
				(xy 54.578758 -272.725134) (xy 56.077358 -272.725134) (xy 56.077358 -273.245072) (xy 54.578758 -273.245072)
			)
		)
	)
	(zone
		(layer "In2.Cu")
		(hatch none 0.5)
		(connect_pads
			(clearance 0)
		)
		(min_thickness 0.25)
		(keepout
			(tracks not_allowed)
			(vias allowed)
			(pads allowed)
			(copperpour not_allowed)
			(footprints allowed)
		)
		(placement
			(enabled no)
			(sheetname "")
		)
		(fill
			(thermal_gap 0.5)
			(thermal_bridge_width 0.5)
			(island_removal_mode 0)
		)
		(polygon
			(pts
				(xy 201.398632 -288.025332) (xy 202.897232 -288.025332) (xy 202.897232 -288.54527) (xy 201.398632 -288.54527)
			)
		)
	)
	(zone
		(layer "In2.Cu")
		(hatch none 0.5)
		(connect_pads
			(clearance 0)
		)
		(min_thickness 0.25)
		(keepout
			(tracks not_allowed)
			(vias allowed)
			(pads allowed)
			(copperpour not_allowed)
			(footprints allowed)
		)
		(placement
			(enabled no)
			(sheetname "")
		)
		(fill
			(thermal_gap 0.5)
			(thermal_bridge_width 0.5)
			(island_removal_mode 0)
		)
		(polygon
			(pts
				(xy 163.678616 -242.97513) (xy 165.177216 -242.97513) (xy 165.177216 -243.495068) (xy 163.678616 -243.495068)
			)
		)
	)
	(zone
		(layer "In2.Cu")
		(hatch none 0.5)
		(connect_pads
			(clearance 0)
		)
		(min_thickness 0.25)
		(keepout
			(tracks not_allowed)
			(vias allowed)
			(pads allowed)
			(copperpour not_allowed)
			(footprints allowed)
		)
		(placement
			(enabled no)
			(sheetname "")
		)
		(fill
			(thermal_gap 0.5)
			(thermal_bridge_width 0.5)
			(island_removal_mode 0)
		)
		(polygon
			(pts
				(xy 445.894968 -225.12528) (xy 447.393568 -225.12528) (xy 447.393568 -225.645218) (xy 445.894968 -225.645218)
			)
		)
	)
	(zone
		(layer "In2.Cu")
		(hatch none 0.5)
		(connect_pads
			(clearance 0)
		)
		(min_thickness 0.25)
		(keepout
			(tracks not_allowed)
			(vias allowed)
			(pads allowed)
			(copperpour not_allowed)
			(footprints allowed)
		)
		(placement
			(enabled no)
			(sheetname "")
		)
		(fill
			(thermal_gap 0.5)
			(thermal_bridge_width 0.5)
			(island_removal_mode 0)
		)
		(polygon
			(pts
				(xy 20.95881 -260.825234) (xy 22.45741 -260.825234) (xy 22.45741 -261.345172) (xy 20.95881 -261.345172)
			)
		)
	)
	(zone
		(layer "In2.Cu")
		(hatch none 0.5)
		(connect_pads
			(clearance 0)
		)
		(min_thickness 0.25)
		(keepout
			(tracks not_allowed)
			(vias allowed)
			(pads allowed)
			(copperpour not_allowed)
			(footprints allowed)
		)
		(placement
			(enabled no)
			(sheetname "")
		)
		(fill
			(thermal_gap 0.5)
			(thermal_bridge_width 0.5)
			(island_removal_mode 0)
		)
		(polygon
			(pts
				(xy 51.134772 -281.225244) (xy 52.633372 -281.225244) (xy 52.633372 -281.745182) (xy 51.134772 -281.745182)
			)
		)
	)
	(zone
		(layer "In2.Cu")
		(hatch none 0.5)
		(connect_pads
			(clearance 0)
		)
		(min_thickness 0.25)
		(keepout
			(tracks not_allowed)
			(vias allowed)
			(pads allowed)
			(copperpour not_allowed)
			(footprints allowed)
		)
		(placement
			(enabled no)
			(sheetname "")
		)
		(fill
			(thermal_gap 0.5)
			(thermal_bridge_width 0.5)
			(island_removal_mode 0)
		)
		(polygon
			(pts
				(xy 426.706792 -268.475206) (xy 428.205392 -268.475206) (xy 428.205392 -268.995144) (xy 426.706792 -268.995144)
			)
		)
	)
	(zone
		(layer "In2.Cu")
		(hatch none 0.5)
		(connect_pads
			(clearance 0)
		)
		(min_thickness 0.25)
		(keepout
			(tracks not_allowed)
			(vias allowed)
			(pads allowed)
			(copperpour not_allowed)
			(footprints allowed)
		)
		(placement
			(enabled no)
			(sheetname "")
		)
		(fill
			(thermal_gap 0.5)
			(thermal_bridge_width 0.5)
			(island_removal_mode 0)
		)
		(polygon
			(pts
				(xy 24.402542 -251.47524) (xy 25.901142 -251.47524) (xy 25.901142 -251.995178) (xy 24.402542 -251.995178)
			)
		)
	)
	(zone
		(layer "In2.Cu")
		(hatch none 0.5)
		(connect_pads
			(clearance 0)
		)
		(min_thickness 0.25)
		(keepout
			(tracks not_allowed)
			(vias allowed)
			(pads allowed)
			(copperpour not_allowed)
			(footprints allowed)
		)
		(placement
			(enabled no)
			(sheetname "")
		)
		(fill
			(thermal_gap 0.5)
			(thermal_bridge_width 0.5)
			(island_removal_mode 0)
		)
		(polygon
			(pts
				(xy 54.578758 -276.125178) (xy 56.077358 -276.125178) (xy 56.077358 -276.645116) (xy 54.578758 -276.645116)
			)
		)
	)
	(zone
		(layer "In2.Cu")
		(hatch none 0.5)
		(connect_pads
			(clearance 0)
		)
		(min_thickness 0.25)
		(keepout
			(tracks not_allowed)
			(vias allowed)
			(pads allowed)
			(copperpour not_allowed)
			(footprints allowed)
		)
		(placement
			(enabled no)
			(sheetname "")
		)
		(fill
			(thermal_gap 0.5)
			(thermal_bridge_width 0.5)
			(island_removal_mode 0)
		)
		(polygon
			(pts
				(xy 31.946596 -202.17511) (xy 33.445196 -202.17511) (xy 33.445196 -202.695048) (xy 31.946596 -202.695048)
			)
		)
	)
	(zone
		(layer "In2.Cu")
		(hatch none 0.5)
		(connect_pads
			(clearance 0)
		)
		(min_thickness 0.25)
		(keepout
			(tracks not_allowed)
			(vias allowed)
			(pads allowed)
			(copperpour not_allowed)
			(footprints allowed)
		)
		(placement
			(enabled no)
			(sheetname "")
		)
		(fill
			(thermal_gap 0.5)
			(thermal_bridge_width 0.5)
			(island_removal_mode 0)
		)
		(polygon
			(pts
				(xy 430.80686 -269.325344) (xy 432.30546 -269.325344) (xy 432.30546 -269.845282) (xy 430.80686 -269.845282)
			)
		)
	)
	(zone
		(layer "In2.Cu")
		(hatch none 0.5)
		(connect_pads
			(clearance 0)
		)
		(min_thickness 0.25)
		(keepout
			(tracks not_allowed)
			(vias allowed)
			(pads allowed)
			(copperpour not_allowed)
			(footprints allowed)
		)
		(placement
			(enabled no)
			(sheetname "")
		)
		(fill
			(thermal_gap 0.5)
			(thermal_bridge_width 0.5)
			(island_removal_mode 0)
		)
		(polygon
			(pts
				(xy 28.50261 -254.025146) (xy 30.00121 -254.025146) (xy 30.00121 -254.545084) (xy 28.50261 -254.545084)
			)
		)
	)
	(zone
		(layer "In2.Cu")
		(hatch none 0.5)
		(connect_pads
			(clearance 0)
		)
		(min_thickness 0.25)
		(keepout
			(tracks not_allowed)
			(vias allowed)
			(pads allowed)
			(copperpour not_allowed)
			(footprints allowed)
		)
		(placement
			(enabled no)
			(sheetname "")
		)
		(fill
			(thermal_gap 0.5)
			(thermal_bridge_width 0.5)
			(island_removal_mode 0)
		)
		(polygon
			(pts
				(xy 190.410846 -273.575272) (xy 191.909446 -273.575272) (xy 191.909446 -274.09521) (xy 190.410846 -274.09521)
			)
		)
	)
	(zone
		(layer "In2.Cu")
		(hatch none 0.5)
		(connect_pads
			(clearance 0)
		)
		(min_thickness 0.25)
		(keepout
			(tracks not_allowed)
			(vias allowed)
			(pads allowed)
			(copperpour not_allowed)
			(footprints allowed)
		)
		(placement
			(enabled no)
			(sheetname "")
		)
		(fill
			(thermal_gap 0.5)
			(thermal_bridge_width 0.5)
			(island_removal_mode 0)
		)
		(polygon
			(pts
				(xy 47.034704 -266.775184) (xy 48.533304 -266.775184) (xy 48.533304 -267.295122) (xy 47.034704 -267.295122)
			)
		)
	)
	(zone
		(layer "In2.Cu")
		(hatch none 0.5)
		(connect_pads
			(clearance 0)
		)
		(min_thickness 0.25)
		(keepout
			(tracks not_allowed)
			(vias allowed)
			(pads allowed)
			(copperpour not_allowed)
			(footprints allowed)
		)
		(placement
			(enabled no)
			(sheetname "")
		)
		(fill
			(thermal_gap 0.5)
			(thermal_bridge_width 0.5)
			(island_removal_mode 0)
		)
		(polygon
			(pts
				(xy 453.438768 -242.125246) (xy 454.937368 -242.125246) (xy 454.937368 -242.645184) (xy 453.438768 -242.645184)
			)
		)
	)
	(zone
		(layer "In2.Cu")
		(hatch none 0.5)
		(connect_pads
			(clearance 0)
		)
		(min_thickness 0.25)
		(keepout
			(tracks not_allowed)
			(vias allowed)
			(pads allowed)
			(copperpour not_allowed)
			(footprints allowed)
		)
		(placement
			(enabled no)
			(sheetname "")
		)
		(fill
			(thermal_gap 0.5)
			(thermal_bridge_width 0.5)
			(island_removal_mode 0)
		)
		(polygon
			(pts
				(xy 287.430718 -266.775184) (xy 288.929318 -266.775184) (xy 288.929318 -267.295122) (xy 287.430718 -267.295122)
			)
		)
	)
	(zone
		(layer "In2.Cu")
		(hatch none 0.5)
		(connect_pads
			(clearance 0)
		)
		(min_thickness 0.25)
		(keepout
			(tracks not_allowed)
			(vias allowed)
			(pads allowed)
			(copperpour not_allowed)
			(footprints allowed)
		)
		(placement
			(enabled no)
			(sheetname "")
		)
		(fill
			(thermal_gap 0.5)
			(thermal_bridge_width 0.5)
			(island_removal_mode 0)
		)
		(polygon
			(pts
				(xy 294.974772 -274.425156) (xy 296.473372 -274.425156) (xy 296.473372 -274.945094) (xy 294.974772 -274.945094)
			)
		)
	)
	(zone
		(layer "In2.Cu")
		(hatch none 0.5)
		(connect_pads
			(clearance 0)
		)
		(min_thickness 0.25)
		(keepout
			(tracks not_allowed)
			(vias allowed)
			(pads allowed)
			(copperpour not_allowed)
			(footprints allowed)
		)
		(placement
			(enabled no)
			(sheetname "")
		)
		(fill
			(thermal_gap 0.5)
			(thermal_bridge_width 0.5)
			(island_removal_mode 0)
		)
		(polygon
			(pts
				(xy 426.706792 -276.975316) (xy 428.205392 -276.975316) (xy 428.205392 -277.495254) (xy 426.706792 -277.495254)
			)
		)
	)
	(zone
		(layer "In2.Cu")
		(hatch none 0.5)
		(connect_pads
			(clearance 0)
		)
		(min_thickness 0.25)
		(keepout
			(tracks not_allowed)
			(vias allowed)
			(pads allowed)
			(copperpour not_allowed)
			(footprints allowed)
		)
		(placement
			(enabled no)
			(sheetname "")
		)
		(fill
			(thermal_gap 0.5)
			(thermal_bridge_width 0.5)
			(island_removal_mode 0)
		)
		(polygon
			(pts
				(xy 54.578758 -202.17511) (xy 56.077358 -202.17511) (xy 56.077358 -202.695048) (xy 54.578758 -202.695048)
			)
		)
	)
	(zone
		(layer "In2.Cu")
		(hatch none 0.5)
		(connect_pads
			(clearance 0)
		)
		(min_thickness 0.25)
		(keepout
			(tracks not_allowed)
			(vias allowed)
			(pads allowed)
			(copperpour not_allowed)
			(footprints allowed)
		)
		(placement
			(enabled no)
			(sheetname "")
		)
		(fill
			(thermal_gap 0.5)
			(thermal_bridge_width 0.5)
			(island_removal_mode 0)
		)
		(polygon
			(pts
				(xy 272.342864 -285.475172) (xy 273.841464 -285.475172) (xy 273.841464 -285.99511) (xy 272.342864 -285.99511)
			)
		)
	)
	(zone
		(layer "In2.Cu")
		(hatch none 0.5)
		(connect_pads
			(clearance 0)
		)
		(min_thickness 0.25)
		(keepout
			(tracks not_allowed)
			(vias allowed)
			(pads allowed)
			(copperpour not_allowed)
			(footprints allowed)
		)
		(placement
			(enabled no)
			(sheetname "")
		)
		(fill
			(thermal_gap 0.5)
			(thermal_bridge_width 0.5)
			(island_removal_mode 0)
		)
		(polygon
			(pts
				(xy 438.350914 -279.525222) (xy 439.849514 -279.525222) (xy 439.849514 -280.04516) (xy 438.350914 -280.04516)
			)
		)
	)
	(zone
		(layer "In2.Cu")
		(hatch none 0.5)
		(connect_pads
			(clearance 0)
		)
		(min_thickness 0.25)
		(keepout
			(tracks not_allowed)
			(vias allowed)
			(pads allowed)
			(copperpour not_allowed)
			(footprints allowed)
		)
		(placement
			(enabled no)
			(sheetname "")
		)
		(fill
			(thermal_gap 0.5)
			(thermal_bridge_width 0.5)
			(island_removal_mode 0)
		)
		(polygon
			(pts
				(xy 291.530786 -198.77532) (xy 293.029386 -198.77532) (xy 293.029386 -199.295258) (xy 291.530786 -199.295258)
			)
		)
	)
	(zone
		(layer "In2.Cu")
		(hatch none 0.5)
		(connect_pads
			(clearance 0)
		)
		(min_thickness 0.25)
		(keepout
			(tracks not_allowed)
			(vias allowed)
			(pads allowed)
			(copperpour not_allowed)
			(footprints allowed)
		)
		(placement
			(enabled no)
			(sheetname "")
		)
		(fill
			(thermal_gap 0.5)
			(thermal_bridge_width 0.5)
			(island_removal_mode 0)
		)
		(polygon
			(pts
				(xy 175.322738 -209.825336) (xy 176.821338 -209.825336) (xy 176.821338 -210.345274) (xy 175.322738 -210.345274)
			)
		)
	)
	(zone
		(layer "In2.Cu")
		(hatch none 0.5)
		(connect_pads
			(clearance 0)
		)
		(min_thickness 0.25)
		(keepout
			(tracks not_allowed)
			(vias allowed)
			(pads allowed)
			(copperpour not_allowed)
			(footprints allowed)
		)
		(placement
			(enabled no)
			(sheetname "")
		)
		(fill
			(thermal_gap 0.5)
			(thermal_bridge_width 0.5)
			(island_removal_mode 0)
		)
		(polygon
			(pts
				(xy 445.894968 -271.87525) (xy 447.393568 -271.87525) (xy 447.393568 -272.395188) (xy 445.894968 -272.395188)
			)
		)
	)
	(zone
		(layer "In2.Cu")
		(hatch none 0.5)
		(connect_pads
			(clearance 0)
		)
		(min_thickness 0.25)
		(keepout
			(tracks not_allowed)
			(vias allowed)
			(pads allowed)
			(copperpour not_allowed)
			(footprints allowed)
		)
		(placement
			(enabled no)
			(sheetname "")
		)
		(fill
			(thermal_gap 0.5)
			(thermal_bridge_width 0.5)
			(island_removal_mode 0)
		)
		(polygon
			(pts
				(xy 441.7949 -286.32531) (xy 443.2935 -286.32531) (xy 443.2935 -286.845248) (xy 441.7949 -286.845248)
			)
		)
	)
	(zone
		(layer "In2.Cu")
		(hatch none 0.5)
		(connect_pads
			(clearance 0)
		)
		(min_thickness 0.25)
		(keepout
			(tracks not_allowed)
			(vias allowed)
			(pads allowed)
			(copperpour not_allowed)
			(footprints allowed)
		)
		(placement
			(enabled no)
			(sheetname "")
		)
		(fill
			(thermal_gap 0.5)
			(thermal_bridge_width 0.5)
			(island_removal_mode 0)
		)
		(polygon
			(pts
				(xy 434.250846 -297.375326) (xy 435.749446 -297.375326) (xy 435.749446 -297.895264) (xy 434.250846 -297.895264)
			)
		)
	)
	(zone
		(layer "In2.Cu")
		(hatch none 0.5)
		(connect_pads
			(clearance 0)
		)
		(min_thickness 0.25)
		(keepout
			(tracks not_allowed)
			(vias allowed)
			(pads allowed)
			(copperpour not_allowed)
			(footprints allowed)
		)
		(placement
			(enabled no)
			(sheetname "")
		)
		(fill
			(thermal_gap 0.5)
			(thermal_bridge_width 0.5)
			(island_removal_mode 0)
		)
		(polygon
			(pts
				(xy 415.718752 -252.325124) (xy 417.217352 -252.325124) (xy 417.217352 -252.845062) (xy 415.718752 -252.845062)
			)
		)
	)
	(zone
		(layer "In2.Cu")
		(hatch none 0.5)
		(connect_pads
			(clearance 0)
		)
		(min_thickness 0.25)
		(keepout
			(tracks not_allowed)
			(vias allowed)
			(pads allowed)
			(copperpour not_allowed)
			(footprints allowed)
		)
		(placement
			(enabled no)
			(sheetname "")
		)
		(fill
			(thermal_gap 0.5)
			(thermal_bridge_width 0.5)
			(island_removal_mode 0)
		)
		(polygon
			(pts
				(xy 163.678616 -220.875098) (xy 165.177216 -220.875098) (xy 165.177216 -221.395036) (xy 163.678616 -221.395036)
			)
		)
	)
	(zone
		(layer "In2.Cu")
		(hatch none 0.5)
		(connect_pads
			(clearance 0)
		)
		(min_thickness 0.25)
		(keepout
			(tracks not_allowed)
			(vias allowed)
			(pads allowed)
			(copperpour not_allowed)
			(footprints allowed)
		)
		(placement
			(enabled no)
			(sheetname "")
		)
		(fill
			(thermal_gap 0.5)
			(thermal_bridge_width 0.5)
			(island_removal_mode 0)
		)
		(polygon
			(pts
				(xy 302.518826 -274.425156) (xy 304.017426 -274.425156) (xy 304.017426 -274.945094) (xy 302.518826 -274.945094)
			)
		)
	)
	(zone
		(layer "In2.Cu")
		(hatch none 0.5)
		(connect_pads
			(clearance 0)
		)
		(min_thickness 0.25)
		(keepout
			(tracks not_allowed)
			(vias allowed)
			(pads allowed)
			(copperpour not_allowed)
			(footprints allowed)
		)
		(placement
			(enabled no)
			(sheetname "")
		)
		(fill
			(thermal_gap 0.5)
			(thermal_bridge_width 0.5)
			(island_removal_mode 0)
		)
		(polygon
			(pts
				(xy 438.350914 -284.625288) (xy 439.849514 -284.625288) (xy 439.849514 -285.145226) (xy 438.350914 -285.145226)
			)
		)
	)
	(zone
		(layer "In2.Cu")
		(hatch none 0.5)
		(connect_pads
			(clearance 0)
		)
		(min_thickness 0.25)
		(keepout
			(tracks not_allowed)
			(vias allowed)
			(pads allowed)
			(copperpour not_allowed)
			(footprints allowed)
		)
		(placement
			(enabled no)
			(sheetname "")
		)
		(fill
			(thermal_gap 0.5)
			(thermal_bridge_width 0.5)
			(island_removal_mode 0)
		)
		(polygon
			(pts
				(arc
					(start 357.837994 -379.360684)
					(mid 357.857918 -379.36992)
					(end 357.87965 -379.37313)
				)
				(arc
					(start 358.074214 -379.37313)
					(mid 358.128096 -379.350812)
					(end 358.150414 -379.29693)
				)
				(arc
					(start 358.150414 -378.61113)
					(mid 358.128096 -378.557248)
					(end 358.074214 -378.53493)
				)
				(arc
					(start 357.87965 -378.53493)
					(mid 357.857906 -378.538098)
					(end 357.837994 -378.547376)
				)
				(arc
					(start 357.54183 -378.740162)
					(mid 357.500146 -378.752384)
					(end 357.458518 -378.739908)
				)
				(arc
					(start 357.164894 -378.547376)
					(mid 357.14497 -378.53814)
					(end 357.123238 -378.53493)
				)
				(arc
					(start 356.928674 -378.53493)
					(mid 356.874792 -378.557248)
					(end 356.852474 -378.61113)
				)
				(arc
					(start 356.852474 -379.29693)
					(mid 356.874792 -379.350812)
					(end 356.928674 -379.37313)
				)
				(arc
					(start 357.124508 -379.37313)
					(mid 357.146252 -379.369962)
					(end 357.166164 -379.360684)
				)
				(arc
					(start 357.459788 -379.168152)
					(mid 357.501444 -379.15575)
					(end 357.5431 -379.168152)
				)
			)
		)
	)
	(zone
		(layer "In2.Cu")
		(hatch none 0.5)
		(connect_pads
			(clearance 0)
		)
		(min_thickness 0.25)
		(keepout
			(tracks not_allowed)
			(vias allowed)
			(pads allowed)
			(copperpour not_allowed)
			(footprints allowed)
		)
		(placement
			(enabled no)
			(sheetname "")
		)
		(fill
			(thermal_gap 0.5)
			(thermal_bridge_width 0.5)
			(island_removal_mode 0)
		)
		(polygon
			(pts
				(xy 54.578758 -238.725202) (xy 56.077358 -238.725202) (xy 56.077358 -239.24514) (xy 54.578758 -239.24514)
			)
		)
	)
	(zone
		(layer "In2.Cu")
		(hatch none 0.5)
		(connect_pads
			(clearance 0)
		)
		(min_thickness 0.25)
		(keepout
			(tracks not_allowed)
			(vias allowed)
			(pads allowed)
			(copperpour not_allowed)
			(footprints allowed)
		)
		(placement
			(enabled no)
			(sheetname "")
		)
		(fill
			(thermal_gap 0.5)
			(thermal_bridge_width 0.5)
			(island_removal_mode 0)
		)
		(polygon
			(pts
				(xy 36.046664 -238.725202) (xy 37.545264 -238.725202) (xy 37.545264 -239.24514) (xy 36.046664 -239.24514)
			)
		)
	)
	(zone
		(layer "In2.Cu")
		(hatch none 0.5)
		(connect_pads
			(clearance 0)
		)
		(min_thickness 0.25)
		(keepout
			(tracks not_allowed)
			(vias allowed)
			(pads allowed)
			(copperpour not_allowed)
			(footprints allowed)
		)
		(placement
			(enabled no)
			(sheetname "")
		)
		(fill
			(thermal_gap 0.5)
			(thermal_bridge_width 0.5)
			(island_removal_mode 0)
		)
		(polygon
			(pts
				(xy 426.706792 -220.875098) (xy 428.205392 -220.875098) (xy 428.205392 -221.395036) (xy 426.706792 -221.395036)
			)
		)
	)
	(zone
		(layer "In2.Cu")
		(hatch none 0.5)
		(connect_pads
			(clearance 0)
		)
		(min_thickness 0.25)
		(keepout
			(tracks not_allowed)
			(vias allowed)
			(pads allowed)
			(copperpour not_allowed)
			(footprints allowed)
		)
		(placement
			(enabled no)
			(sheetname "")
		)
		(fill
			(thermal_gap 0.5)
			(thermal_bridge_width 0.5)
			(island_removal_mode 0)
		)
		(polygon
			(pts
				(xy 441.7949 -276.975316) (xy 443.2935 -276.975316) (xy 443.2935 -277.495254) (xy 441.7949 -277.495254)
			)
		)
	)
	(zone
		(layer "In2.Cu")
		(hatch none 0.5)
		(connect_pads
			(clearance 0)
		)
		(min_thickness 0.25)
		(keepout
			(tracks not_allowed)
			(vias allowed)
			(pads allowed)
			(copperpour not_allowed)
			(footprints allowed)
		)
		(placement
			(enabled no)
			(sheetname "")
		)
		(fill
			(thermal_gap 0.5)
			(thermal_bridge_width 0.5)
			(island_removal_mode 0)
		)
		(polygon
			(pts
				(xy 186.310778 -203.875132) (xy 187.809378 -203.875132) (xy 187.809378 -204.39507) (xy 186.310778 -204.39507)
			)
		)
	)
	(zone
		(layer "In2.Cu")
		(hatch none 0.5)
		(connect_pads
			(clearance 0)
		)
		(min_thickness 0.25)
		(keepout
			(tracks not_allowed)
			(vias allowed)
			(pads allowed)
			(copperpour not_allowed)
			(footprints allowed)
		)
		(placement
			(enabled no)
			(sheetname "")
		)
		(fill
			(thermal_gap 0.5)
			(thermal_bridge_width 0.5)
			(island_removal_mode 0)
		)
		(polygon
			(pts
				(xy 306.618894 -234.475274) (xy 308.117494 -234.475274) (xy 308.117494 -234.995212) (xy 306.618894 -234.995212)
			)
		)
	)
	(zone
		(layer "In2.Cu")
		(hatch none 0.5)
		(connect_pads
			(clearance 0)
		)
		(min_thickness 0.25)
		(keepout
			(tracks not_allowed)
			(vias allowed)
			(pads allowed)
			(copperpour not_allowed)
			(footprints allowed)
		)
		(placement
			(enabled no)
			(sheetname "")
		)
		(fill
			(thermal_gap 0.5)
			(thermal_bridge_width 0.5)
			(island_removal_mode 0)
		)
		(polygon
			(pts
				(xy 430.80686 -225.12528) (xy 432.30546 -225.12528) (xy 432.30546 -225.645218) (xy 430.80686 -225.645218)
			)
		)
	)
	(zone
		(layer "In2.Cu")
		(hatch none 0.5)
		(connect_pads
			(clearance 0)
		)
		(min_thickness 0.25)
		(keepout
			(tracks not_allowed)
			(vias allowed)
			(pads allowed)
			(copperpour not_allowed)
			(footprints allowed)
		)
		(placement
			(enabled no)
			(sheetname "")
		)
		(fill
			(thermal_gap 0.5)
			(thermal_bridge_width 0.5)
			(island_removal_mode 0)
		)
		(polygon
			(pts
				(xy 299.07484 -287.175194) (xy 300.57344 -287.175194) (xy 300.57344 -287.695132) (xy 299.07484 -287.695132)
			)
		)
	)
	(zone
		(layer "In2.Cu")
		(hatch none 0.5)
		(connect_pads
			(clearance 0)
		)
		(min_thickness 0.25)
		(keepout
			(tracks not_allowed)
			(vias allowed)
			(pads allowed)
			(copperpour not_allowed)
			(footprints allowed)
		)
		(placement
			(enabled no)
			(sheetname "")
		)
		(fill
			(thermal_gap 0.5)
			(thermal_bridge_width 0.5)
			(island_removal_mode 0)
		)
		(polygon
			(pts
				(xy 36.046664 -316.925198) (xy 37.545264 -316.925198) (xy 37.545264 -317.445136) (xy 36.046664 -317.445136)
			)
		)
	)
	(zone
		(layer "In2.Cu")
		(hatch none 0.5)
		(connect_pads
			(clearance 0)
		)
		(min_thickness 0.25)
		(keepout
			(tracks not_allowed)
			(vias allowed)
			(pads allowed)
			(copperpour not_allowed)
			(footprints allowed)
		)
		(placement
			(enabled no)
			(sheetname "")
		)
		(fill
			(thermal_gap 0.5)
			(thermal_bridge_width 0.5)
			(island_removal_mode 0)
		)
		(polygon
			(pts
				(xy 28.50261 -228.525324) (xy 30.00121 -228.525324) (xy 30.00121 -229.045262) (xy 28.50261 -229.045262)
			)
		)
	)
	(zone
		(layer "In2.Cu")
		(hatch none 0.5)
		(connect_pads
			(clearance 0)
		)
		(min_thickness 0.25)
		(keepout
			(tracks not_allowed)
			(vias allowed)
			(pads allowed)
			(copperpour not_allowed)
			(footprints allowed)
		)
		(placement
			(enabled no)
			(sheetname "")
		)
		(fill
			(thermal_gap 0.5)
			(thermal_bridge_width 0.5)
			(island_removal_mode 0)
		)
		(polygon
			(pts
				(xy 279.886664 -229.375208) (xy 281.385264 -229.375208) (xy 281.385264 -229.895146) (xy 279.886664 -229.895146)
			)
		)
	)
	(zone
		(layer "In2.Cu")
		(hatch none 0.5)
		(connect_pads
			(clearance 0)
		)
		(min_thickness 0.25)
		(keepout
			(tracks not_allowed)
			(vias allowed)
			(pads allowed)
			(copperpour not_allowed)
			(footprints allowed)
		)
		(placement
			(enabled no)
			(sheetname "")
		)
		(fill
			(thermal_gap 0.5)
			(thermal_bridge_width 0.5)
			(island_removal_mode 0)
		)
		(polygon
			(pts
				(xy 20.95881 -298.22521) (xy 22.45741 -298.22521) (xy 22.45741 -298.745148) (xy 20.95881 -298.745148)
			)
		)
	)
	(zone
		(layer "In2.Cu")
		(hatch none 0.5)
		(connect_pads
			(clearance 0)
		)
		(min_thickness 0.25)
		(keepout
			(tracks not_allowed)
			(vias allowed)
			(pads allowed)
			(copperpour not_allowed)
			(footprints allowed)
		)
		(placement
			(enabled no)
			(sheetname "")
		)
		(fill
			(thermal_gap 0.5)
			(thermal_bridge_width 0.5)
			(island_removal_mode 0)
		)
		(polygon
			(pts
				(xy 51.134772 -248.925334) (xy 52.633372 -248.925334) (xy 52.633372 -249.445272) (xy 51.134772 -249.445272)
			)
		)
	)
	(zone
		(layer "In2.Cu")
		(hatch none 0.5)
		(connect_pads
			(clearance 0)
		)
		(min_thickness 0.25)
		(keepout
			(tracks not_allowed)
			(vias allowed)
			(pads allowed)
			(copperpour not_allowed)
			(footprints allowed)
		)
		(placement
			(enabled no)
			(sheetname "")
		)
		(fill
			(thermal_gap 0.5)
			(thermal_bridge_width 0.5)
			(island_removal_mode 0)
		)
		(polygon
			(pts
				(xy 453.438768 -238.725202) (xy 454.937368 -238.725202) (xy 454.937368 -239.24514) (xy 453.438768 -239.24514)
			)
		)
	)
	(zone
		(layer "In2.Cu")
		(hatch none 0.5)
		(connect_pads
			(clearance 0)
		)
		(min_thickness 0.25)
		(keepout
			(tracks not_allowed)
			(vias allowed)
			(pads allowed)
			(copperpour not_allowed)
			(footprints allowed)
		)
		(placement
			(enabled no)
			(sheetname "")
		)
		(fill
			(thermal_gap 0.5)
			(thermal_bridge_width 0.5)
			(island_removal_mode 0)
		)
		(polygon
			(pts
				(xy 411.618684 -225.975164) (xy 413.117284 -225.975164) (xy 413.117284 -226.495102) (xy 411.618684 -226.495102)
			)
		)
	)
	(zone
		(layer "In2.Cu")
		(hatch none 0.5)
		(connect_pads
			(clearance 0)
		)
		(min_thickness 0.25)
		(keepout
			(tracks not_allowed)
			(vias allowed)
			(pads allowed)
			(copperpour not_allowed)
			(footprints allowed)
		)
		(placement
			(enabled no)
			(sheetname "")
		)
		(fill
			(thermal_gap 0.5)
			(thermal_bridge_width 0.5)
			(island_removal_mode 0)
		)
		(polygon
			(pts
				(xy 287.430718 -202.17511) (xy 288.929318 -202.17511) (xy 288.929318 -202.695048) (xy 287.430718 -202.695048)
			)
		)
	)
	(zone
		(layer "In2.Cu")
		(hatch none 0.5)
		(connect_pads
			(clearance 0)
		)
		(min_thickness 0.25)
		(keepout
			(tracks not_allowed)
			(vias allowed)
			(pads allowed)
			(copperpour not_allowed)
			(footprints allowed)
		)
		(placement
			(enabled no)
			(sheetname "")
		)
		(fill
			(thermal_gap 0.5)
			(thermal_bridge_width 0.5)
			(island_removal_mode 0)
		)
		(polygon
			(pts
				(xy 283.986732 -265.9253) (xy 285.485332 -265.9253) (xy 285.485332 -266.445238) (xy 283.986732 -266.445238)
			)
		)
	)
	(zone
		(layer "In2.Cu")
		(hatch none 0.5)
		(connect_pads
			(clearance 0)
		)
		(min_thickness 0.25)
		(keepout
			(tracks not_allowed)
			(vias allowed)
			(pads allowed)
			(copperpour not_allowed)
			(footprints allowed)
		)
		(placement
			(enabled no)
			(sheetname "")
		)
		(fill
			(thermal_gap 0.5)
			(thermal_bridge_width 0.5)
			(island_removal_mode 0)
		)
		(polygon
			(pts
				(xy 24.402542 -202.17511) (xy 25.901142 -202.17511) (xy 25.901142 -202.695048) (xy 24.402542 -202.695048)
			)
		)
	)
	(zone
		(layer "In2.Cu")
		(hatch none 0.5)
		(connect_pads
			(clearance 0)
		)
		(min_thickness 0.25)
		(keepout
			(tracks not_allowed)
			(vias allowed)
			(pads allowed)
			(copperpour not_allowed)
			(footprints allowed)
		)
		(placement
			(enabled no)
			(sheetname "")
		)
		(fill
			(thermal_gap 0.5)
			(thermal_bridge_width 0.5)
			(island_removal_mode 0)
		)
		(polygon
			(pts
				(xy 201.398632 -241.275108) (xy 202.897232 -241.275108) (xy 202.897232 -241.795046) (xy 201.398632 -241.795046)
			)
		)
	)
	(zone
		(layer "In2.Cu")
		(hatch none 0.5)
		(connect_pads
			(clearance 0)
		)
		(min_thickness 0.25)
		(keepout
			(tracks not_allowed)
			(vias allowed)
			(pads allowed)
			(copperpour not_allowed)
			(footprints allowed)
		)
		(placement
			(enabled no)
			(sheetname "")
		)
		(fill
			(thermal_gap 0.5)
			(thermal_bridge_width 0.5)
			(island_removal_mode 0)
		)
		(polygon
			(pts
				(xy 51.134772 -220.025214) (xy 52.633372 -220.025214) (xy 52.633372 -220.545152) (xy 51.134772 -220.545152)
			)
		)
	)
	(zone
		(layer "In2.Cu")
		(hatch none 0.5)
		(connect_pads
			(clearance 0)
		)
		(min_thickness 0.25)
		(keepout
			(tracks not_allowed)
			(vias allowed)
			(pads allowed)
			(copperpour not_allowed)
			(footprints allowed)
		)
		(placement
			(enabled no)
			(sheetname "")
		)
		(fill
			(thermal_gap 0.5)
			(thermal_bridge_width 0.5)
			(island_removal_mode 0)
		)
		(polygon
			(pts
				(xy 283.986732 -212.375242) (xy 285.485332 -212.375242) (xy 285.485332 -212.89518) (xy 283.986732 -212.89518)
			)
		)
	)
	(zone
		(layer "In2.Cu")
		(hatch none 0.5)
		(connect_pads
			(clearance 0)
		)
		(min_thickness 0.25)
		(keepout
			(tracks allowed)
			(vias allowed)
			(pads allowed)
			(copperpour allowed)
			(footprints allowed)
		)
		(placement
			(enabled no)
			(sheetname "")
		)
		(fill
			(thermal_gap 0.5)
			(thermal_bridge_width 0.5)
			(island_removal_mode 0)
		)
		(polygon
			(pts
				(xy 56.97601 -349.122492) (xy 56.97601 -348.500192) (xy 57.52719 -348.500192) (xy 57.52719 -349.122492)
			)
		)
	)
	(zone
		(layer "In2.Cu")
		(hatch none 0.5)
		(connect_pads
			(clearance 0)
		)
		(min_thickness 0.25)
		(keepout
			(tracks not_allowed)
			(vias allowed)
			(pads allowed)
			(copperpour not_allowed)
			(footprints allowed)
		)
		(placement
			(enabled no)
			(sheetname "")
		)
		(fill
			(thermal_gap 0.5)
			(thermal_bridge_width 0.5)
			(island_removal_mode 0)
		)
		(polygon
			(pts
				(xy 190.410846 -215.775286) (xy 191.909446 -215.775286) (xy 191.909446 -216.295224) (xy 190.410846 -216.295224)
			)
		)
	)
	(zone
		(layer "In2.Cu")
		(hatch none 0.5)
		(connect_pads
			(clearance 0)
		)
		(min_thickness 0.25)
		(keepout
			(tracks not_allowed)
			(vias allowed)
			(pads allowed)
			(copperpour not_allowed)
			(footprints allowed)
		)
		(placement
			(enabled no)
			(sheetname "")
		)
		(fill
			(thermal_gap 0.5)
			(thermal_bridge_width 0.5)
			(island_removal_mode 0)
		)
		(polygon
			(pts
				(xy 47.034704 -274.425156) (xy 48.533304 -274.425156) (xy 48.533304 -274.945094) (xy 47.034704 -274.945094)
			)
		)
	)
	(zone
		(layer "In2.Cu")
		(hatch none 0.5)
		(connect_pads
			(clearance 0)
		)
		(min_thickness 0.25)
		(keepout
			(tracks not_allowed)
			(vias allowed)
			(pads allowed)
			(copperpour not_allowed)
			(footprints allowed)
		)
		(placement
			(enabled no)
			(sheetname "")
		)
		(fill
			(thermal_gap 0.5)
			(thermal_bridge_width 0.5)
			(island_removal_mode 0)
		)
		(polygon
			(pts
				(xy 419.162738 -308.425342) (xy 420.661338 -308.425342) (xy 420.661338 -308.94528) (xy 419.162738 -308.94528)
			)
		)
	)
	(zone
		(layer "In2.Cu")
		(hatch none 0.5)
		(connect_pads
			(clearance 0)
		)
		(min_thickness 0.25)
		(keepout
			(tracks not_allowed)
			(vias allowed)
			(pads allowed)
			(copperpour not_allowed)
			(footprints allowed)
		)
		(placement
			(enabled no)
			(sheetname "")
		)
		(fill
			(thermal_gap 0.5)
			(thermal_bridge_width 0.5)
			(island_removal_mode 0)
		)
		(polygon
			(pts
				(xy 449.3387 -210.67522) (xy 450.8373 -210.67522) (xy 450.8373 -211.195158) (xy 449.3387 -211.195158)
			)
		)
	)
	(zone
		(layer "In2.Cu")
		(hatch none 0.5)
		(connect_pads
			(clearance 0)
		)
		(min_thickness 0.25)
		(keepout
			(tracks not_allowed)
			(vias allowed)
			(pads allowed)
			(copperpour not_allowed)
			(footprints allowed)
		)
		(placement
			(enabled no)
			(sheetname "")
		)
		(fill
			(thermal_gap 0.5)
			(thermal_bridge_width 0.5)
			(island_removal_mode 0)
		)
		(polygon
			(pts
				(xy 287.430718 -310.12511) (xy 288.929318 -310.12511) (xy 288.929318 -310.645048) (xy 287.430718 -310.645048)
			)
		)
	)
	(zone
		(layer "In2.Cu")
		(hatch none 0.5)
		(connect_pads
			(clearance 0)
		)
		(min_thickness 0.25)
		(keepout
			(tracks not_allowed)
			(vias allowed)
			(pads allowed)
			(copperpour not_allowed)
			(footprints allowed)
		)
		(placement
			(enabled no)
			(sheetname "")
		)
		(fill
			(thermal_gap 0.5)
			(thermal_bridge_width 0.5)
			(island_removal_mode 0)
		)
		(polygon
			(pts
				(xy 197.954646 -290.575238) (xy 199.453246 -290.575238) (xy 199.453246 -291.095176) (xy 197.954646 -291.095176)
			)
		)
	)
	(zone
		(layer "In2.Cu")
		(hatch none 0.5)
		(connect_pads
			(clearance 0)
		)
		(min_thickness 0.25)
		(keepout
			(tracks not_allowed)
			(vias allowed)
			(pads allowed)
			(copperpour not_allowed)
			(footprints allowed)
		)
		(placement
			(enabled no)
			(sheetname "")
		)
		(fill
			(thermal_gap 0.5)
			(thermal_bridge_width 0.5)
			(island_removal_mode 0)
		)
		(polygon
			(pts
				(xy 302.518826 -261.675118) (xy 304.017426 -261.675118) (xy 304.017426 -262.195056) (xy 302.518826 -262.195056)
			)
		)
	)
	(zone
		(layer "In2.Cu")
		(hatch none 0.5)
		(connect_pads
			(clearance 0)
		)
		(min_thickness 0.25)
		(keepout
			(tracks not_allowed)
			(vias allowed)
			(pads allowed)
			(copperpour not_allowed)
			(footprints allowed)
		)
		(placement
			(enabled no)
			(sheetname "")
		)
		(fill
			(thermal_gap 0.5)
			(thermal_bridge_width 0.5)
			(island_removal_mode 0)
		)
		(polygon
			(pts
				(xy 28.50261 -287.175194) (xy 30.00121 -287.175194) (xy 30.00121 -287.695132) (xy 28.50261 -287.695132)
			)
		)
	)
	(zone
		(layer "In2.Cu")
		(hatch none 0.5)
		(connect_pads
			(clearance 0)
		)
		(min_thickness 0.25)
		(keepout
			(tracks not_allowed)
			(vias allowed)
			(pads allowed)
			(copperpour not_allowed)
			(footprints allowed)
		)
		(placement
			(enabled no)
			(sheetname "")
		)
		(fill
			(thermal_gap 0.5)
			(thermal_bridge_width 0.5)
			(island_removal_mode 0)
		)
		(polygon
			(pts
				(xy 47.034704 -297.375326) (xy 48.533304 -297.375326) (xy 48.533304 -297.895264) (xy 47.034704 -297.895264)
			)
		)
	)
	(zone
		(layer "In2.Cu")
		(hatch none 0.5)
		(connect_pads
			(clearance 0)
		)
		(min_thickness 0.25)
		(keepout
			(tracks not_allowed)
			(vias allowed)
			(pads allowed)
			(copperpour not_allowed)
			(footprints allowed)
		)
		(placement
			(enabled no)
			(sheetname "")
		)
		(fill
			(thermal_gap 0.5)
			(thermal_bridge_width 0.5)
			(island_removal_mode 0)
		)
		(polygon
			(pts
				(xy 423.262806 -236.175296) (xy 424.761406 -236.175296) (xy 424.761406 -236.695234) (xy 423.262806 -236.695234)
			)
		)
	)
	(zone
		(layer "In2.Cu")
		(hatch none 0.5)
		(connect_pads
			(clearance 0)
		)
		(min_thickness 0.25)
		(keepout
			(tracks not_allowed)
			(vias allowed)
			(pads allowed)
			(copperpour not_allowed)
			(footprints allowed)
		)
		(placement
			(enabled no)
			(sheetname "")
		)
		(fill
			(thermal_gap 0.5)
			(thermal_bridge_width 0.5)
			(island_removal_mode 0)
		)
		(polygon
			(pts
				(xy 268.898878 -281.225244) (xy 270.397478 -281.225244) (xy 270.397478 -281.745182) (xy 268.898878 -281.745182)
			)
		)
	)
	(zone
		(layer "In2.Cu")
		(hatch none 0.5)
		(connect_pads
			(clearance 0)
		)
		(min_thickness 0.25)
		(keepout
			(tracks not_allowed)
			(vias allowed)
			(pads allowed)
			(copperpour not_allowed)
			(footprints allowed)
		)
		(placement
			(enabled no)
			(sheetname "")
		)
		(fill
			(thermal_gap 0.5)
			(thermal_bridge_width 0.5)
			(island_removal_mode 0)
		)
		(polygon
			(pts
				(xy 449.3387 -239.57534) (xy 450.8373 -239.57534) (xy 450.8373 -240.095278) (xy 449.3387 -240.095278)
			)
		)
	)
	(zone
		(layer "In2.Cu")
		(hatch none 0.5)
		(connect_pads
			(clearance 0)
		)
		(min_thickness 0.25)
		(keepout
			(tracks not_allowed)
			(vias allowed)
			(pads allowed)
			(copperpour not_allowed)
			(footprints allowed)
		)
		(placement
			(enabled no)
			(sheetname "")
		)
		(fill
			(thermal_gap 0.5)
			(thermal_bridge_width 0.5)
			(island_removal_mode 0)
		)
		(polygon
			(pts
				(xy 419.162738 -235.325158) (xy 420.661338 -235.325158) (xy 420.661338 -235.845096) (xy 419.162738 -235.845096)
			)
		)
	)
	(zone
		(layer "In2.Cu")
		(hatch none 0.5)
		(connect_pads
			(clearance 0)
		)
		(min_thickness 0.25)
		(keepout
			(tracks not_allowed)
			(vias allowed)
			(pads allowed)
			(copperpour not_allowed)
			(footprints allowed)
		)
		(placement
			(enabled no)
			(sheetname "")
		)
		(fill
			(thermal_gap 0.5)
			(thermal_bridge_width 0.5)
			(island_removal_mode 0)
		)
		(polygon
			(pts
				(xy 167.778684 -313.525154) (xy 169.277284 -313.525154) (xy 169.277284 -314.045092) (xy 167.778684 -314.045092)
			)
		)
	)
	(zone
		(layer "In2.Cu")
		(hatch none 0.5)
		(connect_pads
			(clearance 0)
		)
		(min_thickness 0.25)
		(keepout
			(tracks not_allowed)
			(vias allowed)
			(pads allowed)
			(copperpour not_allowed)
			(footprints allowed)
		)
		(placement
			(enabled no)
			(sheetname "")
		)
		(fill
			(thermal_gap 0.5)
			(thermal_bridge_width 0.5)
			(island_removal_mode 0)
		)
		(polygon
			(pts
				(xy 291.530786 -262.525256) (xy 293.029386 -262.525256) (xy 293.029386 -263.045194) (xy 291.530786 -263.045194)
			)
		)
	)
	(zone
		(layer "In2.Cu")
		(hatch none 0.5)
		(connect_pads
			(clearance 0)
		)
		(min_thickness 0.25)
		(keepout
			(tracks not_allowed)
			(vias allowed)
			(pads allowed)
			(copperpour not_allowed)
			(footprints allowed)
		)
		(placement
			(enabled no)
			(sheetname "")
		)
		(fill
			(thermal_gap 0.5)
			(thermal_bridge_width 0.5)
			(island_removal_mode 0)
		)
		(polygon
			(pts
				(xy 279.886664 -297.375326) (xy 281.385264 -297.375326) (xy 281.385264 -297.895264) (xy 279.886664 -297.895264)
			)
		)
	)
	(zone
		(layer "In2.Cu")
		(hatch none 0.5)
		(connect_pads
			(clearance 0)
		)
		(min_thickness 0.25)
		(keepout
			(tracks not_allowed)
			(vias allowed)
			(pads allowed)
			(copperpour not_allowed)
			(footprints allowed)
		)
		(placement
			(enabled no)
			(sheetname "")
		)
		(fill
			(thermal_gap 0.5)
			(thermal_bridge_width 0.5)
			(island_removal_mode 0)
		)
		(polygon
			(pts
				(xy 419.162738 -227.675186) (xy 420.661338 -227.675186) (xy 420.661338 -228.195124) (xy 419.162738 -228.195124)
			)
		)
	)
	(zone
		(layer "In2.Cu")
		(hatch none 0.5)
		(connect_pads
			(clearance 0)
		)
		(min_thickness 0.25)
		(keepout
			(tracks not_allowed)
			(vias allowed)
			(pads allowed)
			(copperpour not_allowed)
			(footprints allowed)
		)
		(placement
			(enabled no)
			(sheetname "")
		)
		(fill
			(thermal_gap 0.5)
			(thermal_bridge_width 0.5)
			(island_removal_mode 0)
		)
		(polygon
			(pts
				(xy 453.438768 -229.375208) (xy 454.937368 -229.375208) (xy 454.937368 -229.895146) (xy 453.438768 -229.895146)
			)
		)
	)
	(zone
		(layer "In2.Cu")
		(hatch none 0.5)
		(connect_pads
			(clearance 0)
		)
		(min_thickness 0.25)
		(keepout
			(tracks not_allowed)
			(vias allowed)
			(pads allowed)
			(copperpour not_allowed)
			(footprints allowed)
		)
		(placement
			(enabled no)
			(sheetname "")
		)
		(fill
			(thermal_gap 0.5)
			(thermal_bridge_width 0.5)
			(island_removal_mode 0)
		)
		(polygon
			(pts
				(xy 294.974772 -316.075314) (xy 296.473372 -316.075314) (xy 296.473372 -316.595252) (xy 294.974772 -316.595252)
			)
		)
	)
	(zone
		(layer "In2.Cu")
		(hatch none 0.5)
		(connect_pads
			(clearance 0)
		)
		(min_thickness 0.25)
		(keepout
			(tracks not_allowed)
			(vias allowed)
			(pads allowed)
			(copperpour not_allowed)
			(footprints allowed)
		)
		(placement
			(enabled no)
			(sheetname "")
		)
		(fill
			(thermal_gap 0.5)
			(thermal_bridge_width 0.5)
			(island_removal_mode 0)
		)
		(polygon
			(pts
				(arc
					(start 331.088238 -385.11861)
					(mid 331.079002 -385.138534)
					(end 331.075792 -385.160266)
				)
				(arc
					(start 331.075792 -385.35483)
					(mid 331.09811 -385.408712)
					(end 331.151992 -385.43103)
				)
				(arc
					(start 331.837792 -385.43103)
					(mid 331.891674 -385.408712)
					(end 331.913992 -385.35483)
				)
				(arc
					(start 331.913992 -385.160266)
					(mid 331.910824 -385.138522)
					(end 331.901546 -385.11861)
				)
				(arc
					(start 331.70876 -384.822446)
					(mid 331.696538 -384.780762)
					(end 331.709014 -384.739134)
				)
				(arc
					(start 331.901546 -384.44551)
					(mid 331.910782 -384.425586)
					(end 331.913992 -384.403854)
				)
				(arc
					(start 331.913992 -384.20929)
					(mid 331.891674 -384.155408)
					(end 331.837792 -384.13309)
				)
				(arc
					(start 331.151992 -384.13309)
					(mid 331.09811 -384.155408)
					(end 331.075792 -384.20929)
				)
				(arc
					(start 331.075792 -384.405124)
					(mid 331.07896 -384.426868)
					(end 331.088238 -384.44678)
				)
				(arc
					(start 331.28077 -384.740404)
					(mid 331.293172 -384.78206)
					(end 331.28077 -384.823716)
				)
			)
		)
	)
	(zone
		(layer "In2.Cu")
		(hatch none 0.5)
		(connect_pads
			(clearance 0)
		)
		(min_thickness 0.25)
		(keepout
			(tracks not_allowed)
			(vias allowed)
			(pads allowed)
			(copperpour not_allowed)
			(footprints allowed)
		)
		(placement
			(enabled no)
			(sheetname "")
		)
		(fill
			(thermal_gap 0.5)
			(thermal_bridge_width 0.5)
			(island_removal_mode 0)
		)
		(polygon
			(pts
				(xy 16.858742 -276.125178) (xy 18.357342 -276.125178) (xy 18.357342 -276.645116) (xy 16.858742 -276.645116)
			)
		)
	)
	(zone
		(layer "In2.Cu")
		(hatch none 0.5)
		(connect_pads
			(clearance 0)
		)
		(min_thickness 0.25)
		(keepout
			(tracks not_allowed)
			(vias allowed)
			(pads allowed)
			(copperpour not_allowed)
			(footprints allowed)
		)
		(placement
			(enabled no)
			(sheetname "")
		)
		(fill
			(thermal_gap 0.5)
			(thermal_bridge_width 0.5)
			(island_removal_mode 0)
		)
		(polygon
			(pts
				(xy 294.974772 -276.975316) (xy 296.473372 -276.975316) (xy 296.473372 -277.495254) (xy 294.974772 -277.495254)
			)
		)
	)
	(zone
		(layer "In2.Cu")
		(hatch none 0.5)
		(connect_pads
			(clearance 0)
		)
		(min_thickness 0.25)
		(keepout
			(tracks not_allowed)
			(vias allowed)
			(pads allowed)
			(copperpour not_allowed)
			(footprints allowed)
		)
		(placement
			(enabled no)
			(sheetname "")
		)
		(fill
			(thermal_gap 0.5)
			(thermal_bridge_width 0.5)
			(island_removal_mode 0)
		)
		(polygon
			(pts
				(xy 291.530786 -294.825166) (xy 293.029386 -294.825166) (xy 293.029386 -295.345104) (xy 291.530786 -295.345104)
			)
		)
	)
	(zone
		(layer "In2.Cu")
		(hatch none 0.5)
		(connect_pads
			(clearance 0)
		)
		(min_thickness 0.25)
		(keepout
			(tracks not_allowed)
			(vias allowed)
			(pads allowed)
			(copperpour not_allowed)
			(footprints allowed)
		)
		(placement
			(enabled no)
			(sheetname "")
		)
		(fill
			(thermal_gap 0.5)
			(thermal_bridge_width 0.5)
			(island_removal_mode 0)
		)
		(polygon
			(pts
				(xy 28.50261 -267.625322) (xy 30.00121 -267.625322) (xy 30.00121 -268.14526) (xy 28.50261 -268.14526)
			)
		)
	)
	(zone
		(layer "In2.Cu")
		(hatch none 0.5)
		(connect_pads
			(clearance 0)
		)
		(min_thickness 0.25)
		(keepout
			(tracks not_allowed)
			(vias allowed)
			(pads allowed)
			(copperpour not_allowed)
			(footprints allowed)
		)
		(placement
			(enabled no)
			(sheetname "")
		)
		(fill
			(thermal_gap 0.5)
			(thermal_bridge_width 0.5)
			(island_removal_mode 0)
		)
		(polygon
			(pts
				(xy 16.858742 -216.62517) (xy 18.357342 -216.62517) (xy 18.357342 -217.145108) (xy 16.858742 -217.145108)
			)
		)
	)
	(zone
		(layer "In2.Cu")
		(hatch none 0.5)
		(connect_pads
			(clearance 0)
		)
		(min_thickness 0.25)
		(keepout
			(tracks not_allowed)
			(vias allowed)
			(pads allowed)
			(copperpour not_allowed)
			(footprints allowed)
		)
		(placement
			(enabled no)
			(sheetname "")
		)
		(fill
			(thermal_gap 0.5)
			(thermal_bridge_width 0.5)
			(island_removal_mode 0)
		)
		(polygon
			(pts
				(xy 306.618894 -225.12528) (xy 308.117494 -225.12528) (xy 308.117494 -225.645218) (xy 306.618894 -225.645218)
			)
		)
	)
	(zone
		(layer "In2.Cu")
		(hatch none 0.5)
		(connect_pads
			(clearance 0)
		)
		(min_thickness 0.25)
		(keepout
			(tracks not_allowed)
			(vias allowed)
			(pads allowed)
			(copperpour not_allowed)
			(footprints allowed)
		)
		(placement
			(enabled no)
			(sheetname "")
		)
		(fill
			(thermal_gap 0.5)
			(thermal_bridge_width 0.5)
			(island_removal_mode 0)
		)
		(polygon
			(pts
				(xy 279.886664 -310.12511) (xy 281.385264 -310.12511) (xy 281.385264 -310.645048) (xy 279.886664 -310.645048)
			)
		)
	)
	(zone
		(layer "In2.Cu")
		(hatch none 0.5)
		(connect_pads
			(clearance 0)
		)
		(min_thickness 0.25)
		(keepout
			(tracks not_allowed)
			(vias allowed)
			(pads allowed)
			(copperpour not_allowed)
			(footprints allowed)
		)
		(placement
			(enabled no)
			(sheetname "")
		)
		(fill
			(thermal_gap 0.5)
			(thermal_bridge_width 0.5)
			(island_removal_mode 0)
		)
		(polygon
			(pts
				(xy 294.974772 -233.625136) (xy 296.473372 -233.625136) (xy 296.473372 -234.145074) (xy 294.974772 -234.145074)
			)
		)
	)
	(zone
		(layer "In2.Cu")
		(hatch none 0.5)
		(connect_pads
			(clearance 0)
		)
		(min_thickness 0.25)
		(keepout
			(tracks not_allowed)
			(vias allowed)
			(pads allowed)
			(copperpour not_allowed)
			(footprints allowed)
		)
		(placement
			(enabled no)
			(sheetname "")
		)
		(fill
			(thermal_gap 0.5)
			(thermal_bridge_width 0.5)
			(island_removal_mode 0)
		)
		(polygon
			(pts
				(xy 302.518826 -299.075348) (xy 304.017426 -299.075348) (xy 304.017426 -299.595286) (xy 302.518826 -299.595286)
			)
		)
	)
	(zone
		(layer "In2.Cu")
		(hatch none 0.5)
		(connect_pads
			(clearance 0)
		)
		(min_thickness 0.25)
		(keepout
			(tracks not_allowed)
			(vias allowed)
			(pads allowed)
			(copperpour not_allowed)
			(footprints allowed)
		)
		(placement
			(enabled no)
			(sheetname "")
		)
		(fill
			(thermal_gap 0.5)
			(thermal_bridge_width 0.5)
			(island_removal_mode 0)
		)
		(polygon
			(pts
				(xy 287.430718 -306.72532) (xy 288.929318 -306.72532) (xy 288.929318 -307.245258) (xy 287.430718 -307.245258)
			)
		)
	)
	(zone
		(layer "In2.Cu")
		(hatch none 0.5)
		(connect_pads
			(clearance 0)
		)
		(min_thickness 0.25)
		(keepout
			(tracks not_allowed)
			(vias allowed)
			(pads allowed)
			(copperpour not_allowed)
			(footprints allowed)
		)
		(placement
			(enabled no)
			(sheetname "")
		)
		(fill
			(thermal_gap 0.5)
			(thermal_bridge_width 0.5)
			(island_removal_mode 0)
		)
		(polygon
			(pts
				(xy 58.678826 -236.175296) (xy 60.177426 -236.175296) (xy 60.177426 -236.695234) (xy 58.678826 -236.695234)
			)
		)
	)
	(zone
		(layer "In2.Cu")
		(hatch none 0.5)
		(connect_pads
			(clearance 0)
		)
		(min_thickness 0.25)
		(keepout
			(tracks not_allowed)
			(vias allowed)
			(pads allowed)
			(copperpour not_allowed)
			(footprints allowed)
		)
		(placement
			(enabled no)
			(sheetname "")
		)
		(fill
			(thermal_gap 0.5)
			(thermal_bridge_width 0.5)
			(island_removal_mode 0)
		)
		(polygon
			(pts
				(xy 415.718752 -212.375242) (xy 417.217352 -212.375242) (xy 417.217352 -212.89518) (xy 415.718752 -212.89518)
			)
		)
	)
	(zone
		(layer "In2.Cu")
		(hatch none 0.5)
		(connect_pads
			(clearance 0)
		)
		(min_thickness 0.25)
		(keepout
			(tracks not_allowed)
			(vias allowed)
			(pads allowed)
			(copperpour not_allowed)
			(footprints allowed)
		)
		(placement
			(enabled no)
			(sheetname "")
		)
		(fill
			(thermal_gap 0.5)
			(thermal_bridge_width 0.5)
			(island_removal_mode 0)
		)
		(polygon
			(pts
				(xy 268.898878 -204.72527) (xy 270.397478 -204.72527) (xy 270.397478 -205.245208) (xy 268.898878 -205.245208)
			)
		)
	)
	(zone
		(layer "In2.Cu")
		(hatch none 0.5)
		(connect_pads
			(clearance 0)
		)
		(min_thickness 0.25)
		(keepout
			(tracks not_allowed)
			(vias allowed)
			(pads allowed)
			(copperpour not_allowed)
			(footprints allowed)
		)
		(placement
			(enabled no)
			(sheetname "")
		)
		(fill
			(thermal_gap 0.5)
			(thermal_bridge_width 0.5)
			(island_removal_mode 0)
		)
		(polygon
			(pts
				(xy 411.618684 -214.925148) (xy 413.117284 -214.925148) (xy 413.117284 -215.445086) (xy 411.618684 -215.445086)
			)
		)
	)
	(zone
		(layer "In2.Cu")
		(hatch none 0.5)
		(connect_pads
			(clearance 0)
		)
		(min_thickness 0.25)
		(keepout
			(tracks not_allowed)
			(vias allowed)
			(pads allowed)
			(copperpour not_allowed)
			(footprints allowed)
		)
		(placement
			(enabled no)
			(sheetname "")
		)
		(fill
			(thermal_gap 0.5)
			(thermal_bridge_width 0.5)
			(island_removal_mode 0)
		)
		(polygon
			(pts
				(xy 423.262806 -315.225176) (xy 424.761406 -315.225176) (xy 424.761406 -315.745114) (xy 423.262806 -315.745114)
			)
		)
	)
	(zone
		(layer "In2.Cu")
		(hatch none 0.5)
		(connect_pads
			(clearance 0)
		)
		(min_thickness 0.25)
		(keepout
			(tracks not_allowed)
			(vias allowed)
			(pads allowed)
			(copperpour not_allowed)
			(footprints allowed)
		)
		(placement
			(enabled no)
			(sheetname "")
		)
		(fill
			(thermal_gap 0.5)
			(thermal_bridge_width 0.5)
			(island_removal_mode 0)
		)
		(polygon
			(pts
				(xy 167.778684 -270.175228) (xy 169.277284 -270.175228) (xy 169.277284 -270.695166) (xy 167.778684 -270.695166)
			)
		)
	)
	(zone
		(layer "In2.Cu")
		(hatch none 0.5)
		(connect_pads
			(clearance 0)
		)
		(min_thickness 0.25)
		(keepout
			(tracks not_allowed)
			(vias allowed)
			(pads allowed)
			(copperpour not_allowed)
			(footprints allowed)
		)
		(placement
			(enabled no)
			(sheetname "")
		)
		(fill
			(thermal_gap 0.5)
			(thermal_bridge_width 0.5)
			(island_removal_mode 0)
		)
		(polygon
			(pts
				(xy 171.22267 -199.625204) (xy 172.72127 -199.625204) (xy 172.72127 -200.145142) (xy 171.22267 -200.145142)
			)
		)
	)
	(zone
		(layer "In2.Cu")
		(hatch none 0.5)
		(connect_pads
			(clearance 0)
		)
		(min_thickness 0.25)
		(keepout
			(tracks not_allowed)
			(vias allowed)
			(pads allowed)
			(copperpour not_allowed)
			(footprints allowed)
		)
		(placement
			(enabled no)
			(sheetname "")
		)
		(fill
			(thermal_gap 0.5)
			(thermal_bridge_width 0.5)
			(island_removal_mode 0)
		)
		(polygon
			(pts
				(xy 430.80686 -212.375242) (xy 432.30546 -212.375242) (xy 432.30546 -212.89518) (xy 430.80686 -212.89518)
			)
		)
	)
	(zone
		(layer "In2.Cu")
		(hatch none 0.5)
		(connect_pads
			(clearance 0)
		)
		(min_thickness 0.25)
		(keepout
			(tracks not_allowed)
			(vias allowed)
			(pads allowed)
			(copperpour not_allowed)
			(footprints allowed)
		)
		(placement
			(enabled no)
			(sheetname "")
		)
		(fill
			(thermal_gap 0.5)
			(thermal_bridge_width 0.5)
			(island_removal_mode 0)
		)
		(polygon
			(pts
				(xy 302.518826 -201.325226) (xy 304.017426 -201.325226) (xy 304.017426 -201.845164) (xy 302.518826 -201.845164)
			)
		)
	)
	(zone
		(layer "In2.Cu")
		(hatch none 0.5)
		(connect_pads
			(clearance 0)
		)
		(min_thickness 0.25)
		(keepout
			(tracks not_allowed)
			(vias allowed)
			(pads allowed)
			(copperpour not_allowed)
			(footprints allowed)
		)
		(placement
			(enabled no)
			(sheetname "")
		)
		(fill
			(thermal_gap 0.5)
			(thermal_bridge_width 0.5)
			(island_removal_mode 0)
		)
		(polygon
			(pts
				(xy 423.262806 -284.625288) (xy 424.761406 -284.625288) (xy 424.761406 -285.145226) (xy 423.262806 -285.145226)
			)
		)
	)
	(zone
		(layer "In2.Cu")
		(hatch none 0.5)
		(connect_pads
			(clearance 0)
		)
		(min_thickness 0.25)
		(keepout
			(tracks not_allowed)
			(vias allowed)
			(pads allowed)
			(copperpour not_allowed)
			(footprints allowed)
		)
		(placement
			(enabled no)
			(sheetname "")
		)
		(fill
			(thermal_gap 0.5)
			(thermal_bridge_width 0.5)
			(island_removal_mode 0)
		)
		(polygon
			(pts
				(xy 441.7949 -276.125178) (xy 443.2935 -276.125178) (xy 443.2935 -276.645116) (xy 441.7949 -276.645116)
			)
		)
	)
	(zone
		(layer "In2.Cu")
		(hatch none 0.5)
		(connect_pads
			(clearance 0)
		)
		(min_thickness 0.25)
		(keepout
			(tracks not_allowed)
			(vias allowed)
			(pads allowed)
			(copperpour not_allowed)
			(footprints allowed)
		)
		(placement
			(enabled no)
			(sheetname "")
		)
		(fill
			(thermal_gap 0.5)
			(thermal_bridge_width 0.5)
			(island_removal_mode 0)
		)
		(polygon
			(pts
				(xy 190.410846 -212.375242) (xy 191.909446 -212.375242) (xy 191.909446 -212.89518) (xy 190.410846 -212.89518)
			)
		)
	)
	(zone
		(layer "In2.Cu")
		(hatch none 0.5)
		(connect_pads
			(clearance 0)
		)
		(min_thickness 0.25)
		(keepout
			(tracks not_allowed)
			(vias allowed)
			(pads allowed)
			(copperpour not_allowed)
			(footprints allowed)
		)
		(placement
			(enabled no)
			(sheetname "")
		)
		(fill
			(thermal_gap 0.5)
			(thermal_bridge_width 0.5)
			(island_removal_mode 0)
		)
		(polygon
			(pts
				(xy 31.946596 -316.075314) (xy 33.445196 -316.075314) (xy 33.445196 -316.595252) (xy 31.946596 -316.595252)
			)
		)
	)
	(zone
		(layer "In2.Cu")
		(hatch none 0.5)
		(connect_pads
			(clearance 0)
		)
		(min_thickness 0.25)
		(keepout
			(tracks not_allowed)
			(vias allowed)
			(pads allowed)
			(copperpour not_allowed)
			(footprints allowed)
		)
		(placement
			(enabled no)
			(sheetname "")
		)
		(fill
			(thermal_gap 0.5)
			(thermal_bridge_width 0.5)
			(island_removal_mode 0)
		)
		(polygon
			(pts
				(xy 434.250846 -317.775336) (xy 435.749446 -317.775336) (xy 435.749446 -318.295274) (xy 434.250846 -318.295274)
			)
		)
	)
	(zone
		(layer "In2.Cu")
		(hatch none 0.5)
		(connect_pads
			(clearance 0)
		)
		(min_thickness 0.25)
		(keepout
			(tracks not_allowed)
			(vias allowed)
			(pads allowed)
			(copperpour not_allowed)
			(footprints allowed)
		)
		(placement
			(enabled no)
			(sheetname "")
		)
		(fill
			(thermal_gap 0.5)
			(thermal_bridge_width 0.5)
			(island_removal_mode 0)
		)
		(polygon
			(pts
				(xy 294.974772 -235.325158) (xy 296.473372 -235.325158) (xy 296.473372 -235.845096) (xy 294.974772 -235.845096)
			)
		)
	)
	(zone
		(layer "In2.Cu")
		(hatch none 0.5)
		(connect_pads
			(clearance 0)
		)
		(min_thickness 0.25)
		(keepout
			(tracks not_allowed)
			(vias allowed)
			(pads allowed)
			(copperpour not_allowed)
			(footprints allowed)
		)
		(placement
			(enabled no)
			(sheetname "")
		)
		(fill
			(thermal_gap 0.5)
			(thermal_bridge_width 0.5)
			(island_removal_mode 0)
		)
		(polygon
			(pts
				(xy 16.858742 -268.475206) (xy 18.357342 -268.475206) (xy 18.357342 -268.995144) (xy 16.858742 -268.995144)
			)
		)
	)
	(zone
		(layer "In2.Cu")
		(hatch none 0.5)
		(connect_pads
			(clearance 0)
		)
		(min_thickness 0.25)
		(keepout
			(tracks not_allowed)
			(vias allowed)
			(pads allowed)
			(copperpour not_allowed)
			(footprints allowed)
		)
		(placement
			(enabled no)
			(sheetname "")
		)
		(fill
			(thermal_gap 0.5)
			(thermal_bridge_width 0.5)
			(island_removal_mode 0)
		)
		(polygon
			(pts
				(xy 283.986732 -226.825302) (xy 285.485332 -226.825302) (xy 285.485332 -227.34524) (xy 283.986732 -227.34524)
			)
		)
	)
	(zone
		(layer "In2.Cu")
		(hatch none 0.5)
		(connect_pads
			(clearance 0)
		)
		(min_thickness 0.25)
		(keepout
			(tracks not_allowed)
			(vias allowed)
			(pads allowed)
			(copperpour not_allowed)
			(footprints allowed)
		)
		(placement
			(enabled no)
			(sheetname "")
		)
		(fill
			(thermal_gap 0.5)
			(thermal_bridge_width 0.5)
			(island_removal_mode 0)
		)
		(polygon
			(pts
				(xy 197.954646 -265.9253) (xy 199.453246 -265.9253) (xy 199.453246 -266.445238) (xy 197.954646 -266.445238)
			)
		)
	)
	(zone
		(layer "In2.Cu")
		(hatch none 0.5)
		(connect_pads
			(clearance 0)
		)
		(min_thickness 0.25)
		(keepout
			(tracks not_allowed)
			(vias allowed)
			(pads allowed)
			(copperpour not_allowed)
			(footprints allowed)
		)
		(placement
			(enabled no)
			(sheetname "")
		)
		(fill
			(thermal_gap 0.5)
			(thermal_bridge_width 0.5)
			(island_removal_mode 0)
		)
		(polygon
			(pts
				(xy 291.530786 -242.125246) (xy 293.029386 -242.125246) (xy 293.029386 -242.645184) (xy 291.530786 -242.645184)
			)
		)
	)
	(zone
		(layer "In2.Cu")
		(hatch none 0.5)
		(connect_pads
			(clearance 0)
		)
		(min_thickness 0.25)
		(keepout
			(tracks not_allowed)
			(vias allowed)
			(pads allowed)
			(copperpour not_allowed)
			(footprints allowed)
		)
		(placement
			(enabled no)
			(sheetname "")
		)
		(fill
			(thermal_gap 0.5)
			(thermal_bridge_width 0.5)
			(island_removal_mode 0)
		)
		(polygon
			(pts
				(xy 272.342864 -239.57534) (xy 273.841464 -239.57534) (xy 273.841464 -240.095278) (xy 272.342864 -240.095278)
			)
		)
	)
	(zone
		(layer "In2.Cu")
		(hatch none 0.5)
		(connect_pads
			(clearance 0)
		)
		(min_thickness 0.25)
		(keepout
			(tracks not_allowed)
			(vias allowed)
			(pads allowed)
			(copperpour not_allowed)
			(footprints allowed)
		)
		(placement
			(enabled no)
			(sheetname "")
		)
		(fill
			(thermal_gap 0.5)
			(thermal_bridge_width 0.5)
			(island_removal_mode 0)
		)
		(polygon
			(pts
				(xy 449.3387 -272.725134) (xy 450.8373 -272.725134) (xy 450.8373 -273.245072) (xy 449.3387 -273.245072)
			)
		)
	)
	(zone
		(layer "In2.Cu")
		(hatch none 0.5)
		(connect_pads
			(clearance 0)
		)
		(min_thickness 0.25)
		(keepout
			(tracks not_allowed)
			(vias allowed)
			(pads allowed)
			(copperpour not_allowed)
			(footprints allowed)
		)
		(placement
			(enabled no)
			(sheetname "")
		)
		(fill
			(thermal_gap 0.5)
			(thermal_bridge_width 0.5)
			(island_removal_mode 0)
		)
		(polygon
			(pts
				(xy 306.618894 -204.72527) (xy 308.117494 -204.72527) (xy 308.117494 -205.245208) (xy 306.618894 -205.245208)
			)
		)
	)
	(zone
		(layer "In2.Cu")
		(hatch none 0.5)
		(connect_pads
			(clearance 0)
		)
		(min_thickness 0.25)
		(keepout
			(tracks not_allowed)
			(vias allowed)
			(pads allowed)
			(copperpour not_allowed)
			(footprints allowed)
		)
		(placement
			(enabled no)
			(sheetname "")
		)
		(fill
			(thermal_gap 0.5)
			(thermal_bridge_width 0.5)
			(island_removal_mode 0)
		)
		(polygon
			(pts
				(xy 193.854578 -222.57512) (xy 195.353178 -222.57512) (xy 195.353178 -223.095058) (xy 193.854578 -223.095058)
			)
		)
	)
	(zone
		(layer "In2.Cu")
		(hatch none 0.5)
		(connect_pads
			(clearance 0)
		)
		(min_thickness 0.25)
		(keepout
			(tracks not_allowed)
			(vias allowed)
			(pads allowed)
			(copperpour not_allowed)
			(footprints allowed)
		)
		(placement
			(enabled no)
			(sheetname "")
		)
		(fill
			(thermal_gap 0.5)
			(thermal_bridge_width 0.5)
			(island_removal_mode 0)
		)
		(polygon
			(pts
				(xy 20.95881 -248.925334) (xy 22.45741 -248.925334) (xy 22.45741 -249.445272) (xy 20.95881 -249.445272)
			)
		)
	)
	(zone
		(layer "In2.Cu")
		(hatch none 0.5)
		(connect_pads
			(clearance 0)
		)
		(min_thickness 0.25)
		(keepout
			(tracks not_allowed)
			(vias allowed)
			(pads allowed)
			(copperpour not_allowed)
			(footprints allowed)
		)
		(placement
			(enabled no)
			(sheetname "")
		)
		(fill
			(thermal_gap 0.5)
			(thermal_bridge_width 0.5)
			(island_removal_mode 0)
		)
		(polygon
			(pts
				(xy 445.894968 -305.875182) (xy 447.393568 -305.875182) (xy 447.393568 -306.39512) (xy 445.894968 -306.39512)
			)
		)
	)
	(zone
		(layer "In2.Cu")
		(hatch none 0.5)
		(connect_pads
			(clearance 0)
		)
		(min_thickness 0.25)
		(keepout
			(tracks not_allowed)
			(vias allowed)
			(pads allowed)
			(copperpour not_allowed)
			(footprints allowed)
		)
		(placement
			(enabled no)
			(sheetname "")
		)
		(fill
			(thermal_gap 0.5)
			(thermal_bridge_width 0.5)
			(island_removal_mode 0)
		)
		(polygon
			(pts
				(xy 31.946596 -239.57534) (xy 33.445196 -239.57534) (xy 33.445196 -240.095278) (xy 31.946596 -240.095278)
			)
		)
	)
	(zone
		(layer "In2.Cu")
		(hatch none 0.5)
		(connect_pads
			(clearance 0)
		)
		(min_thickness 0.25)
		(keepout
			(tracks not_allowed)
			(vias allowed)
			(pads allowed)
			(copperpour not_allowed)
			(footprints allowed)
		)
		(placement
			(enabled no)
			(sheetname "")
		)
		(fill
			(thermal_gap 0.5)
			(thermal_bridge_width 0.5)
			(island_removal_mode 0)
		)
		(polygon
			(pts
				(xy 291.530786 -299.925232) (xy 293.029386 -299.925232) (xy 293.029386 -300.44517) (xy 291.530786 -300.44517)
			)
		)
	)
	(zone
		(layer "In2.Cu")
		(hatch none 0.5)
		(connect_pads
			(clearance 0)
		)
		(min_thickness 0.25)
		(keepout
			(tracks allowed)
			(vias allowed)
			(pads allowed)
			(copperpour allowed)
			(footprints allowed)
		)
		(placement
			(enabled no)
			(sheetname "")
		)
		(fill
			(thermal_gap 0.5)
			(thermal_bridge_width 0.5)
			(island_removal_mode 0)
		)
		(polygon
			(pts
				(xy 33.28035 -347.689932) (xy 33.28035 -348.441772) (xy 33.09493 -348.441772) (xy 33.09493 -347.689932)
			)
		)
	)
	(zone
		(layer "In2.Cu")
		(hatch none 0.5)
		(connect_pads
			(clearance 0)
		)
		(min_thickness 0.25)
		(keepout
			(tracks not_allowed)
			(vias allowed)
			(pads allowed)
			(copperpour not_allowed)
			(footprints allowed)
		)
		(placement
			(enabled no)
			(sheetname "")
		)
		(fill
			(thermal_gap 0.5)
			(thermal_bridge_width 0.5)
			(island_removal_mode 0)
		)
		(polygon
			(pts
				(xy 302.518826 -244.675152) (xy 304.017426 -244.675152) (xy 304.017426 -245.19509) (xy 302.518826 -245.19509)
			)
		)
	)
	(zone
		(layer "In2.Cu")
		(hatch none 0.5)
		(connect_pads
			(clearance 0)
		)
		(min_thickness 0.25)
		(keepout
			(tracks not_allowed)
			(vias allowed)
			(pads allowed)
			(copperpour not_allowed)
			(footprints allowed)
		)
		(placement
			(enabled no)
			(sheetname "")
		)
		(fill
			(thermal_gap 0.5)
			(thermal_bridge_width 0.5)
			(island_removal_mode 0)
		)
		(polygon
			(pts
				(xy 54.578758 -276.975316) (xy 56.077358 -276.975316) (xy 56.077358 -277.495254) (xy 54.578758 -277.495254)
			)
		)
	)
	(zone
		(layer "In2.Cu")
		(hatch none 0.5)
		(connect_pads
			(clearance 0)
		)
		(min_thickness 0.25)
		(keepout
			(tracks not_allowed)
			(vias allowed)
			(pads allowed)
			(copperpour not_allowed)
			(footprints allowed)
		)
		(placement
			(enabled no)
			(sheetname "")
		)
		(fill
			(thermal_gap 0.5)
			(thermal_bridge_width 0.5)
			(island_removal_mode 0)
		)
		(polygon
			(pts
				(xy 299.07484 -238.725202) (xy 300.57344 -238.725202) (xy 300.57344 -239.24514) (xy 299.07484 -239.24514)
			)
		)
	)
	(zone
		(layer "In2.Cu")
		(hatch none 0.5)
		(connect_pads
			(clearance 0)
		)
		(min_thickness 0.25)
		(keepout
			(tracks not_allowed)
			(vias allowed)
			(pads allowed)
			(copperpour not_allowed)
			(footprints allowed)
		)
		(placement
			(enabled no)
			(sheetname "")
		)
		(fill
			(thermal_gap 0.5)
			(thermal_bridge_width 0.5)
			(island_removal_mode 0)
		)
		(polygon
			(pts
				(xy 193.854578 -213.225126) (xy 195.353178 -213.225126) (xy 195.353178 -213.745064) (xy 193.854578 -213.745064)
			)
		)
	)
	(zone
		(layer "In2.Cu")
		(hatch none 0.5)
		(connect_pads
			(clearance 0)
		)
		(min_thickness 0.25)
		(keepout
			(tracks not_allowed)
			(vias allowed)
			(pads allowed)
			(copperpour not_allowed)
			(footprints allowed)
		)
		(placement
			(enabled no)
			(sheetname "")
		)
		(fill
			(thermal_gap 0.5)
			(thermal_bridge_width 0.5)
			(island_removal_mode 0)
		)
		(polygon
			(pts
				(xy 434.250846 -216.62517) (xy 435.749446 -216.62517) (xy 435.749446 -217.145108) (xy 434.250846 -217.145108)
			)
		)
	)
	(zone
		(layer "In2.Cu")
		(hatch none 0.5)
		(connect_pads
			(clearance 0)
		)
		(min_thickness 0.25)
		(keepout
			(tracks not_allowed)
			(vias allowed)
			(pads allowed)
			(copperpour not_allowed)
			(footprints allowed)
		)
		(placement
			(enabled no)
			(sheetname "")
		)
		(fill
			(thermal_gap 0.5)
			(thermal_bridge_width 0.5)
			(island_removal_mode 0)
		)
		(polygon
			(pts
				(xy 175.322738 -290.575238) (xy 176.821338 -290.575238) (xy 176.821338 -291.095176) (xy 175.322738 -291.095176)
			)
		)
	)
	(zone
		(layer "In2.Cu")
		(hatch none 0.5)
		(connect_pads
			(clearance 0)
		)
		(min_thickness 0.25)
		(keepout
			(tracks not_allowed)
			(vias allowed)
			(pads allowed)
			(copperpour not_allowed)
			(footprints allowed)
		)
		(placement
			(enabled no)
			(sheetname "")
		)
		(fill
			(thermal_gap 0.5)
			(thermal_bridge_width 0.5)
			(island_removal_mode 0)
		)
		(polygon
			(pts
				(xy 193.854578 -201.325226) (xy 195.353178 -201.325226) (xy 195.353178 -201.845164) (xy 193.854578 -201.845164)
			)
		)
	)
	(zone
		(layer "In2.Cu")
		(hatch none 0.5)
		(connect_pads
			(clearance 0)
		)
		(min_thickness 0.25)
		(keepout
			(tracks not_allowed)
			(vias allowed)
			(pads allowed)
			(copperpour not_allowed)
			(footprints allowed)
		)
		(placement
			(enabled no)
			(sheetname "")
		)
		(fill
			(thermal_gap 0.5)
			(thermal_bridge_width 0.5)
			(island_removal_mode 0)
		)
		(polygon
			(pts
				(xy 197.954646 -252.325124) (xy 199.453246 -252.325124) (xy 199.453246 -252.845062) (xy 197.954646 -252.845062)
			)
		)
	)
	(zone
		(layer "In2.Cu")
		(hatch none 0.5)
		(connect_pads
			(clearance 0)
		)
		(min_thickness 0.25)
		(keepout
			(tracks not_allowed)
			(vias allowed)
			(pads allowed)
			(copperpour not_allowed)
			(footprints allowed)
		)
		(placement
			(enabled no)
			(sheetname "")
		)
		(fill
			(thermal_gap 0.5)
			(thermal_bridge_width 0.5)
			(island_removal_mode 0)
		)
		(polygon
			(pts
				(xy 175.322738 -228.525324) (xy 176.821338 -228.525324) (xy 176.821338 -229.045262) (xy 175.322738 -229.045262)
			)
		)
	)
	(zone
		(layer "In2.Cu")
		(hatch none 0.5)
		(connect_pads
			(clearance 0)
		)
		(min_thickness 0.25)
		(keepout
			(tracks not_allowed)
			(vias allowed)
			(pads allowed)
			(copperpour not_allowed)
			(footprints allowed)
		)
		(placement
			(enabled no)
			(sheetname "")
		)
		(fill
			(thermal_gap 0.5)
			(thermal_bridge_width 0.5)
			(island_removal_mode 0)
		)
		(polygon
			(pts
				(xy 449.3387 -308.425342) (xy 450.8373 -308.425342) (xy 450.8373 -308.94528) (xy 449.3387 -308.94528)
			)
		)
	)
	(zone
		(layer "In2.Cu")
		(hatch none 0.5)
		(connect_pads
			(clearance 0)
		)
		(min_thickness 0.25)
		(keepout
			(tracks not_allowed)
			(vias allowed)
			(pads allowed)
			(copperpour not_allowed)
			(footprints allowed)
		)
		(placement
			(enabled no)
			(sheetname "")
		)
		(fill
			(thermal_gap 0.5)
			(thermal_bridge_width 0.5)
			(island_removal_mode 0)
		)
		(polygon
			(pts
				(xy 279.886664 -285.475172) (xy 281.385264 -285.475172) (xy 281.385264 -285.99511) (xy 279.886664 -285.99511)
			)
		)
	)
	(zone
		(layer "In2.Cu")
		(hatch none 0.5)
		(connect_pads
			(clearance 0)
		)
		(min_thickness 0.25)
		(keepout
			(tracks not_allowed)
			(vias allowed)
			(pads allowed)
			(copperpour not_allowed)
			(footprints allowed)
		)
		(placement
			(enabled no)
			(sheetname "")
		)
		(fill
			(thermal_gap 0.5)
			(thermal_bridge_width 0.5)
			(island_removal_mode 0)
		)
		(polygon
			(pts
				(xy 193.854578 -276.125178) (xy 195.353178 -276.125178) (xy 195.353178 -276.645116) (xy 193.854578 -276.645116)
			)
		)
	)
	(zone
		(layer "In2.Cu")
		(hatch none 0.5)
		(connect_pads
			(clearance 0)
		)
		(min_thickness 0.25)
		(keepout
			(tracks not_allowed)
			(vias allowed)
			(pads allowed)
			(copperpour not_allowed)
			(footprints allowed)
		)
		(placement
			(enabled no)
			(sheetname "")
		)
		(fill
			(thermal_gap 0.5)
			(thermal_bridge_width 0.5)
			(island_removal_mode 0)
		)
		(polygon
			(pts
				(arc
					(start 416.251644 -11.91768)
					(mid 416.229326 -11.971562)
					(end 416.175444 -11.99388)
				)
				(arc
					(start 415.13887 -11.99388)
					(mid 415.084988 -11.971562)
					(end 415.06267 -11.91768)
				)
				(arc
					(start 415.06267 -10.51814)
					(mid 415.084988 -10.464258)
					(end 415.13887 -10.44194)
				)
				(arc
					(start 416.175444 -10.44194)
					(mid 416.229326 -10.464258)
					(end 416.251644 -10.51814)
				)
			)
		)
	)
	(zone
		(layer "In2.Cu")
		(hatch none 0.5)
		(connect_pads
			(clearance 0)
		)
		(min_thickness 0.25)
		(keepout
			(tracks not_allowed)
			(vias allowed)
			(pads allowed)
			(copperpour not_allowed)
			(footprints allowed)
		)
		(placement
			(enabled no)
			(sheetname "")
		)
		(fill
			(thermal_gap 0.5)
			(thermal_bridge_width 0.5)
			(island_removal_mode 0)
		)
		(polygon
			(pts
				(xy 306.618894 -209.825336) (xy 308.117494 -209.825336) (xy 308.117494 -210.345274) (xy 306.618894 -210.345274)
			)
		)
	)
	(zone
		(layer "In2.Cu")
		(hatch none 0.5)
		(connect_pads
			(clearance 0)
		)
		(min_thickness 0.25)
		(keepout
			(tracks not_allowed)
			(vias allowed)
			(pads allowed)
			(copperpour not_allowed)
			(footprints allowed)
		)
		(placement
			(enabled no)
			(sheetname "")
		)
		(fill
			(thermal_gap 0.5)
			(thermal_bridge_width 0.5)
			(island_removal_mode 0)
		)
		(polygon
			(pts
				(xy 438.350914 -238.725202) (xy 439.849514 -238.725202) (xy 439.849514 -239.24514) (xy 438.350914 -239.24514)
			)
		)
	)
	(zone
		(layer "In2.Cu")
		(hatch none 0.5)
		(connect_pads
			(clearance 0)
		)
		(min_thickness 0.25)
		(keepout
			(tracks not_allowed)
			(vias allowed)
			(pads allowed)
			(copperpour not_allowed)
			(footprints allowed)
		)
		(placement
			(enabled no)
			(sheetname "")
		)
		(fill
			(thermal_gap 0.5)
			(thermal_bridge_width 0.5)
			(island_removal_mode 0)
		)
		(polygon
			(pts
				(xy 20.95881 -267.625322) (xy 22.45741 -267.625322) (xy 22.45741 -268.14526) (xy 20.95881 -268.14526)
			)
		)
	)
	(zone
		(layer "In2.Cu")
		(hatch none 0.5)
		(connect_pads
			(clearance 0)
		)
		(min_thickness 0.25)
		(keepout
			(tracks not_allowed)
			(vias allowed)
			(pads allowed)
			(copperpour not_allowed)
			(footprints allowed)
		)
		(placement
			(enabled no)
			(sheetname "")
		)
		(fill
			(thermal_gap 0.5)
			(thermal_bridge_width 0.5)
			(island_removal_mode 0)
		)
		(polygon
			(pts
				(xy 453.438768 -250.625102) (xy 454.937368 -250.625102) (xy 454.937368 -251.14504) (xy 453.438768 -251.14504)
			)
		)
	)
	(zone
		(layer "In2.Cu")
		(hatch none 0.5)
		(connect_pads
			(clearance 0)
		)
		(min_thickness 0.25)
		(keepout
			(tracks not_allowed)
			(vias allowed)
			(pads allowed)
			(copperpour not_allowed)
			(footprints allowed)
		)
		(placement
			(enabled no)
			(sheetname "")
		)
		(fill
			(thermal_gap 0.5)
			(thermal_bridge_width 0.5)
			(island_removal_mode 0)
		)
		(polygon
			(pts
				(xy 426.706792 -289.725354) (xy 428.205392 -289.725354) (xy 428.205392 -290.245292) (xy 426.706792 -290.245292)
			)
		)
	)
	(zone
		(layer "In2.Cu")
		(hatch none 0.5)
		(connect_pads
			(clearance 0)
		)
		(min_thickness 0.25)
		(keepout
			(tracks not_allowed)
			(vias allowed)
			(pads allowed)
			(copperpour not_allowed)
			(footprints allowed)
		)
		(placement
			(enabled no)
			(sheetname "")
		)
		(fill
			(thermal_gap 0.5)
			(thermal_bridge_width 0.5)
			(island_removal_mode 0)
		)
		(polygon
			(pts
				(xy 294.974772 -311.825132) (xy 296.473372 -311.825132) (xy 296.473372 -312.34507) (xy 294.974772 -312.34507)
			)
		)
	)
	(zone
		(layer "In2.Cu")
		(hatch none 0.5)
		(connect_pads
			(clearance 0)
		)
		(min_thickness 0.25)
		(keepout
			(tracks not_allowed)
			(vias allowed)
			(pads allowed)
			(copperpour not_allowed)
			(footprints allowed)
		)
		(placement
			(enabled no)
			(sheetname "")
		)
		(fill
			(thermal_gap 0.5)
			(thermal_bridge_width 0.5)
			(island_removal_mode 0)
		)
		(polygon
			(pts
				(xy 449.3387 -249.775218) (xy 450.8373 -249.775218) (xy 450.8373 -250.295156) (xy 449.3387 -250.295156)
			)
		)
	)
	(zone
		(layer "In2.Cu")
		(hatch none 0.5)
		(connect_pads
			(clearance 0)
		)
		(min_thickness 0.25)
		(keepout
			(tracks not_allowed)
			(vias allowed)
			(pads allowed)
			(copperpour not_allowed)
			(footprints allowed)
		)
		(placement
			(enabled no)
			(sheetname "")
		)
		(fill
			(thermal_gap 0.5)
			(thermal_bridge_width 0.5)
			(island_removal_mode 0)
		)
		(polygon
			(pts
				(xy 453.438768 -269.325344) (xy 454.937368 -269.325344) (xy 454.937368 -269.845282) (xy 453.438768 -269.845282)
			)
		)
	)
	(zone
		(layer "In2.Cu")
		(hatch none 0.5)
		(connect_pads
			(clearance 0)
		)
		(min_thickness 0.25)
		(keepout
			(tracks not_allowed)
			(vias allowed)
			(pads allowed)
			(copperpour not_allowed)
			(footprints allowed)
		)
		(placement
			(enabled no)
			(sheetname "")
		)
		(fill
			(thermal_gap 0.5)
			(thermal_bridge_width 0.5)
			(island_removal_mode 0)
		)
		(polygon
			(pts
				(xy 190.410846 -243.825268) (xy 191.909446 -243.825268) (xy 191.909446 -244.345206) (xy 190.410846 -244.345206)
			)
		)
	)
	(zone
		(layer "In2.Cu")
		(hatch none 0.5)
		(connect_pads
			(clearance 0)
		)
		(min_thickness 0.25)
		(keepout
			(tracks not_allowed)
			(vias allowed)
			(pads allowed)
			(copperpour not_allowed)
			(footprints allowed)
		)
		(placement
			(enabled no)
			(sheetname "")
		)
		(fill
			(thermal_gap 0.5)
			(thermal_bridge_width 0.5)
			(island_removal_mode 0)
		)
		(polygon
			(pts
				(xy 31.946596 -230.225346) (xy 33.445196 -230.225346) (xy 33.445196 -230.745284) (xy 31.946596 -230.745284)
			)
		)
	)
	(zone
		(layer "In2.Cu")
		(hatch none 0.5)
		(connect_pads
			(clearance 0)
		)
		(min_thickness 0.25)
		(keepout
			(tracks not_allowed)
			(vias allowed)
			(pads allowed)
			(copperpour not_allowed)
			(footprints allowed)
		)
		(placement
			(enabled no)
			(sheetname "")
		)
		(fill
			(thermal_gap 0.5)
			(thermal_bridge_width 0.5)
			(island_removal_mode 0)
		)
		(polygon
			(pts
				(xy 31.946596 -268.475206) (xy 33.445196 -268.475206) (xy 33.445196 -268.995144) (xy 31.946596 -268.995144)
			)
		)
	)
	(zone
		(layer "In2.Cu")
		(hatch none 0.5)
		(connect_pads
			(clearance 0)
		)
		(min_thickness 0.25)
		(keepout
			(tracks not_allowed)
			(vias allowed)
			(pads allowed)
			(copperpour not_allowed)
			(footprints allowed)
		)
		(placement
			(enabled no)
			(sheetname "")
		)
		(fill
			(thermal_gap 0.5)
			(thermal_bridge_width 0.5)
			(island_removal_mode 0)
		)
		(polygon
			(pts
				(xy 197.954646 -204.72527) (xy 199.453246 -204.72527) (xy 199.453246 -205.245208) (xy 197.954646 -205.245208)
			)
		)
	)
	(zone
		(layer "In2.Cu")
		(hatch none 0.5)
		(connect_pads
			(clearance 0)
		)
		(min_thickness 0.25)
		(keepout
			(tracks not_allowed)
			(vias allowed)
			(pads allowed)
			(copperpour not_allowed)
			(footprints allowed)
		)
		(placement
			(enabled no)
			(sheetname "")
		)
		(fill
			(thermal_gap 0.5)
			(thermal_bridge_width 0.5)
			(island_removal_mode 0)
		)
		(polygon
			(pts
				(xy 51.134772 -296.525188) (xy 52.633372 -296.525188) (xy 52.633372 -297.045126) (xy 51.134772 -297.045126)
			)
		)
	)
	(zone
		(layer "In2.Cu")
		(hatch none 0.5)
		(connect_pads
			(clearance 0)
		)
		(min_thickness 0.25)
		(keepout
			(tracks not_allowed)
			(vias allowed)
			(pads allowed)
			(copperpour not_allowed)
			(footprints allowed)
		)
		(placement
			(enabled no)
			(sheetname "")
		)
		(fill
			(thermal_gap 0.5)
			(thermal_bridge_width 0.5)
			(island_removal_mode 0)
		)
		(polygon
			(pts
				(xy 54.578758 -244.675152) (xy 56.077358 -244.675152) (xy 56.077358 -245.19509) (xy 54.578758 -245.19509)
			)
		)
	)
	(zone
		(layer "In2.Cu")
		(hatch none 0.5)
		(connect_pads
			(clearance 0)
		)
		(min_thickness 0.25)
		(keepout
			(tracks not_allowed)
			(vias allowed)
			(pads allowed)
			(copperpour not_allowed)
			(footprints allowed)
		)
		(placement
			(enabled no)
			(sheetname "")
		)
		(fill
			(thermal_gap 0.5)
			(thermal_bridge_width 0.5)
			(island_removal_mode 0)
		)
		(polygon
			(pts
				(xy 411.618684 -199.625204) (xy 413.117284 -199.625204) (xy 413.117284 -200.145142) (xy 411.618684 -200.145142)
			)
		)
	)
	(zone
		(layer "In2.Cu")
		(hatch none 0.5)
		(connect_pads
			(clearance 0)
		)
		(min_thickness 0.25)
		(keepout
			(tracks not_allowed)
			(vias allowed)
			(pads allowed)
			(copperpour not_allowed)
			(footprints allowed)
		)
		(placement
			(enabled no)
			(sheetname "")
		)
		(fill
			(thermal_gap 0.5)
			(thermal_bridge_width 0.5)
			(island_removal_mode 0)
		)
		(polygon
			(pts
				(xy 294.974772 -241.275108) (xy 296.473372 -241.275108) (xy 296.473372 -241.795046) (xy 294.974772 -241.795046)
			)
		)
	)
	(zone
		(layer "In2.Cu")
		(hatch none 0.5)
		(connect_pads
			(clearance 0)
		)
		(min_thickness 0.25)
		(keepout
			(tracks not_allowed)
			(vias allowed)
			(pads allowed)
			(copperpour not_allowed)
			(footprints allowed)
		)
		(placement
			(enabled no)
			(sheetname "")
		)
		(fill
			(thermal_gap 0.5)
			(thermal_bridge_width 0.5)
			(island_removal_mode 0)
		)
		(polygon
			(pts
				(xy 16.858742 -222.57512) (xy 18.357342 -222.57512) (xy 18.357342 -223.095058) (xy 16.858742 -223.095058)
			)
		)
	)
	(zone
		(layer "In2.Cu")
		(hatch none 0.5)
		(connect_pads
			(clearance 0)
		)
		(min_thickness 0.25)
		(keepout
			(tracks not_allowed)
			(vias allowed)
			(pads allowed)
			(copperpour not_allowed)
			(footprints allowed)
		)
		(placement
			(enabled no)
			(sheetname "")
		)
		(fill
			(thermal_gap 0.5)
			(thermal_bridge_width 0.5)
			(island_removal_mode 0)
		)
		(polygon
			(pts
				(xy 139.15517 -15.82674) (xy 140.136118 -15.82674) (xy 140.136118 -17.27454) (xy 139.15517 -17.27454)
			)
		)
	)
	(zone
		(layer "In2.Cu")
		(hatch none 0.5)
		(connect_pads
			(clearance 0)
		)
		(min_thickness 0.25)
		(keepout
			(tracks not_allowed)
			(vias allowed)
			(pads allowed)
			(copperpour not_allowed)
			(footprints allowed)
		)
		(placement
			(enabled no)
			(sheetname "")
		)
		(fill
			(thermal_gap 0.5)
			(thermal_bridge_width 0.5)
			(island_removal_mode 0)
		)
		(polygon
			(pts
				(xy 426.706792 -280.375106) (xy 428.205392 -280.375106) (xy 428.205392 -280.895044) (xy 426.706792 -280.895044)
			)
		)
	)
	(zone
		(layer "In2.Cu")
		(hatch none 0.5)
		(connect_pads
			(clearance 0)
		)
		(min_thickness 0.25)
		(keepout
			(tracks not_allowed)
			(vias allowed)
			(pads allowed)
			(copperpour not_allowed)
			(footprints allowed)
		)
		(placement
			(enabled no)
			(sheetname "")
		)
		(fill
			(thermal_gap 0.5)
			(thermal_bridge_width 0.5)
			(island_removal_mode 0)
		)
		(polygon
			(pts
				(xy 306.618894 -273.575272) (xy 308.117494 -273.575272) (xy 308.117494 -274.09521) (xy 306.618894 -274.09521)
			)
		)
	)
	(zone
		(layer "In2.Cu")
		(hatch none 0.5)
		(connect_pads
			(clearance 0)
		)
		(min_thickness 0.25)
		(keepout
			(tracks not_allowed)
			(vias allowed)
			(pads allowed)
			(copperpour not_allowed)
			(footprints allowed)
		)
		(placement
			(enabled no)
			(sheetname "")
		)
		(fill
			(thermal_gap 0.5)
			(thermal_bridge_width 0.5)
			(island_removal_mode 0)
		)
		(polygon
			(pts
				(xy 24.402542 -211.525104) (xy 25.901142 -211.525104) (xy 25.901142 -212.045042) (xy 24.402542 -212.045042)
			)
		)
	)
	(zone
		(layer "In2.Cu")
		(hatch none 0.5)
		(connect_pads
			(clearance 0)
		)
		(min_thickness 0.25)
		(keepout
			(tracks not_allowed)
			(vias allowed)
			(pads allowed)
			(copperpour not_allowed)
			(footprints allowed)
		)
		(placement
			(enabled no)
			(sheetname "")
		)
		(fill
			(thermal_gap 0.5)
			(thermal_bridge_width 0.5)
			(island_removal_mode 0)
		)
		(polygon
			(pts
				(xy 276.442932 -237.875318) (xy 277.941532 -237.875318) (xy 277.941532 -238.395256) (xy 276.442932 -238.395256)
			)
		)
	)
	(zone
		(layer "In2.Cu")
		(hatch none 0.5)
		(connect_pads
			(clearance 0)
		)
		(min_thickness 0.25)
		(keepout
			(tracks not_allowed)
			(vias allowed)
			(pads allowed)
			(copperpour not_allowed)
			(footprints allowed)
		)
		(placement
			(enabled no)
			(sheetname "")
		)
		(fill
			(thermal_gap 0.5)
			(thermal_bridge_width 0.5)
			(island_removal_mode 0)
		)
		(polygon
			(pts
				(xy 306.618894 -197.075298) (xy 308.117494 -197.075298) (xy 308.117494 -197.595236) (xy 306.618894 -197.595236)
			)
		)
	)
	(zone
		(layer "In2.Cu")
		(hatch none 0.5)
		(connect_pads
			(clearance 0)
		)
		(min_thickness 0.25)
		(keepout
			(tracks not_allowed)
			(vias allowed)
			(pads allowed)
			(copperpour not_allowed)
			(footprints allowed)
		)
		(placement
			(enabled no)
			(sheetname "")
		)
		(fill
			(thermal_gap 0.5)
			(thermal_bridge_width 0.5)
			(island_removal_mode 0)
		)
		(polygon
			(pts
				(xy 302.518826 -197.925182) (xy 304.017426 -197.925182) (xy 304.017426 -198.44512) (xy 302.518826 -198.44512)
			)
		)
	)
	(zone
		(layer "In2.Cu")
		(hatch none 0.5)
		(connect_pads
			(clearance 0)
		)
		(min_thickness 0.25)
		(keepout
			(tracks not_allowed)
			(vias allowed)
			(pads allowed)
			(copperpour not_allowed)
			(footprints allowed)
		)
		(placement
			(enabled no)
			(sheetname "")
		)
		(fill
			(thermal_gap 0.5)
			(thermal_bridge_width 0.5)
			(island_removal_mode 0)
		)
		(polygon
			(pts
				(xy 449.3387 -263.37514) (xy 450.8373 -263.37514) (xy 450.8373 -263.895078) (xy 449.3387 -263.895078)
			)
		)
	)
	(zone
		(layer "In2.Cu")
		(hatch none 0.5)
		(connect_pads
			(clearance 0)
		)
		(min_thickness 0.25)
		(keepout
			(tracks allowed)
			(vias allowed)
			(pads allowed)
			(copperpour allowed)
			(footprints allowed)
		)
		(placement
			(enabled no)
			(sheetname "")
		)
		(fill
			(thermal_gap 0.5)
			(thermal_bridge_width 0.5)
			(island_removal_mode 0)
		)
		(polygon
			(pts
				(xy 186.352434 -353.696778) (xy 186.352434 -353.074478) (xy 186.903614 -353.074478) (xy 186.903614 -353.696778)
			)
		)
	)
	(zone
		(layer "In2.Cu")
		(hatch none 0.5)
		(connect_pads
			(clearance 0)
		)
		(min_thickness 0.25)
		(keepout
			(tracks not_allowed)
			(vias allowed)
			(pads allowed)
			(copperpour not_allowed)
			(footprints allowed)
		)
		(placement
			(enabled no)
			(sheetname "")
		)
		(fill
			(thermal_gap 0.5)
			(thermal_bridge_width 0.5)
			(island_removal_mode 0)
		)
		(polygon
			(pts
				(xy 201.398632 -205.575154) (xy 202.897232 -205.575154) (xy 202.897232 -206.095092) (xy 201.398632 -206.095092)
			)
		)
	)
	(zone
		(layer "In2.Cu")
		(hatch none 0.5)
		(connect_pads
			(clearance 0)
		)
		(min_thickness 0.25)
		(keepout
			(tracks not_allowed)
			(vias allowed)
			(pads allowed)
			(copperpour not_allowed)
			(footprints allowed)
		)
		(placement
			(enabled no)
			(sheetname "")
		)
		(fill
			(thermal_gap 0.5)
			(thermal_bridge_width 0.5)
			(island_removal_mode 0)
		)
		(polygon
			(pts
				(xy 193.854578 -208.975198) (xy 195.353178 -208.975198) (xy 195.353178 -209.495136) (xy 193.854578 -209.495136)
			)
		)
	)
	(zone
		(layer "In2.Cu")
		(hatch none 0.5)
		(connect_pads
			(clearance 0)
		)
		(min_thickness 0.25)
		(keepout
			(tracks not_allowed)
			(vias allowed)
			(pads allowed)
			(copperpour not_allowed)
			(footprints allowed)
		)
		(placement
			(enabled no)
			(sheetname "")
		)
		(fill
			(thermal_gap 0.5)
			(thermal_bridge_width 0.5)
			(island_removal_mode 0)
		)
		(polygon
			(pts
				(xy 58.678826 -225.12528) (xy 60.177426 -225.12528) (xy 60.177426 -225.645218) (xy 58.678826 -225.645218)
			)
		)
	)
	(zone
		(layer "In2.Cu")
		(hatch none 0.5)
		(connect_pads
			(clearance 0)
		)
		(min_thickness 0.25)
		(keepout
			(tracks not_allowed)
			(vias allowed)
			(pads allowed)
			(copperpour not_allowed)
			(footprints allowed)
		)
		(placement
			(enabled no)
			(sheetname "")
		)
		(fill
			(thermal_gap 0.5)
			(thermal_bridge_width 0.5)
			(island_removal_mode 0)
		)
		(polygon
			(pts
				(xy 175.322738 -252.325124) (xy 176.821338 -252.325124) (xy 176.821338 -252.845062) (xy 175.322738 -252.845062)
			)
		)
	)
	(zone
		(layer "In2.Cu")
		(hatch none 0.5)
		(connect_pads
			(clearance 0)
		)
		(min_thickness 0.25)
		(keepout
			(tracks not_allowed)
			(vias allowed)
			(pads allowed)
			(copperpour not_allowed)
			(footprints allowed)
		)
		(placement
			(enabled no)
			(sheetname "")
		)
		(fill
			(thermal_gap 0.5)
			(thermal_bridge_width 0.5)
			(island_removal_mode 0)
		)
		(polygon
			(pts
				(xy 287.430718 -205.575154) (xy 288.929318 -205.575154) (xy 288.929318 -206.095092) (xy 287.430718 -206.095092)
			)
		)
	)
	(zone
		(layer "In2.Cu")
		(hatch none 0.5)
		(connect_pads
			(clearance 0)
		)
		(min_thickness 0.25)
		(keepout
			(tracks not_allowed)
			(vias allowed)
			(pads allowed)
			(copperpour not_allowed)
			(footprints allowed)
		)
		(placement
			(enabled no)
			(sheetname "")
		)
		(fill
			(thermal_gap 0.5)
			(thermal_bridge_width 0.5)
			(island_removal_mode 0)
		)
		(polygon
			(pts
				(xy 423.262806 -254.025146) (xy 424.761406 -254.025146) (xy 424.761406 -254.545084) (xy 423.262806 -254.545084)
			)
		)
	)
	(zone
		(layer "In2.Cu")
		(hatch none 0.5)
		(connect_pads
			(clearance 0)
		)
		(min_thickness 0.25)
		(keepout
			(tracks not_allowed)
			(vias allowed)
			(pads allowed)
			(copperpour not_allowed)
			(footprints allowed)
		)
		(placement
			(enabled no)
			(sheetname "")
		)
		(fill
			(thermal_gap 0.5)
			(thermal_bridge_width 0.5)
			(island_removal_mode 0)
		)
		(polygon
			(pts
				(xy 51.134772 -282.925266) (xy 52.633372 -282.925266) (xy 52.633372 -283.445204) (xy 51.134772 -283.445204)
			)
		)
	)
	(zone
		(layer "In2.Cu")
		(hatch none 0.5)
		(connect_pads
			(clearance 0)
		)
		(min_thickness 0.25)
		(keepout
			(tracks not_allowed)
			(vias allowed)
			(pads allowed)
			(copperpour not_allowed)
			(footprints allowed)
		)
		(placement
			(enabled no)
			(sheetname "")
		)
		(fill
			(thermal_gap 0.5)
			(thermal_bridge_width 0.5)
			(island_removal_mode 0)
		)
		(polygon
			(pts
				(xy 434.250846 -229.375208) (xy 435.749446 -229.375208) (xy 435.749446 -229.895146) (xy 434.250846 -229.895146)
			)
		)
	)
	(zone
		(layer "In2.Cu")
		(hatch none 0.5)
		(connect_pads
			(clearance 0)
		)
		(min_thickness 0.25)
		(keepout
			(tracks not_allowed)
			(vias allowed)
			(pads allowed)
			(copperpour not_allowed)
			(footprints allowed)
		)
		(placement
			(enabled no)
			(sheetname "")
		)
		(fill
			(thermal_gap 0.5)
			(thermal_bridge_width 0.5)
			(island_removal_mode 0)
		)
		(polygon
			(pts
				(xy 123.74626 -36.925504)
				(arc
					(start 123.886468 -36.925504)
					(mid 123.95635 -36.896295)
					(end 123.98502 -36.82619)
				)
				(arc
					(start 123.98502 -36.524946)
					(mid 123.95635 -36.454841)
					(end 123.886468 -36.425632)
				)
				(xy 123.74626 -36.425632) (xy 123.74626 -36.485576)
				(arc
					(start 123.177046 -36.485576)
					(mid 123.140677 -36.442077)
					(end 123.086368 -36.425632)
				)
				(arc
					(start 122.826272 -36.425632)
					(mid 122.77188 -36.441951)
					(end 122.735594 -36.485576)
				)
				(xy 122.16638 -36.485576) (xy 122.16638 -36.425632)
				(arc
					(start 122.026172 -36.425632)
					(mid 121.95629 -36.454841)
					(end 121.92762 -36.524946)
				)
				(arc
					(start 121.92762 -36.82619)
					(mid 121.95629 -36.896295)
					(end 122.026172 -36.925504)
				)
				(xy 122.16638 -36.925504) (xy 122.16638 -36.86556)
				(arc
					(start 122.735594 -36.86556)
					(mid 122.771963 -36.909059)
					(end 122.826272 -36.925504)
				)
				(arc
					(start 123.086368 -36.925504)
					(mid 123.14076 -36.909185)
					(end 123.177046 -36.86556)
				)
				(xy 123.74626 -36.86556)
			)
		)
	)
	(zone
		(layer "In2.Cu")
		(hatch none 0.5)
		(connect_pads
			(clearance 0)
		)
		(min_thickness 0.25)
		(keepout
			(tracks not_allowed)
			(vias allowed)
			(pads allowed)
			(copperpour not_allowed)
			(footprints allowed)
		)
		(placement
			(enabled no)
			(sheetname "")
		)
		(fill
			(thermal_gap 0.5)
			(thermal_bridge_width 0.5)
			(island_removal_mode 0)
		)
		(polygon
			(pts
				(xy 167.778684 -197.075298) (xy 169.277284 -197.075298) (xy 169.277284 -197.595236) (xy 167.778684 -197.595236)
			)
		)
	)
	(zone
		(layer "In2.Cu")
		(hatch none 0.5)
		(connect_pads
			(clearance 0)
		)
		(min_thickness 0.25)
		(keepout
			(tracks not_allowed)
			(vias allowed)
			(pads allowed)
			(copperpour not_allowed)
			(footprints allowed)
		)
		(placement
			(enabled no)
			(sheetname "")
		)
		(fill
			(thermal_gap 0.5)
			(thermal_bridge_width 0.5)
			(island_removal_mode 0)
		)
		(polygon
			(pts
				(xy 294.974772 -263.37514) (xy 296.473372 -263.37514) (xy 296.473372 -263.895078) (xy 294.974772 -263.895078)
			)
		)
	)
	(zone
		(layer "In2.Cu")
		(hatch none 0.5)
		(connect_pads
			(clearance 0)
		)
		(min_thickness 0.25)
		(keepout
			(tracks not_allowed)
			(vias allowed)
			(pads allowed)
			(copperpour not_allowed)
			(footprints allowed)
		)
		(placement
			(enabled no)
			(sheetname "")
		)
		(fill
			(thermal_gap 0.5)
			(thermal_bridge_width 0.5)
			(island_removal_mode 0)
		)
		(polygon
			(pts
				(xy 190.410846 -238.725202) (xy 191.909446 -238.725202) (xy 191.909446 -239.24514) (xy 190.410846 -239.24514)
			)
		)
	)
	(zone
		(layer "In2.Cu")
		(hatch none 0.5)
		(connect_pads
			(clearance 0)
		)
		(min_thickness 0.25)
		(keepout
			(tracks not_allowed)
			(vias allowed)
			(pads allowed)
			(copperpour not_allowed)
			(footprints allowed)
		)
		(placement
			(enabled no)
			(sheetname "")
		)
		(fill
			(thermal_gap 0.5)
			(thermal_bridge_width 0.5)
			(island_removal_mode 0)
		)
		(polygon
			(pts
				(xy 24.402542 -285.475172) (xy 25.901142 -285.475172) (xy 25.901142 -285.99511) (xy 24.402542 -285.99511)
			)
		)
	)
	(zone
		(layer "In2.Cu")
		(hatch none 0.5)
		(connect_pads
			(clearance 0)
		)
		(min_thickness 0.25)
		(keepout
			(tracks not_allowed)
			(vias allowed)
			(pads allowed)
			(copperpour not_allowed)
			(footprints allowed)
		)
		(placement
			(enabled no)
			(sheetname "")
		)
		(fill
			(thermal_gap 0.5)
			(thermal_bridge_width 0.5)
			(island_removal_mode 0)
		)
		(polygon
			(pts
				(xy 58.678826 -240.425224) (xy 60.177426 -240.425224) (xy 60.177426 -240.945162) (xy 58.678826 -240.945162)
			)
		)
	)
	(zone
		(layer "In2.Cu")
		(hatch none 0.5)
		(connect_pads
			(clearance 0)
		)
		(min_thickness 0.25)
		(keepout
			(tracks not_allowed)
			(vias allowed)
			(pads allowed)
			(copperpour not_allowed)
			(footprints allowed)
		)
		(placement
			(enabled no)
			(sheetname "")
		)
		(fill
			(thermal_gap 0.5)
			(thermal_bridge_width 0.5)
			(island_removal_mode 0)
		)
		(polygon
			(pts
				(xy 20.95881 -304.17516) (xy 22.45741 -304.17516) (xy 22.45741 -304.695098) (xy 20.95881 -304.695098)
			)
		)
	)
	(zone
		(layer "In2.Cu")
		(hatch none 0.5)
		(connect_pads
			(clearance 0)
		)
		(min_thickness 0.25)
		(keepout
			(tracks not_allowed)
			(vias allowed)
			(pads allowed)
			(copperpour not_allowed)
			(footprints allowed)
		)
		(placement
			(enabled no)
			(sheetname "")
		)
		(fill
			(thermal_gap 0.5)
			(thermal_bridge_width 0.5)
			(island_removal_mode 0)
		)
		(polygon
			(pts
				(xy 58.678826 -316.925198) (xy 60.177426 -316.925198) (xy 60.177426 -317.445136) (xy 58.678826 -317.445136)
			)
		)
	)
	(zone
		(layer "In2.Cu")
		(hatch none 0.5)
		(connect_pads
			(clearance 0)
		)
		(min_thickness 0.25)
		(keepout
			(tracks not_allowed)
			(vias allowed)
			(pads allowed)
			(copperpour not_allowed)
			(footprints allowed)
		)
		(placement
			(enabled no)
			(sheetname "")
		)
		(fill
			(thermal_gap 0.5)
			(thermal_bridge_width 0.5)
			(island_removal_mode 0)
		)
		(polygon
			(pts
				(xy 306.618894 -270.175228) (xy 308.117494 -270.175228) (xy 308.117494 -270.695166) (xy 306.618894 -270.695166)
			)
		)
	)
	(zone
		(layer "In2.Cu")
		(hatch none 0.5)
		(connect_pads
			(clearance 0)
		)
		(min_thickness 0.25)
		(keepout
			(tracks not_allowed)
			(vias allowed)
			(pads allowed)
			(copperpour not_allowed)
			(footprints allowed)
		)
		(placement
			(enabled no)
			(sheetname "")
		)
		(fill
			(thermal_gap 0.5)
			(thermal_bridge_width 0.5)
			(island_removal_mode 0)
		)
		(polygon
			(pts
				(xy 24.402542 -254.025146) (xy 25.901142 -254.025146) (xy 25.901142 -254.545084) (xy 24.402542 -254.545084)
			)
		)
	)
	(zone
		(layer "In2.Cu")
		(hatch none 0.5)
		(connect_pads
			(clearance 0)
		)
		(min_thickness 0.25)
		(keepout
			(tracks not_allowed)
			(vias allowed)
			(pads allowed)
			(copperpour not_allowed)
			(footprints allowed)
		)
		(placement
			(enabled no)
			(sheetname "")
		)
		(fill
			(thermal_gap 0.5)
			(thermal_bridge_width 0.5)
			(island_removal_mode 0)
		)
		(polygon
			(pts
				(xy 426.706792 -308.425342) (xy 428.205392 -308.425342) (xy 428.205392 -308.94528) (xy 426.706792 -308.94528)
			)
		)
	)
	(zone
		(layer "In2.Cu")
		(hatch none 0.5)
		(connect_pads
			(clearance 0)
		)
		(min_thickness 0.25)
		(keepout
			(tracks not_allowed)
			(vias allowed)
			(pads allowed)
			(copperpour not_allowed)
			(footprints allowed)
		)
		(placement
			(enabled no)
			(sheetname "")
		)
		(fill
			(thermal_gap 0.5)
			(thermal_bridge_width 0.5)
			(island_removal_mode 0)
		)
		(polygon
			(pts
				(xy 24.402542 -297.375326) (xy 25.901142 -297.375326) (xy 25.901142 -297.895264) (xy 24.402542 -297.895264)
			)
		)
	)
	(zone
		(layer "In2.Cu")
		(hatch none 0.5)
		(connect_pads
			(clearance 0)
		)
		(min_thickness 0.25)
		(keepout
			(tracks not_allowed)
			(vias allowed)
			(pads allowed)
			(copperpour not_allowed)
			(footprints allowed)
		)
		(placement
			(enabled no)
			(sheetname "")
		)
		(fill
			(thermal_gap 0.5)
			(thermal_bridge_width 0.5)
			(island_removal_mode 0)
		)
		(polygon
			(pts
				(xy 419.162738 -220.025214) (xy 420.661338 -220.025214) (xy 420.661338 -220.545152) (xy 419.162738 -220.545152)
			)
		)
	)
	(zone
		(layer "In2.Cu")
		(hatch none 0.5)
		(connect_pads
			(clearance 0)
		)
		(min_thickness 0.25)
		(keepout
			(tracks not_allowed)
			(vias allowed)
			(pads allowed)
			(copperpour not_allowed)
			(footprints allowed)
		)
		(placement
			(enabled no)
			(sheetname "")
		)
		(fill
			(thermal_gap 0.5)
			(thermal_bridge_width 0.5)
			(island_removal_mode 0)
		)
		(polygon
			(pts
				(xy 287.430718 -317.775336) (xy 288.929318 -317.775336) (xy 288.929318 -318.295274) (xy 287.430718 -318.295274)
			)
		)
	)
	(zone
		(layer "In2.Cu")
		(hatch none 0.5)
		(connect_pads
			(clearance 0)
		)
		(min_thickness 0.25)
		(keepout
			(tracks not_allowed)
			(vias allowed)
			(pads allowed)
			(copperpour not_allowed)
			(footprints allowed)
		)
		(placement
			(enabled no)
			(sheetname "")
		)
		(fill
			(thermal_gap 0.5)
			(thermal_bridge_width 0.5)
			(island_removal_mode 0)
		)
		(polygon
			(pts
				(xy 438.350914 -247.225312) (xy 439.849514 -247.225312) (xy 439.849514 -247.74525) (xy 438.350914 -247.74525)
			)
		)
	)
	(zone
		(layer "In2.Cu")
		(hatch none 0.5)
		(connect_pads
			(clearance 0)
		)
		(min_thickness 0.25)
		(keepout
			(tracks not_allowed)
			(vias allowed)
			(pads allowed)
			(copperpour not_allowed)
			(footprints allowed)
		)
		(placement
			(enabled no)
			(sheetname "")
		)
		(fill
			(thermal_gap 0.5)
			(thermal_bridge_width 0.5)
			(island_removal_mode 0)
		)
		(polygon
			(pts
				(xy 54.578758 -246.375174) (xy 56.077358 -246.375174) (xy 56.077358 -246.895112) (xy 54.578758 -246.895112)
			)
		)
	)
	(zone
		(layer "In2.Cu")
		(hatch none 0.5)
		(connect_pads
			(clearance 0)
		)
		(min_thickness 0.25)
		(keepout
			(tracks not_allowed)
			(vias allowed)
			(pads allowed)
			(copperpour not_allowed)
			(footprints allowed)
		)
		(placement
			(enabled no)
			(sheetname "")
		)
		(fill
			(thermal_gap 0.5)
			(thermal_bridge_width 0.5)
			(island_removal_mode 0)
		)
		(polygon
			(pts
				(xy 302.518826 -266.775184) (xy 304.017426 -266.775184) (xy 304.017426 -267.295122) (xy 302.518826 -267.295122)
			)
		)
	)
	(zone
		(layer "In2.Cu")
		(hatch none 0.5)
		(connect_pads
			(clearance 0)
		)
		(min_thickness 0.25)
		(keepout
			(tracks not_allowed)
			(vias allowed)
			(pads allowed)
			(copperpour not_allowed)
			(footprints allowed)
		)
		(placement
			(enabled no)
			(sheetname "")
		)
		(fill
			(thermal_gap 0.5)
			(thermal_bridge_width 0.5)
			(island_removal_mode 0)
		)
		(polygon
			(pts
				(xy 51.134772 -206.425292) (xy 52.633372 -206.425292) (xy 52.633372 -206.94523) (xy 51.134772 -206.94523)
			)
		)
	)
	(zone
		(layer "In2.Cu")
		(hatch none 0.5)
		(connect_pads
			(clearance 0)
		)
		(min_thickness 0.25)
		(keepout
			(tracks not_allowed)
			(vias allowed)
			(pads allowed)
			(copperpour not_allowed)
			(footprints allowed)
		)
		(placement
			(enabled no)
			(sheetname "")
		)
		(fill
			(thermal_gap 0.5)
			(thermal_bridge_width 0.5)
			(island_removal_mode 0)
		)
		(polygon
			(pts
				(arc
					(start 311.695846 -384.288284)
					(mid 311.71577 -384.29752)
					(end 311.737502 -384.30073)
				)
				(arc
					(start 311.932066 -384.30073)
					(mid 311.985948 -384.278412)
					(end 312.008266 -384.22453)
				)
				(arc
					(start 312.008266 -383.53873)
					(mid 311.985948 -383.484848)
					(end 311.932066 -383.46253)
				)
				(arc
					(start 311.737502 -383.46253)
					(mid 311.715758 -383.465698)
					(end 311.695846 -383.474976)
				)
				(arc
					(start 311.399682 -383.667762)
					(mid 311.357998 -383.679984)
					(end 311.31637 -383.667508)
				)
				(arc
					(start 311.022746 -383.474976)
					(mid 311.002822 -383.46574)
					(end 310.98109 -383.46253)
				)
				(arc
					(start 310.786526 -383.46253)
					(mid 310.732644 -383.484848)
					(end 310.710326 -383.53873)
				)
				(arc
					(start 310.710326 -384.22453)
					(mid 310.732644 -384.278412)
					(end 310.786526 -384.30073)
				)
				(arc
					(start 310.98236 -384.30073)
					(mid 311.004104 -384.297562)
					(end 311.024016 -384.288284)
				)
				(arc
					(start 311.31764 -384.095752)
					(mid 311.359296 -384.08335)
					(end 311.400952 -384.095752)
				)
			)
		)
	)
	(zone
		(layer "In2.Cu")
		(hatch none 0.5)
		(connect_pads
			(clearance 0)
		)
		(min_thickness 0.25)
		(keepout
			(tracks not_allowed)
			(vias allowed)
			(pads allowed)
			(copperpour not_allowed)
			(footprints allowed)
		)
		(placement
			(enabled no)
			(sheetname "")
		)
		(fill
			(thermal_gap 0.5)
			(thermal_bridge_width 0.5)
			(island_removal_mode 0)
		)
		(polygon
			(pts
				(xy 294.974772 -205.575154) (xy 296.473372 -205.575154) (xy 296.473372 -206.095092) (xy 294.974772 -206.095092)
			)
		)
	)
	(zone
		(layer "In2.Cu")
		(hatch none 0.5)
		(connect_pads
			(clearance 0)
		)
		(min_thickness 0.25)
		(keepout
			(tracks allowed)
			(vias allowed)
			(pads allowed)
			(copperpour allowed)
			(footprints allowed)
		)
		(placement
			(enabled no)
			(sheetname "")
		)
		(fill
			(thermal_gap 0.5)
			(thermal_bridge_width 0.5)
			(island_removal_mode 0)
		)
		(polygon
			(pts
				(xy 84.72932 -180.14696) (xy 84.72932 -179.600606) (xy 85.28177 -179.600606) (xy 85.28177 -180.14696)
			)
		)
	)
	(zone
		(layer "In2.Cu")
		(hatch none 0.5)
		(connect_pads
			(clearance 0)
		)
		(min_thickness 0.25)
		(keepout
			(tracks not_allowed)
			(vias allowed)
			(pads allowed)
			(copperpour not_allowed)
			(footprints allowed)
		)
		(placement
			(enabled no)
			(sheetname "")
		)
		(fill
			(thermal_gap 0.5)
			(thermal_bridge_width 0.5)
			(island_removal_mode 0)
		)
		(polygon
			(pts
				(xy 51.134772 -285.475172) (xy 52.633372 -285.475172) (xy 52.633372 -285.99511) (xy 51.134772 -285.99511)
			)
		)
	)
	(zone
		(layer "In2.Cu")
		(hatch none 0.5)
		(connect_pads
			(clearance 0)
		)
		(min_thickness 0.25)
		(keepout
			(tracks not_allowed)
			(vias allowed)
			(pads allowed)
			(copperpour not_allowed)
			(footprints allowed)
		)
		(placement
			(enabled no)
			(sheetname "")
		)
		(fill
			(thermal_gap 0.5)
			(thermal_bridge_width 0.5)
			(island_removal_mode 0)
		)
		(polygon
			(pts
				(xy 163.678616 -283.77515) (xy 165.177216 -283.77515) (xy 165.177216 -284.295088) (xy 163.678616 -284.295088)
			)
		)
	)
	(zone
		(layer "In2.Cu")
		(hatch none 0.5)
		(connect_pads
			(clearance 0)
		)
		(min_thickness 0.25)
		(keepout
			(tracks not_allowed)
			(vias allowed)
			(pads allowed)
			(copperpour not_allowed)
			(footprints allowed)
		)
		(placement
			(enabled no)
			(sheetname "")
		)
		(fill
			(thermal_gap 0.5)
			(thermal_bridge_width 0.5)
			(island_removal_mode 0)
		)
		(polygon
			(pts
				(xy 438.350914 -252.325124) (xy 439.849514 -252.325124) (xy 439.849514 -252.845062) (xy 438.350914 -252.845062)
			)
		)
	)
	(zone
		(layer "In2.Cu")
		(hatch none 0.5)
		(connect_pads
			(clearance 0)
		)
		(min_thickness 0.25)
		(keepout
			(tracks not_allowed)
			(vias allowed)
			(pads allowed)
			(copperpour not_allowed)
			(footprints allowed)
		)
		(placement
			(enabled no)
			(sheetname "")
		)
		(fill
			(thermal_gap 0.5)
			(thermal_bridge_width 0.5)
			(island_removal_mode 0)
		)
		(polygon
			(pts
				(xy 197.954646 -223.425258) (xy 199.453246 -223.425258) (xy 199.453246 -223.945196) (xy 197.954646 -223.945196)
			)
		)
	)
	(zone
		(layer "In2.Cu")
		(hatch none 0.5)
		(connect_pads
			(clearance 0)
		)
		(min_thickness 0.25)
		(keepout
			(tracks not_allowed)
			(vias allowed)
			(pads allowed)
			(copperpour not_allowed)
			(footprints allowed)
		)
		(placement
			(enabled no)
			(sheetname "")
		)
		(fill
			(thermal_gap 0.5)
			(thermal_bridge_width 0.5)
			(island_removal_mode 0)
		)
		(polygon
			(pts
				(xy 186.310778 -249.775218) (xy 187.809378 -249.775218) (xy 187.809378 -250.295156) (xy 186.310778 -250.295156)
			)
		)
	)
	(zone
		(layer "In2.Cu")
		(hatch none 0.5)
		(connect_pads
			(clearance 0)
		)
		(min_thickness 0.25)
		(keepout
			(tracks not_allowed)
			(vias allowed)
			(pads allowed)
			(copperpour not_allowed)
			(footprints allowed)
		)
		(placement
			(enabled no)
			(sheetname "")
		)
		(fill
			(thermal_gap 0.5)
			(thermal_bridge_width 0.5)
			(island_removal_mode 0)
		)
		(polygon
			(pts
				(xy 423.262806 -226.825302) (xy 424.761406 -226.825302) (xy 424.761406 -227.34524) (xy 423.262806 -227.34524)
			)
		)
	)
	(zone
		(layer "In2.Cu")
		(hatch none 0.5)
		(connect_pads
			(clearance 0)
		)
		(min_thickness 0.25)
		(keepout
			(tracks not_allowed)
			(vias allowed)
			(pads allowed)
			(copperpour not_allowed)
			(footprints allowed)
		)
		(placement
			(enabled no)
			(sheetname "")
		)
		(fill
			(thermal_gap 0.5)
			(thermal_bridge_width 0.5)
			(island_removal_mode 0)
		)
		(polygon
			(pts
				(xy 445.894968 -288.875216) (xy 447.393568 -288.875216) (xy 447.393568 -289.395154) (xy 445.894968 -289.395154)
			)
		)
	)
	(zone
		(layer "In2.Cu")
		(hatch none 0.5)
		(connect_pads
			(clearance 0)
		)
		(min_thickness 0.25)
		(keepout
			(tracks not_allowed)
			(vias allowed)
			(pads allowed)
			(copperpour not_allowed)
			(footprints allowed)
		)
		(placement
			(enabled no)
			(sheetname "")
		)
		(fill
			(thermal_gap 0.5)
			(thermal_bridge_width 0.5)
			(island_removal_mode 0)
		)
		(polygon
			(pts
				(xy 24.402542 -239.57534) (xy 25.901142 -239.57534) (xy 25.901142 -240.095278) (xy 24.402542 -240.095278)
			)
		)
	)
	(zone
		(layer "In2.Cu")
		(hatch none 0.5)
		(connect_pads
			(clearance 0)
		)
		(min_thickness 0.25)
		(keepout
			(tracks not_allowed)
			(vias allowed)
			(pads allowed)
			(copperpour not_allowed)
			(footprints allowed)
		)
		(placement
			(enabled no)
			(sheetname "")
		)
		(fill
			(thermal_gap 0.5)
			(thermal_bridge_width 0.5)
			(island_removal_mode 0)
		)
		(polygon
			(pts
				(xy 306.618894 -275.275294) (xy 308.117494 -275.275294) (xy 308.117494 -275.795232) (xy 306.618894 -275.795232)
			)
		)
	)
	(zone
		(layer "In2.Cu")
		(hatch none 0.5)
		(connect_pads
			(clearance 0)
		)
		(min_thickness 0.25)
		(keepout
			(tracks not_allowed)
			(vias allowed)
			(pads allowed)
			(copperpour not_allowed)
			(footprints allowed)
		)
		(placement
			(enabled no)
			(sheetname "")
		)
		(fill
			(thermal_gap 0.5)
			(thermal_bridge_width 0.5)
			(island_removal_mode 0)
		)
		(polygon
			(pts
				(xy 201.398632 -286.32531) (xy 202.897232 -286.32531) (xy 202.897232 -286.845248) (xy 201.398632 -286.845248)
			)
		)
	)
	(zone
		(layer "In2.Cu")
		(hatch none 0.5)
		(connect_pads
			(clearance 0)
		)
		(min_thickness 0.25)
		(keepout
			(tracks not_allowed)
			(vias allowed)
			(pads allowed)
			(copperpour not_allowed)
			(footprints allowed)
		)
		(placement
			(enabled no)
			(sheetname "")
		)
		(fill
			(thermal_gap 0.5)
			(thermal_bridge_width 0.5)
			(island_removal_mode 0)
		)
		(polygon
			(pts
				(xy 276.442932 -254.025146) (xy 277.941532 -254.025146) (xy 277.941532 -254.545084) (xy 276.442932 -254.545084)
			)
		)
	)
	(zone
		(layer "In2.Cu")
		(hatch none 0.5)
		(connect_pads
			(clearance 0)
		)
		(min_thickness 0.25)
		(keepout
			(tracks not_allowed)
			(vias allowed)
			(pads allowed)
			(copperpour not_allowed)
			(footprints allowed)
		)
		(placement
			(enabled no)
			(sheetname "")
		)
		(fill
			(thermal_gap 0.5)
			(thermal_bridge_width 0.5)
			(island_removal_mode 0)
		)
		(polygon
			(pts
				(xy 31.946596 -197.925182) (xy 33.445196 -197.925182) (xy 33.445196 -198.44512) (xy 31.946596 -198.44512)
			)
		)
	)
	(zone
		(layer "In2.Cu")
		(hatch none 0.5)
		(connect_pads
			(clearance 0)
		)
		(min_thickness 0.25)
		(keepout
			(tracks not_allowed)
			(vias allowed)
			(pads allowed)
			(copperpour not_allowed)
			(footprints allowed)
		)
		(placement
			(enabled no)
			(sheetname "")
		)
		(fill
			(thermal_gap 0.5)
			(thermal_bridge_width 0.5)
			(island_removal_mode 0)
		)
		(polygon
			(pts
				(xy 306.618894 -313.525154) (xy 308.117494 -313.525154) (xy 308.117494 -314.045092) (xy 306.618894 -314.045092)
			)
		)
	)
	(zone
		(layer "In2.Cu")
		(hatch none 0.5)
		(connect_pads
			(clearance 0)
		)
		(min_thickness 0.25)
		(keepout
			(tracks not_allowed)
			(vias allowed)
			(pads allowed)
			(copperpour not_allowed)
			(footprints allowed)
		)
		(placement
			(enabled no)
			(sheetname "")
		)
		(fill
			(thermal_gap 0.5)
			(thermal_bridge_width 0.5)
			(island_removal_mode 0)
		)
		(polygon
			(pts
				(xy 434.250846 -237.02518) (xy 435.749446 -237.02518) (xy 435.749446 -237.545118) (xy 434.250846 -237.545118)
			)
		)
	)
	(zone
		(layer "In2.Cu")
		(hatch none 0.5)
		(connect_pads
			(clearance 0)
		)
		(min_thickness 0.25)
		(keepout
			(tracks not_allowed)
			(vias allowed)
			(pads allowed)
			(copperpour not_allowed)
			(footprints allowed)
		)
		(placement
			(enabled no)
			(sheetname "")
		)
		(fill
			(thermal_gap 0.5)
			(thermal_bridge_width 0.5)
			(island_removal_mode 0)
		)
		(polygon
			(pts
				(xy 434.250846 -203.875132) (xy 435.749446 -203.875132) (xy 435.749446 -204.39507) (xy 434.250846 -204.39507)
			)
		)
	)
	(zone
		(layer "In2.Cu")
		(hatch none 0.5)
		(connect_pads
			(clearance 0)
		)
		(min_thickness 0.25)
		(keepout
			(tracks not_allowed)
			(vias allowed)
			(pads allowed)
			(copperpour not_allowed)
			(footprints allowed)
		)
		(placement
			(enabled no)
			(sheetname "")
		)
		(fill
			(thermal_gap 0.5)
			(thermal_bridge_width 0.5)
			(island_removal_mode 0)
		)
		(polygon
			(pts
				(xy 434.250846 -224.275142) (xy 435.749446 -224.275142) (xy 435.749446 -224.79508) (xy 434.250846 -224.79508)
			)
		)
	)
	(zone
		(layer "In2.Cu")
		(hatch none 0.5)
		(connect_pads
			(clearance 0)
		)
		(min_thickness 0.25)
		(keepout
			(tracks not_allowed)
			(vias allowed)
			(pads allowed)
			(copperpour not_allowed)
			(footprints allowed)
		)
		(placement
			(enabled no)
			(sheetname "")
		)
		(fill
			(thermal_gap 0.5)
			(thermal_bridge_width 0.5)
			(island_removal_mode 0)
		)
		(polygon
			(pts
				(xy 299.07484 -214.075264) (xy 300.57344 -214.075264) (xy 300.57344 -214.595202) (xy 299.07484 -214.595202)
			)
		)
	)
	(zone
		(layer "In2.Cu")
		(hatch none 0.5)
		(connect_pads
			(clearance 0)
		)
		(min_thickness 0.25)
		(keepout
			(tracks not_allowed)
			(vias allowed)
			(pads allowed)
			(copperpour not_allowed)
			(footprints allowed)
		)
		(placement
			(enabled no)
			(sheetname "")
		)
		(fill
			(thermal_gap 0.5)
			(thermal_bridge_width 0.5)
			(island_removal_mode 0)
		)
		(polygon
			(pts
				(xy 163.678616 -254.025146) (xy 165.177216 -254.025146) (xy 165.177216 -254.545084) (xy 163.678616 -254.545084)
			)
		)
	)
	(zone
		(layer "In2.Cu")
		(hatch none 0.5)
		(connect_pads
			(clearance 0)
		)
		(min_thickness 0.25)
		(keepout
			(tracks not_allowed)
			(vias allowed)
			(pads allowed)
			(copperpour not_allowed)
			(footprints allowed)
		)
		(placement
			(enabled no)
			(sheetname "")
		)
		(fill
			(thermal_gap 0.5)
			(thermal_bridge_width 0.5)
			(island_removal_mode 0)
		)
		(polygon
			(pts
				(xy 276.442932 -284.625288) (xy 277.941532 -284.625288) (xy 277.941532 -285.145226) (xy 276.442932 -285.145226)
			)
		)
	)
	(zone
		(layer "In2.Cu")
		(hatch none 0.5)
		(connect_pads
			(clearance 0)
		)
		(min_thickness 0.25)
		(keepout
			(tracks not_allowed)
			(vias allowed)
			(pads allowed)
			(copperpour not_allowed)
			(footprints allowed)
		)
		(placement
			(enabled no)
			(sheetname "")
		)
		(fill
			(thermal_gap 0.5)
			(thermal_bridge_width 0.5)
			(island_removal_mode 0)
		)
		(polygon
			(pts
				(xy 283.986732 -231.07523) (xy 285.485332 -231.07523) (xy 285.485332 -231.595168) (xy 283.986732 -231.595168)
			)
		)
	)
	(zone
		(layer "In2.Cu")
		(hatch none 0.5)
		(connect_pads
			(clearance 0)
		)
		(min_thickness 0.25)
		(keepout
			(tracks not_allowed)
			(vias allowed)
			(pads allowed)
			(copperpour not_allowed)
			(footprints allowed)
		)
		(placement
			(enabled no)
			(sheetname "")
		)
		(fill
			(thermal_gap 0.5)
			(thermal_bridge_width 0.5)
			(island_removal_mode 0)
		)
		(polygon
			(pts
				(xy 279.886664 -230.225346) (xy 281.385264 -230.225346) (xy 281.385264 -230.745284) (xy 279.886664 -230.745284)
			)
		)
	)
	(zone
		(layer "In2.Cu")
		(hatch none 0.5)
		(connect_pads
			(clearance 0)
		)
		(min_thickness 0.25)
		(keepout
			(tracks not_allowed)
			(vias allowed)
			(pads allowed)
			(copperpour not_allowed)
			(footprints allowed)
		)
		(placement
			(enabled no)
			(sheetname "")
		)
		(fill
			(thermal_gap 0.5)
			(thermal_bridge_width 0.5)
			(island_removal_mode 0)
		)
		(polygon
			(pts
				(xy 268.898878 -271.87525) (xy 270.397478 -271.87525) (xy 270.397478 -272.395188) (xy 268.898878 -272.395188)
			)
		)
	)
	(zone
		(layer "In2.Cu")
		(hatch none 0.5)
		(connect_pads
			(clearance 0)
		)
		(min_thickness 0.25)
		(keepout
			(tracks not_allowed)
			(vias allowed)
			(pads allowed)
			(copperpour not_allowed)
			(footprints allowed)
		)
		(placement
			(enabled no)
			(sheetname "")
		)
		(fill
			(thermal_gap 0.5)
			(thermal_bridge_width 0.5)
			(island_removal_mode 0)
		)
		(polygon
			(pts
				(xy 453.438768 -228.525324) (xy 454.937368 -228.525324) (xy 454.937368 -229.045262) (xy 453.438768 -229.045262)
			)
		)
	)
	(zone
		(layer "In2.Cu")
		(hatch none 0.5)
		(connect_pads
			(clearance 0)
		)
		(min_thickness 0.25)
		(keepout
			(tracks not_allowed)
			(vias allowed)
			(pads allowed)
			(copperpour not_allowed)
			(footprints allowed)
		)
		(placement
			(enabled no)
			(sheetname "")
		)
		(fill
			(thermal_gap 0.5)
			(thermal_bridge_width 0.5)
			(island_removal_mode 0)
		)
		(polygon
			(pts
				(xy 20.95881 -197.075298) (xy 22.45741 -197.075298) (xy 22.45741 -197.595236) (xy 20.95881 -197.595236)
			)
		)
	)
	(zone
		(layer "In2.Cu")
		(hatch none 0.5)
		(connect_pads
			(clearance 0)
		)
		(min_thickness 0.25)
		(keepout
			(tracks not_allowed)
			(vias allowed)
			(pads allowed)
			(copperpour not_allowed)
			(footprints allowed)
		)
		(placement
			(enabled no)
			(sheetname "")
		)
		(fill
			(thermal_gap 0.5)
			(thermal_bridge_width 0.5)
			(island_removal_mode 0)
		)
		(polygon
			(pts
				(xy 294.974772 -283.77515) (xy 296.473372 -283.77515) (xy 296.473372 -284.295088) (xy 294.974772 -284.295088)
			)
		)
	)
	(zone
		(layer "In2.Cu")
		(hatch none 0.5)
		(connect_pads
			(clearance 0)
		)
		(min_thickness 0.25)
		(keepout
			(tracks not_allowed)
			(vias allowed)
			(pads allowed)
			(copperpour not_allowed)
			(footprints allowed)
		)
		(placement
			(enabled no)
			(sheetname "")
		)
		(fill
			(thermal_gap 0.5)
			(thermal_bridge_width 0.5)
			(island_removal_mode 0)
		)
		(polygon
			(pts
				(xy 31.946596 -253.175262) (xy 33.445196 -253.175262) (xy 33.445196 -253.6952) (xy 31.946596 -253.6952)
			)
		)
	)
	(zone
		(layer "In2.Cu")
		(hatch none 0.5)
		(connect_pads
			(clearance 0)
		)
		(min_thickness 0.25)
		(keepout
			(tracks not_allowed)
			(vias allowed)
			(pads allowed)
			(copperpour not_allowed)
			(footprints allowed)
		)
		(placement
			(enabled no)
			(sheetname "")
		)
		(fill
			(thermal_gap 0.5)
			(thermal_bridge_width 0.5)
			(island_removal_mode 0)
		)
		(polygon
			(pts
				(xy 175.322738 -229.375208) (xy 176.821338 -229.375208) (xy 176.821338 -229.895146) (xy 175.322738 -229.895146)
			)
		)
	)
	(zone
		(layer "In2.Cu")
		(hatch none 0.5)
		(connect_pads
			(clearance 0)
		)
		(min_thickness 0.25)
		(keepout
			(tracks not_allowed)
			(vias allowed)
			(pads allowed)
			(copperpour not_allowed)
			(footprints allowed)
		)
		(placement
			(enabled no)
			(sheetname "")
		)
		(fill
			(thermal_gap 0.5)
			(thermal_bridge_width 0.5)
			(island_removal_mode 0)
		)
		(polygon
			(pts
				(xy 54.578758 -225.975164) (xy 56.077358 -225.975164) (xy 56.077358 -226.495102) (xy 54.578758 -226.495102)
			)
		)
	)
	(zone
		(layer "In2.Cu")
		(hatch none 0.5)
		(connect_pads
			(clearance 0)
		)
		(min_thickness 0.25)
		(keepout
			(tracks not_allowed)
			(vias allowed)
			(pads allowed)
			(copperpour not_allowed)
			(footprints allowed)
		)
		(placement
			(enabled no)
			(sheetname "")
		)
		(fill
			(thermal_gap 0.5)
			(thermal_bridge_width 0.5)
			(island_removal_mode 0)
		)
		(polygon
			(pts
				(xy 54.578758 -242.97513) (xy 56.077358 -242.97513) (xy 56.077358 -243.495068) (xy 54.578758 -243.495068)
			)
		)
	)
	(zone
		(layer "In2.Cu")
		(hatch none 0.5)
		(connect_pads
			(clearance 0)
		)
		(min_thickness 0.25)
		(keepout
			(tracks not_allowed)
			(vias allowed)
			(pads allowed)
			(copperpour not_allowed)
			(footprints allowed)
		)
		(placement
			(enabled no)
			(sheetname "")
		)
		(fill
			(thermal_gap 0.5)
			(thermal_bridge_width 0.5)
			(island_removal_mode 0)
		)
		(polygon
			(pts
				(xy 36.046664 -307.575204) (xy 37.545264 -307.575204) (xy 37.545264 -308.095142) (xy 36.046664 -308.095142)
			)
		)
	)
	(zone
		(layer "In2.Cu")
		(hatch none 0.5)
		(connect_pads
			(clearance 0)
		)
		(min_thickness 0.25)
		(keepout
			(tracks not_allowed)
			(vias allowed)
			(pads allowed)
			(copperpour not_allowed)
			(footprints allowed)
		)
		(placement
			(enabled no)
			(sheetname "")
		)
		(fill
			(thermal_gap 0.5)
			(thermal_bridge_width 0.5)
			(island_removal_mode 0)
		)
		(polygon
			(pts
				(xy 434.250846 -218.325192) (xy 435.749446 -218.325192) (xy 435.749446 -218.84513) (xy 434.250846 -218.84513)
			)
		)
	)
	(zone
		(layer "In2.Cu")
		(hatch none 0.5)
		(connect_pads
			(clearance 0)
		)
		(min_thickness 0.25)
		(keepout
			(tracks not_allowed)
			(vias allowed)
			(pads allowed)
			(copperpour not_allowed)
			(footprints allowed)
		)
		(placement
			(enabled no)
			(sheetname "")
		)
		(fill
			(thermal_gap 0.5)
			(thermal_bridge_width 0.5)
			(island_removal_mode 0)
		)
		(polygon
			(pts
				(xy 268.898878 -238.725202) (xy 270.397478 -238.725202) (xy 270.397478 -239.24514) (xy 268.898878 -239.24514)
			)
		)
	)
	(zone
		(layer "In2.Cu")
		(hatch none 0.5)
		(connect_pads
			(clearance 0)
		)
		(min_thickness 0.25)
		(keepout
			(tracks allowed)
			(vias allowed)
			(pads allowed)
			(copperpour allowed)
			(footprints allowed)
		)
		(placement
			(enabled no)
			(sheetname "")
		)
		(fill
			(thermal_gap 0.5)
			(thermal_bridge_width 0.5)
			(island_removal_mode 0)
		)
		(polygon
			(pts
				(xy 92.450412 -338.251292) (xy 92.450412 -337.628992) (xy 93.001592 -337.628992) (xy 93.001592 -338.251292)
			)
		)
	)
	(zone
		(layer "In2.Cu")
		(hatch none 0.5)
		(connect_pads
			(clearance 0)
		)
		(min_thickness 0.25)
		(keepout
			(tracks not_allowed)
			(vias allowed)
			(pads allowed)
			(copperpour not_allowed)
			(footprints allowed)
		)
		(placement
			(enabled no)
			(sheetname "")
		)
		(fill
			(thermal_gap 0.5)
			(thermal_bridge_width 0.5)
			(island_removal_mode 0)
		)
		(polygon
			(pts
				(xy 201.398632 -263.37514) (xy 202.897232 -263.37514) (xy 202.897232 -263.895078) (xy 201.398632 -263.895078)
			)
		)
	)
	(zone
		(layer "In2.Cu")
		(hatch none 0.5)
		(connect_pads
			(clearance 0)
		)
		(min_thickness 0.25)
		(keepout
			(tracks not_allowed)
			(vias allowed)
			(pads allowed)
			(copperpour not_allowed)
			(footprints allowed)
		)
		(placement
			(enabled no)
			(sheetname "")
		)
		(fill
			(thermal_gap 0.5)
			(thermal_bridge_width 0.5)
			(island_removal_mode 0)
		)
		(polygon
			(pts
				(xy 190.410846 -303.325276) (xy 191.909446 -303.325276) (xy 191.909446 -303.845214) (xy 190.410846 -303.845214)
			)
		)
	)
	(zone
		(layer "In2.Cu")
		(hatch none 0.5)
		(connect_pads
			(clearance 0)
		)
		(min_thickness 0.25)
		(keepout
			(tracks not_allowed)
			(vias allowed)
			(pads allowed)
			(copperpour not_allowed)
			(footprints allowed)
		)
		(placement
			(enabled no)
			(sheetname "")
		)
		(fill
			(thermal_gap 0.5)
			(thermal_bridge_width 0.5)
			(island_removal_mode 0)
		)
		(polygon
			(pts
				(xy 54.578758 -230.225346) (xy 56.077358 -230.225346) (xy 56.077358 -230.745284) (xy 54.578758 -230.745284)
			)
		)
	)
	(zone
		(layer "In2.Cu")
		(hatch none 0.5)
		(connect_pads
			(clearance 0)
		)
		(min_thickness 0.25)
		(keepout
			(tracks not_allowed)
			(vias allowed)
			(pads allowed)
			(copperpour not_allowed)
			(footprints allowed)
		)
		(placement
			(enabled no)
			(sheetname "")
		)
		(fill
			(thermal_gap 0.5)
			(thermal_bridge_width 0.5)
			(island_removal_mode 0)
		)
		(polygon
			(pts
				(xy 434.250846 -213.225126) (xy 435.749446 -213.225126) (xy 435.749446 -213.745064) (xy 434.250846 -213.745064)
			)
		)
	)
	(zone
		(layer "In2.Cu")
		(hatch none 0.5)
		(connect_pads
			(clearance 0)
		)
		(min_thickness 0.25)
		(keepout
			(tracks not_allowed)
			(vias allowed)
			(pads allowed)
			(copperpour not_allowed)
			(footprints allowed)
		)
		(placement
			(enabled no)
			(sheetname "")
		)
		(fill
			(thermal_gap 0.5)
			(thermal_bridge_width 0.5)
			(island_removal_mode 0)
		)
		(polygon
			(pts
				(xy 175.322738 -206.425292) (xy 176.821338 -206.425292) (xy 176.821338 -206.94523) (xy 175.322738 -206.94523)
			)
		)
	)
	(zone
		(layer "In2.Cu")
		(hatch none 0.5)
		(connect_pads
			(clearance 0)
		)
		(min_thickness 0.25)
		(keepout
			(tracks not_allowed)
			(vias allowed)
			(pads allowed)
			(copperpour not_allowed)
			(footprints allowed)
		)
		(placement
			(enabled no)
			(sheetname "")
		)
		(fill
			(thermal_gap 0.5)
			(thermal_bridge_width 0.5)
			(island_removal_mode 0)
		)
		(polygon
			(pts
				(xy 268.898878 -284.625288) (xy 270.397478 -284.625288) (xy 270.397478 -285.145226) (xy 268.898878 -285.145226)
			)
		)
	)
	(zone
		(layer "In2.Cu")
		(hatch none 0.5)
		(connect_pads
			(clearance 0)
		)
		(min_thickness 0.25)
		(keepout
			(tracks not_allowed)
			(vias allowed)
			(pads allowed)
			(copperpour not_allowed)
			(footprints allowed)
		)
		(placement
			(enabled no)
			(sheetname "")
		)
		(fill
			(thermal_gap 0.5)
			(thermal_bridge_width 0.5)
			(island_removal_mode 0)
		)
		(polygon
			(pts
				(xy 291.530786 -316.925198) (xy 293.029386 -316.925198) (xy 293.029386 -317.445136) (xy 291.530786 -317.445136)
			)
		)
	)
	(zone
		(layer "In2.Cu")
		(hatch none 0.5)
		(connect_pads
			(clearance 0)
		)
		(min_thickness 0.25)
		(keepout
			(tracks not_allowed)
			(vias allowed)
			(pads allowed)
			(copperpour not_allowed)
			(footprints allowed)
		)
		(placement
			(enabled no)
			(sheetname "")
		)
		(fill
			(thermal_gap 0.5)
			(thermal_bridge_width 0.5)
			(island_removal_mode 0)
		)
		(polygon
			(pts
				(xy 438.350914 -198.77532) (xy 439.849514 -198.77532) (xy 439.849514 -199.295258) (xy 438.350914 -199.295258)
			)
		)
	)
	(zone
		(layer "In2.Cu")
		(hatch none 0.5)
		(connect_pads
			(clearance 0)
		)
		(min_thickness 0.25)
		(keepout
			(tracks not_allowed)
			(vias allowed)
			(pads allowed)
			(copperpour not_allowed)
			(footprints allowed)
		)
		(placement
			(enabled no)
			(sheetname "")
		)
		(fill
			(thermal_gap 0.5)
			(thermal_bridge_width 0.5)
			(island_removal_mode 0)
		)
		(polygon
			(pts
				(xy 51.134772 -215.775286) (xy 52.633372 -215.775286) (xy 52.633372 -216.295224) (xy 51.134772 -216.295224)
			)
		)
	)
	(zone
		(layer "In2.Cu")
		(hatch none 0.5)
		(connect_pads
			(clearance 0)
		)
		(min_thickness 0.25)
		(keepout
			(tracks not_allowed)
			(vias allowed)
			(pads allowed)
			(copperpour not_allowed)
			(footprints allowed)
		)
		(placement
			(enabled no)
			(sheetname "")
		)
		(fill
			(thermal_gap 0.5)
			(thermal_bridge_width 0.5)
			(island_removal_mode 0)
		)
		(polygon
			(pts
				(xy 438.350914 -309.275226) (xy 439.849514 -309.275226) (xy 439.849514 -309.795164) (xy 438.350914 -309.795164)
			)
		)
	)
	(zone
		(layer "In2.Cu")
		(hatch none 0.5)
		(connect_pads
			(clearance 0)
		)
		(min_thickness 0.25)
		(keepout
			(tracks not_allowed)
			(vias allowed)
			(pads allowed)
			(copperpour not_allowed)
			(footprints allowed)
		)
		(placement
			(enabled no)
			(sheetname "")
		)
		(fill
			(thermal_gap 0.5)
			(thermal_bridge_width 0.5)
			(island_removal_mode 0)
		)
		(polygon
			(pts
				(xy 201.398632 -316.075314) (xy 202.897232 -316.075314) (xy 202.897232 -316.595252) (xy 201.398632 -316.595252)
			)
		)
	)
	(zone
		(layer "In2.Cu")
		(hatch none 0.5)
		(connect_pads
			(clearance 0)
		)
		(min_thickness 0.25)
		(keepout
			(tracks not_allowed)
			(vias allowed)
			(pads allowed)
			(copperpour not_allowed)
			(footprints allowed)
		)
		(placement
			(enabled no)
			(sheetname "")
		)
		(fill
			(thermal_gap 0.5)
			(thermal_bridge_width 0.5)
			(island_removal_mode 0)
		)
		(polygon
			(pts
				(xy 24.402542 -263.37514) (xy 25.901142 -263.37514) (xy 25.901142 -263.895078) (xy 24.402542 -263.895078)
			)
		)
	)
	(zone
		(layer "In2.Cu")
		(hatch none 0.5)
		(connect_pads
			(clearance 0)
		)
		(min_thickness 0.25)
		(keepout
			(tracks not_allowed)
			(vias allowed)
			(pads allowed)
			(copperpour not_allowed)
			(footprints allowed)
		)
		(placement
			(enabled no)
			(sheetname "")
		)
		(fill
			(thermal_gap 0.5)
			(thermal_bridge_width 0.5)
			(island_removal_mode 0)
		)
		(polygon
			(pts
				(xy 423.262806 -275.275294) (xy 424.761406 -275.275294) (xy 424.761406 -275.795232) (xy 423.262806 -275.795232)
			)
		)
	)
	(zone
		(layer "In2.Cu")
		(hatch none 0.5)
		(connect_pads
			(clearance 0)
		)
		(min_thickness 0.25)
		(keepout
			(tracks not_allowed)
			(vias allowed)
			(pads allowed)
			(copperpour not_allowed)
			(footprints allowed)
		)
		(placement
			(enabled no)
			(sheetname "")
		)
		(fill
			(thermal_gap 0.5)
			(thermal_bridge_width 0.5)
			(island_removal_mode 0)
		)
		(polygon
			(pts
				(xy 283.986732 -267.625322) (xy 285.485332 -267.625322) (xy 285.485332 -268.14526) (xy 283.986732 -268.14526)
			)
		)
	)
	(zone
		(layer "In2.Cu")
		(hatch none 0.5)
		(connect_pads
			(clearance 0)
		)
		(min_thickness 0.25)
		(keepout
			(tracks not_allowed)
			(vias allowed)
			(pads allowed)
			(copperpour not_allowed)
			(footprints allowed)
		)
		(placement
			(enabled no)
			(sheetname "")
		)
		(fill
			(thermal_gap 0.5)
			(thermal_bridge_width 0.5)
			(island_removal_mode 0)
		)
		(polygon
			(pts
				(xy 449.3387 -246.375174) (xy 450.8373 -246.375174) (xy 450.8373 -246.895112) (xy 449.3387 -246.895112)
			)
		)
	)
	(zone
		(layer "In2.Cu")
		(hatch none 0.5)
		(connect_pads
			(clearance 0)
		)
		(min_thickness 0.25)
		(keepout
			(tracks not_allowed)
			(vias allowed)
			(pads allowed)
			(copperpour not_allowed)
			(footprints allowed)
		)
		(placement
			(enabled no)
			(sheetname "")
		)
		(fill
			(thermal_gap 0.5)
			(thermal_bridge_width 0.5)
			(island_removal_mode 0)
		)
		(polygon
			(pts
				(xy 31.946596 -211.525104) (xy 33.445196 -211.525104) (xy 33.445196 -212.045042) (xy 31.946596 -212.045042)
			)
		)
	)
	(zone
		(layer "In2.Cu")
		(hatch none 0.5)
		(connect_pads
			(clearance 0)
		)
		(min_thickness 0.25)
		(keepout
			(tracks not_allowed)
			(vias allowed)
			(pads allowed)
			(copperpour not_allowed)
			(footprints allowed)
		)
		(placement
			(enabled no)
			(sheetname "")
		)
		(fill
			(thermal_gap 0.5)
			(thermal_bridge_width 0.5)
			(island_removal_mode 0)
		)
		(polygon
			(pts
				(xy 201.398632 -310.12511) (xy 202.897232 -310.12511) (xy 202.897232 -310.645048) (xy 201.398632 -310.645048)
			)
		)
	)
	(zone
		(layer "In2.Cu")
		(hatch none 0.5)
		(connect_pads
			(clearance 0)
		)
		(min_thickness 0.25)
		(keepout
			(tracks not_allowed)
			(vias allowed)
			(pads allowed)
			(copperpour not_allowed)
			(footprints allowed)
		)
		(placement
			(enabled no)
			(sheetname "")
		)
		(fill
			(thermal_gap 0.5)
			(thermal_bridge_width 0.5)
			(island_removal_mode 0)
		)
		(polygon
			(pts
				(xy 449.3387 -220.875098) (xy 450.8373 -220.875098) (xy 450.8373 -221.395036) (xy 449.3387 -221.395036)
			)
		)
	)
	(zone
		(layer "In2.Cu")
		(hatch none 0.5)
		(connect_pads
			(clearance 0)
		)
		(min_thickness 0.25)
		(keepout
			(tracks not_allowed)
			(vias allowed)
			(pads allowed)
			(copperpour not_allowed)
			(footprints allowed)
		)
		(placement
			(enabled no)
			(sheetname "")
		)
		(fill
			(thermal_gap 0.5)
			(thermal_bridge_width 0.5)
			(island_removal_mode 0)
		)
		(polygon
			(pts
				(xy 302.518826 -263.37514) (xy 304.017426 -263.37514) (xy 304.017426 -263.895078) (xy 302.518826 -263.895078)
			)
		)
	)
	(zone
		(layer "In2.Cu")
		(hatch none 0.5)
		(connect_pads
			(clearance 0)
		)
		(min_thickness 0.25)
		(keepout
			(tracks not_allowed)
			(vias allowed)
			(pads allowed)
			(copperpour not_allowed)
			(footprints allowed)
		)
		(placement
			(enabled no)
			(sheetname "")
		)
		(fill
			(thermal_gap 0.5)
			(thermal_bridge_width 0.5)
			(island_removal_mode 0)
		)
		(polygon
			(pts
				(xy 287.430718 -278.675338) (xy 288.929318 -278.675338) (xy 288.929318 -279.195276) (xy 287.430718 -279.195276)
			)
		)
	)
	(zone
		(layer "In2.Cu")
		(hatch none 0.5)
		(connect_pads
			(clearance 0)
		)
		(min_thickness 0.25)
		(keepout
			(tracks not_allowed)
			(vias allowed)
			(pads allowed)
			(copperpour not_allowed)
			(footprints allowed)
		)
		(placement
			(enabled no)
			(sheetname "")
		)
		(fill
			(thermal_gap 0.5)
			(thermal_bridge_width 0.5)
			(island_removal_mode 0)
		)
		(polygon
			(pts
				(arc
					(start 428.072296 -7.672324)
					(mid 428.094614 -7.618442)
					(end 428.148496 -7.596124)
				)
				(arc
					(start 429.18507 -7.596124)
					(mid 429.238952 -7.618442)
					(end 429.26127 -7.672324)
				)
				(arc
					(start 429.26127 -9.071864)
					(mid 429.238952 -9.125746)
					(end 429.18507 -9.148064)
				)
				(arc
					(start 428.148496 -9.148064)
					(mid 428.094614 -9.125746)
					(end 428.072296 -9.071864)
				)
			)
		)
	)
	(zone
		(layer "In2.Cu")
		(hatch none 0.5)
		(connect_pads
			(clearance 0)
		)
		(min_thickness 0.25)
		(keepout
			(tracks not_allowed)
			(vias allowed)
			(pads allowed)
			(copperpour not_allowed)
			(footprints allowed)
		)
		(placement
			(enabled no)
			(sheetname "")
		)
		(fill
			(thermal_gap 0.5)
			(thermal_bridge_width 0.5)
			(island_removal_mode 0)
		)
		(polygon
			(pts
				(xy 28.50261 -296.525188) (xy 30.00121 -296.525188) (xy 30.00121 -297.045126) (xy 28.50261 -297.045126)
			)
		)
	)
	(zone
		(layer "In2.Cu")
		(hatch none 0.5)
		(connect_pads
			(clearance 0)
		)
		(min_thickness 0.25)
		(keepout
			(tracks not_allowed)
			(vias allowed)
			(pads allowed)
			(copperpour not_allowed)
			(footprints allowed)
		)
		(placement
			(enabled no)
			(sheetname "")
		)
		(fill
			(thermal_gap 0.5)
			(thermal_bridge_width 0.5)
			(island_removal_mode 0)
		)
		(polygon
			(pts
				(xy 16.858742 -317.775336) (xy 18.357342 -317.775336) (xy 18.357342 -318.295274) (xy 16.858742 -318.295274)
			)
		)
	)
	(zone
		(layer "In2.Cu")
		(hatch none 0.5)
		(connect_pads
			(clearance 0)
		)
		(min_thickness 0.25)
		(keepout
			(tracks not_allowed)
			(vias allowed)
			(pads allowed)
			(copperpour not_allowed)
			(footprints allowed)
		)
		(placement
			(enabled no)
			(sheetname "")
		)
		(fill
			(thermal_gap 0.5)
			(thermal_bridge_width 0.5)
			(island_removal_mode 0)
		)
		(polygon
			(pts
				(xy 302.518826 -233.625136) (xy 304.017426 -233.625136) (xy 304.017426 -234.145074) (xy 302.518826 -234.145074)
			)
		)
	)
	(zone
		(layer "In2.Cu")
		(hatch none 0.5)
		(connect_pads
			(clearance 0)
		)
		(min_thickness 0.25)
		(keepout
			(tracks not_allowed)
			(vias allowed)
			(pads allowed)
			(copperpour not_allowed)
			(footprints allowed)
		)
		(placement
			(enabled no)
			(sheetname "")
		)
		(fill
			(thermal_gap 0.5)
			(thermal_bridge_width 0.5)
			(island_removal_mode 0)
		)
		(polygon
			(pts
				(xy 299.07484 -229.375208) (xy 300.57344 -229.375208) (xy 300.57344 -229.895146) (xy 299.07484 -229.895146)
			)
		)
	)
	(zone
		(layer "In2.Cu")
		(hatch none 0.5)
		(connect_pads
			(clearance 0)
		)
		(min_thickness 0.25)
		(keepout
			(tracks not_allowed)
			(vias allowed)
			(pads allowed)
			(copperpour not_allowed)
			(footprints allowed)
		)
		(placement
			(enabled no)
			(sheetname "")
		)
		(fill
			(thermal_gap 0.5)
			(thermal_bridge_width 0.5)
			(island_removal_mode 0)
		)
		(polygon
			(pts
				(xy 423.262806 -267.625322) (xy 424.761406 -267.625322) (xy 424.761406 -268.14526) (xy 423.262806 -268.14526)
			)
		)
	)
	(zone
		(layer "In2.Cu")
		(hatch none 0.5)
		(connect_pads
			(clearance 0)
		)
		(min_thickness 0.25)
		(keepout
			(tracks not_allowed)
			(vias allowed)
			(pads allowed)
			(copperpour not_allowed)
			(footprints allowed)
		)
		(placement
			(enabled no)
			(sheetname "")
		)
		(fill
			(thermal_gap 0.5)
			(thermal_bridge_width 0.5)
			(island_removal_mode 0)
		)
		(polygon
			(pts
				(xy 449.3387 -295.675304) (xy 450.8373 -295.675304) (xy 450.8373 -296.195242) (xy 449.3387 -296.195242)
			)
		)
	)
	(zone
		(layer "In2.Cu")
		(hatch none 0.5)
		(connect_pads
			(clearance 0)
		)
		(min_thickness 0.25)
		(keepout
			(tracks not_allowed)
			(vias allowed)
			(pads allowed)
			(copperpour not_allowed)
			(footprints allowed)
		)
		(placement
			(enabled no)
			(sheetname "")
		)
		(fill
			(thermal_gap 0.5)
			(thermal_bridge_width 0.5)
			(island_removal_mode 0)
		)
		(polygon
			(pts
				(xy 197.954646 -229.375208) (xy 199.453246 -229.375208) (xy 199.453246 -229.895146) (xy 197.954646 -229.895146)
			)
		)
	)
	(zone
		(layer "In2.Cu")
		(hatch none 0.5)
		(connect_pads
			(clearance 0)
		)
		(min_thickness 0.25)
		(keepout
			(tracks not_allowed)
			(vias allowed)
			(pads allowed)
			(copperpour not_allowed)
			(footprints allowed)
		)
		(placement
			(enabled no)
			(sheetname "")
		)
		(fill
			(thermal_gap 0.5)
			(thermal_bridge_width 0.5)
			(island_removal_mode 0)
		)
		(polygon
			(pts
				(xy 411.618684 -201.325226) (xy 413.117284 -201.325226) (xy 413.117284 -201.845164) (xy 411.618684 -201.845164)
			)
		)
	)
	(zone
		(layer "In2.Cu")
		(hatch none 0.5)
		(connect_pads
			(clearance 0)
		)
		(min_thickness 0.25)
		(keepout
			(tracks not_allowed)
			(vias allowed)
			(pads allowed)
			(copperpour not_allowed)
			(footprints allowed)
		)
		(placement
			(enabled no)
			(sheetname "")
		)
		(fill
			(thermal_gap 0.5)
			(thermal_bridge_width 0.5)
			(island_removal_mode 0)
		)
		(polygon
			(pts
				(xy 287.430718 -314.375292) (xy 288.929318 -314.375292) (xy 288.929318 -314.89523) (xy 287.430718 -314.89523)
			)
		)
	)
	(zone
		(layer "In2.Cu")
		(hatch none 0.5)
		(connect_pads
			(clearance 0)
		)
		(min_thickness 0.25)
		(keepout
			(tracks not_allowed)
			(vias allowed)
			(pads allowed)
			(copperpour not_allowed)
			(footprints allowed)
		)
		(placement
			(enabled no)
			(sheetname "")
		)
		(fill
			(thermal_gap 0.5)
			(thermal_bridge_width 0.5)
			(island_removal_mode 0)
		)
		(polygon
			(pts
				(xy 306.618894 -277.8252) (xy 308.117494 -277.8252) (xy 308.117494 -278.345138) (xy 306.618894 -278.345138)
			)
		)
	)
	(zone
		(layer "In2.Cu")
		(hatch none 0.5)
		(connect_pads
			(clearance 0)
		)
		(min_thickness 0.25)
		(keepout
			(tracks not_allowed)
			(vias allowed)
			(pads allowed)
			(copperpour not_allowed)
			(footprints allowed)
		)
		(placement
			(enabled no)
			(sheetname "")
		)
		(fill
			(thermal_gap 0.5)
			(thermal_bridge_width 0.5)
			(island_removal_mode 0)
		)
		(polygon
			(pts
				(xy 299.07484 -215.775286) (xy 300.57344 -215.775286) (xy 300.57344 -216.295224) (xy 299.07484 -216.295224)
			)
		)
	)
	(zone
		(layer "In2.Cu")
		(hatch none 0.5)
		(connect_pads
			(clearance 0)
		)
		(min_thickness 0.25)
		(keepout
			(tracks not_allowed)
			(vias allowed)
			(pads allowed)
			(copperpour not_allowed)
			(footprints allowed)
		)
		(placement
			(enabled no)
			(sheetname "")
		)
		(fill
			(thermal_gap 0.5)
			(thermal_bridge_width 0.5)
			(island_removal_mode 0)
		)
		(polygon
			(pts
				(xy 434.250846 -242.97513) (xy 435.749446 -242.97513) (xy 435.749446 -243.495068) (xy 434.250846 -243.495068)
			)
		)
	)
	(zone
		(layer "In2.Cu")
		(hatch none 0.5)
		(connect_pads
			(clearance 0)
		)
		(min_thickness 0.25)
		(keepout
			(tracks not_allowed)
			(vias allowed)
			(pads allowed)
			(copperpour not_allowed)
			(footprints allowed)
		)
		(placement
			(enabled no)
			(sheetname "")
		)
		(fill
			(thermal_gap 0.5)
			(thermal_bridge_width 0.5)
			(island_removal_mode 0)
		)
		(polygon
			(pts
				(xy 16.858742 -202.17511) (xy 18.357342 -202.17511) (xy 18.357342 -202.695048) (xy 16.858742 -202.695048)
			)
		)
	)
	(zone
		(layer "In2.Cu")
		(hatch none 0.5)
		(connect_pads
			(clearance 0)
		)
		(min_thickness 0.25)
		(keepout
			(tracks not_allowed)
			(vias allowed)
			(pads allowed)
			(copperpour not_allowed)
			(footprints allowed)
		)
		(placement
			(enabled no)
			(sheetname "")
		)
		(fill
			(thermal_gap 0.5)
			(thermal_bridge_width 0.5)
			(island_removal_mode 0)
		)
		(polygon
			(pts
				(xy 279.886664 -242.97513) (xy 281.385264 -242.97513) (xy 281.385264 -243.495068) (xy 279.886664 -243.495068)
			)
		)
	)
	(zone
		(layer "In2.Cu")
		(hatch none 0.5)
		(connect_pads
			(clearance 0)
		)
		(min_thickness 0.25)
		(keepout
			(tracks not_allowed)
			(vias allowed)
			(pads allowed)
			(copperpour not_allowed)
			(footprints allowed)
		)
		(placement
			(enabled no)
			(sheetname "")
		)
		(fill
			(thermal_gap 0.5)
			(thermal_bridge_width 0.5)
			(island_removal_mode 0)
		)
		(polygon
			(pts
				(xy 453.438768 -232.775252) (xy 454.937368 -232.775252) (xy 454.937368 -233.29519) (xy 453.438768 -233.29519)
			)
		)
	)
	(zone
		(layer "In2.Cu")
		(hatch none 0.5)
		(connect_pads
			(clearance 0)
		)
		(min_thickness 0.25)
		(keepout
			(tracks not_allowed)
			(vias allowed)
			(pads allowed)
			(copperpour not_allowed)
			(footprints allowed)
		)
		(placement
			(enabled no)
			(sheetname "")
		)
		(fill
			(thermal_gap 0.5)
			(thermal_bridge_width 0.5)
			(island_removal_mode 0)
		)
		(polygon
			(pts
				(xy 167.778684 -276.125178) (xy 169.277284 -276.125178) (xy 169.277284 -276.645116) (xy 167.778684 -276.645116)
			)
		)
	)
	(zone
		(layer "In2.Cu")
		(hatch none 0.5)
		(connect_pads
			(clearance 0)
		)
		(min_thickness 0.25)
		(keepout
			(tracks not_allowed)
			(vias allowed)
			(pads allowed)
			(copperpour not_allowed)
			(footprints allowed)
		)
		(placement
			(enabled no)
			(sheetname "")
		)
		(fill
			(thermal_gap 0.5)
			(thermal_bridge_width 0.5)
			(island_removal_mode 0)
		)
		(polygon
			(pts
				(xy 291.530786 -270.175228) (xy 293.029386 -270.175228) (xy 293.029386 -270.695166) (xy 291.530786 -270.695166)
			)
		)
	)
	(zone
		(layer "In2.Cu")
		(hatch none 0.5)
		(connect_pads
			(clearance 0)
		)
		(min_thickness 0.25)
		(keepout
			(tracks not_allowed)
			(vias allowed)
			(pads allowed)
			(copperpour not_allowed)
			(footprints allowed)
		)
		(placement
			(enabled no)
			(sheetname "")
		)
		(fill
			(thermal_gap 0.5)
			(thermal_bridge_width 0.5)
			(island_removal_mode 0)
		)
		(polygon
			(pts
				(xy 419.162738 -294.825166) (xy 420.661338 -294.825166) (xy 420.661338 -295.345104) (xy 419.162738 -295.345104)
			)
		)
	)
	(zone
		(layer "In2.Cu")
		(hatch none 0.5)
		(connect_pads
			(clearance 0)
		)
		(min_thickness 0.25)
		(keepout
			(tracks not_allowed)
			(vias allowed)
			(pads allowed)
			(copperpour not_allowed)
			(footprints allowed)
		)
		(placement
			(enabled no)
			(sheetname "")
		)
		(fill
			(thermal_gap 0.5)
			(thermal_bridge_width 0.5)
			(island_removal_mode 0)
		)
		(polygon
			(pts
				(xy 190.410846 -298.22521) (xy 191.909446 -298.22521) (xy 191.909446 -298.745148) (xy 190.410846 -298.745148)
			)
		)
	)
	(zone
		(layer "In2.Cu")
		(hatch none 0.5)
		(connect_pads
			(clearance 0)
		)
		(min_thickness 0.25)
		(keepout
			(tracks not_allowed)
			(vias allowed)
			(pads allowed)
			(copperpour not_allowed)
			(footprints allowed)
		)
		(placement
			(enabled no)
			(sheetname "")
		)
		(fill
			(thermal_gap 0.5)
			(thermal_bridge_width 0.5)
			(island_removal_mode 0)
		)
		(polygon
			(pts
				(xy 302.518826 -297.375326) (xy 304.017426 -297.375326) (xy 304.017426 -297.895264) (xy 302.518826 -297.895264)
			)
		)
	)
	(zone
		(layer "In2.Cu")
		(hatch none 0.5)
		(connect_pads
			(clearance 0)
		)
		(min_thickness 0.25)
		(keepout
			(tracks allowed)
			(vias allowed)
			(pads allowed)
			(copperpour allowed)
			(footprints allowed)
		)
		(placement
			(enabled no)
			(sheetname "")
		)
		(fill
			(thermal_gap 0.5)
			(thermal_bridge_width 0.5)
			(island_removal_mode 0)
		)
		(polygon
			(pts
				(xy 338.383372 -338.246466) (xy 338.383372 -337.624166) (xy 338.934552 -337.624166) (xy 338.934552 -338.246466)
			)
		)
	)
	(zone
		(layer "In2.Cu")
		(hatch none 0.5)
		(connect_pads
			(clearance 0)
		)
		(min_thickness 0.25)
		(keepout
			(tracks not_allowed)
			(vias allowed)
			(pads allowed)
			(copperpour not_allowed)
			(footprints allowed)
		)
		(placement
			(enabled no)
			(sheetname "")
		)
		(fill
			(thermal_gap 0.5)
			(thermal_bridge_width 0.5)
			(island_removal_mode 0)
		)
		(polygon
			(pts
				(xy 306.618894 -298.22521) (xy 308.117494 -298.22521) (xy 308.117494 -298.745148) (xy 306.618894 -298.745148)
			)
		)
	)
	(zone
		(layer "In2.Cu")
		(hatch none 0.5)
		(connect_pads
			(clearance 0)
		)
		(min_thickness 0.25)
		(keepout
			(tracks not_allowed)
			(vias allowed)
			(pads allowed)
			(copperpour not_allowed)
			(footprints allowed)
		)
		(placement
			(enabled no)
			(sheetname "")
		)
		(fill
			(thermal_gap 0.5)
			(thermal_bridge_width 0.5)
			(island_removal_mode 0)
		)
		(polygon
			(pts
				(xy 445.894968 -290.575238) (xy 447.393568 -290.575238) (xy 447.393568 -291.095176) (xy 445.894968 -291.095176)
			)
		)
	)
	(zone
		(layer "In2.Cu")
		(hatch none 0.5)
		(connect_pads
			(clearance 0)
		)
		(min_thickness 0.25)
		(keepout
			(tracks not_allowed)
			(vias allowed)
			(pads allowed)
			(copperpour not_allowed)
			(footprints allowed)
		)
		(placement
			(enabled no)
			(sheetname "")
		)
		(fill
			(thermal_gap 0.5)
			(thermal_bridge_width 0.5)
			(island_removal_mode 0)
		)
		(polygon
			(pts
				(xy 441.7949 -211.525104) (xy 443.2935 -211.525104) (xy 443.2935 -212.045042) (xy 441.7949 -212.045042)
			)
		)
	)
	(zone
		(layer "In2.Cu")
		(hatch none 0.5)
		(connect_pads
			(clearance 0)
		)
		(min_thickness 0.25)
		(keepout
			(tracks not_allowed)
			(vias allowed)
			(pads allowed)
			(copperpour not_allowed)
			(footprints allowed)
		)
		(placement
			(enabled no)
			(sheetname "")
		)
		(fill
			(thermal_gap 0.5)
			(thermal_bridge_width 0.5)
			(island_removal_mode 0)
		)
		(polygon
			(pts
				(xy 47.034704 -244.675152) (xy 48.533304 -244.675152) (xy 48.533304 -245.19509) (xy 47.034704 -245.19509)
			)
		)
	)
	(zone
		(layer "In2.Cu")
		(hatch none 0.5)
		(connect_pads
			(clearance 0)
		)
		(min_thickness 0.25)
		(keepout
			(tracks not_allowed)
			(vias allowed)
			(pads allowed)
			(copperpour not_allowed)
			(footprints allowed)
		)
		(placement
			(enabled no)
			(sheetname "")
		)
		(fill
			(thermal_gap 0.5)
			(thermal_bridge_width 0.5)
			(island_removal_mode 0)
		)
		(polygon
			(pts
				(xy 24.402542 -231.925114) (xy 25.901142 -231.925114) (xy 25.901142 -232.445052) (xy 24.402542 -232.445052)
			)
		)
	)
	(zone
		(layer "In2.Cu")
		(hatch none 0.5)
		(connect_pads
			(clearance 0)
		)
		(min_thickness 0.25)
		(keepout
			(tracks allowed)
			(vias allowed)
			(pads allowed)
			(copperpour allowed)
			(footprints allowed)
		)
		(placement
			(enabled no)
			(sheetname "")
		)
		(fill
			(thermal_gap 0.5)
			(thermal_bridge_width 0.5)
			(island_removal_mode 0)
		)
		(polygon
			(pts
				(xy 319.77457 -338.133182) (xy 319.77457 -337.510882) (xy 320.32575 -337.510882) (xy 320.32575 -338.133182)
			)
		)
	)
	(zone
		(layer "In2.Cu")
		(hatch none 0.5)
		(connect_pads
			(clearance 0)
		)
		(min_thickness 0.25)
		(keepout
			(tracks not_allowed)
			(vias allowed)
			(pads allowed)
			(copperpour not_allowed)
			(footprints allowed)
		)
		(placement
			(enabled no)
			(sheetname "")
		)
		(fill
			(thermal_gap 0.5)
			(thermal_bridge_width 0.5)
			(island_removal_mode 0)
		)
		(polygon
			(pts
				(xy 20.95881 -264.225278) (xy 22.45741 -264.225278) (xy 22.45741 -264.745216) (xy 20.95881 -264.745216)
			)
		)
	)
	(zone
		(layer "In2.Cu")
		(hatch none 0.5)
		(connect_pads
			(clearance 0)
		)
		(min_thickness 0.25)
		(keepout
			(tracks not_allowed)
			(vias allowed)
			(pads allowed)
			(copperpour not_allowed)
			(footprints allowed)
		)
		(placement
			(enabled no)
			(sheetname "")
		)
		(fill
			(thermal_gap 0.5)
			(thermal_bridge_width 0.5)
			(island_removal_mode 0)
		)
		(polygon
			(pts
				(xy 279.886664 -241.275108) (xy 281.385264 -241.275108) (xy 281.385264 -241.795046) (xy 279.886664 -241.795046)
			)
		)
	)
	(zone
		(layer "In2.Cu")
		(hatch none 0.5)
		(connect_pads
			(clearance 0)
		)
		(min_thickness 0.25)
		(keepout
			(tracks not_allowed)
			(vias allowed)
			(pads allowed)
			(copperpour not_allowed)
			(footprints allowed)
		)
		(placement
			(enabled no)
			(sheetname "")
		)
		(fill
			(thermal_gap 0.5)
			(thermal_bridge_width 0.5)
			(island_removal_mode 0)
		)
		(polygon
			(pts
				(xy 190.410846 -206.425292) (xy 191.909446 -206.425292) (xy 191.909446 -206.94523) (xy 190.410846 -206.94523)
			)
		)
	)
	(zone
		(layer "In2.Cu")
		(hatch none 0.5)
		(connect_pads
			(clearance 0)
		)
		(min_thickness 0.25)
		(keepout
			(tracks not_allowed)
			(vias allowed)
			(pads allowed)
			(copperpour not_allowed)
			(footprints allowed)
		)
		(placement
			(enabled no)
			(sheetname "")
		)
		(fill
			(thermal_gap 0.5)
			(thermal_bridge_width 0.5)
			(island_removal_mode 0)
		)
		(polygon
			(pts
				(xy 268.898878 -315.225176) (xy 270.397478 -315.225176) (xy 270.397478 -315.745114) (xy 268.898878 -315.745114)
			)
		)
	)
	(zone
		(layer "In2.Cu")
		(hatch none 0.5)
		(connect_pads
			(clearance 0)
		)
		(min_thickness 0.25)
		(keepout
			(tracks not_allowed)
			(vias allowed)
			(pads allowed)
			(copperpour not_allowed)
			(footprints allowed)
		)
		(placement
			(enabled no)
			(sheetname "")
		)
		(fill
			(thermal_gap 0.5)
			(thermal_bridge_width 0.5)
			(island_removal_mode 0)
		)
		(polygon
			(pts
				(xy 415.718752 -293.975282) (xy 417.217352 -293.975282) (xy 417.217352 -294.49522) (xy 415.718752 -294.49522)
			)
		)
	)
	(zone
		(layer "In2.Cu")
		(hatch none 0.5)
		(connect_pads
			(clearance 0)
		)
		(min_thickness 0.25)
		(keepout
			(tracks not_allowed)
			(vias allowed)
			(pads allowed)
			(copperpour not_allowed)
			(footprints allowed)
		)
		(placement
			(enabled no)
			(sheetname "")
		)
		(fill
			(thermal_gap 0.5)
			(thermal_bridge_width 0.5)
			(island_removal_mode 0)
		)
		(polygon
			(pts
				(xy 16.858742 -276.975316) (xy 18.357342 -276.975316) (xy 18.357342 -277.495254) (xy 16.858742 -277.495254)
			)
		)
	)
	(zone
		(layer "In2.Cu")
		(hatch none 0.5)
		(connect_pads
			(clearance 0)
		)
		(min_thickness 0.25)
		(keepout
			(tracks not_allowed)
			(vias allowed)
			(pads allowed)
			(copperpour not_allowed)
			(footprints allowed)
		)
		(placement
			(enabled no)
			(sheetname "")
		)
		(fill
			(thermal_gap 0.5)
			(thermal_bridge_width 0.5)
			(island_removal_mode 0)
		)
		(polygon
			(pts
				(xy 426.706792 -286.32531) (xy 428.205392 -286.32531) (xy 428.205392 -286.845248) (xy 426.706792 -286.845248)
			)
		)
	)
	(zone
		(layer "In2.Cu")
		(hatch none 0.5)
		(connect_pads
			(clearance 0)
		)
		(min_thickness 0.25)
		(keepout
			(tracks not_allowed)
			(vias allowed)
			(pads allowed)
			(copperpour not_allowed)
			(footprints allowed)
		)
		(placement
			(enabled no)
			(sheetname "")
		)
		(fill
			(thermal_gap 0.5)
			(thermal_bridge_width 0.5)
			(island_removal_mode 0)
		)
		(polygon
			(pts
				(xy 445.894968 -240.425224) (xy 447.393568 -240.425224) (xy 447.393568 -240.945162) (xy 445.894968 -240.945162)
			)
		)
	)
	(zone
		(layer "In2.Cu")
		(hatch none 0.5)
		(connect_pads
			(clearance 0)
		)
		(min_thickness 0.25)
		(keepout
			(tracks not_allowed)
			(vias allowed)
			(pads allowed)
			(copperpour not_allowed)
			(footprints allowed)
		)
		(placement
			(enabled no)
			(sheetname "")
		)
		(fill
			(thermal_gap 0.5)
			(thermal_bridge_width 0.5)
			(island_removal_mode 0)
		)
		(polygon
			(pts
				(xy 24.402542 -311.825132) (xy 25.901142 -311.825132) (xy 25.901142 -312.34507) (xy 24.402542 -312.34507)
			)
		)
	)
	(zone
		(layer "In2.Cu")
		(hatch none 0.5)
		(connect_pads
			(clearance 0)
		)
		(min_thickness 0.25)
		(keepout
			(tracks not_allowed)
			(vias allowed)
			(pads allowed)
			(copperpour not_allowed)
			(footprints allowed)
		)
		(placement
			(enabled no)
			(sheetname "")
		)
		(fill
			(thermal_gap 0.5)
			(thermal_bridge_width 0.5)
			(island_removal_mode 0)
		)
		(polygon
			(pts
				(xy 31.946596 -314.375292) (xy 33.445196 -314.375292) (xy 33.445196 -314.89523) (xy 31.946596 -314.89523)
			)
		)
	)
	(zone
		(layer "In2.Cu")
		(hatch none 0.5)
		(connect_pads
			(clearance 0)
		)
		(min_thickness 0.25)
		(keepout
			(tracks not_allowed)
			(vias allowed)
			(pads allowed)
			(copperpour not_allowed)
			(footprints allowed)
		)
		(placement
			(enabled no)
			(sheetname "")
		)
		(fill
			(thermal_gap 0.5)
			(thermal_bridge_width 0.5)
			(island_removal_mode 0)
		)
		(polygon
			(pts
				(xy 272.342864 -280.375106) (xy 273.841464 -280.375106) (xy 273.841464 -280.895044) (xy 272.342864 -280.895044)
			)
		)
	)
	(zone
		(layer "In2.Cu")
		(hatch none 0.5)
		(connect_pads
			(clearance 0)
		)
		(min_thickness 0.25)
		(keepout
			(tracks not_allowed)
			(vias allowed)
			(pads allowed)
			(copperpour not_allowed)
			(footprints allowed)
		)
		(placement
			(enabled no)
			(sheetname "")
		)
		(fill
			(thermal_gap 0.5)
			(thermal_bridge_width 0.5)
			(island_removal_mode 0)
		)
		(polygon
			(pts
				(xy 272.342864 -244.675152) (xy 273.841464 -244.675152) (xy 273.841464 -245.19509) (xy 272.342864 -245.19509)
			)
		)
	)
	(zone
		(layer "In2.Cu")
		(hatch none 0.5)
		(connect_pads
			(clearance 0)
		)
		(min_thickness 0.25)
		(keepout
			(tracks not_allowed)
			(vias allowed)
			(pads allowed)
			(copperpour not_allowed)
			(footprints allowed)
		)
		(placement
			(enabled no)
			(sheetname "")
		)
		(fill
			(thermal_gap 0.5)
			(thermal_bridge_width 0.5)
			(island_removal_mode 0)
		)
		(polygon
			(pts
				(xy 438.350914 -221.725236) (xy 439.849514 -221.725236) (xy 439.849514 -222.245174) (xy 438.350914 -222.245174)
			)
		)
	)
	(zone
		(layer "In2.Cu")
		(hatch none 0.5)
		(connect_pads
			(clearance 0)
		)
		(min_thickness 0.25)
		(keepout
			(tracks not_allowed)
			(vias allowed)
			(pads allowed)
			(copperpour not_allowed)
			(footprints allowed)
		)
		(placement
			(enabled no)
			(sheetname "")
		)
		(fill
			(thermal_gap 0.5)
			(thermal_bridge_width 0.5)
			(island_removal_mode 0)
		)
		(polygon
			(pts
				(xy 302.518826 -300.775116) (xy 304.017426 -300.775116) (xy 304.017426 -301.295054) (xy 302.518826 -301.295054)
			)
		)
	)
	(zone
		(layer "In2.Cu")
		(hatch none 0.5)
		(connect_pads
			(clearance 0)
		)
		(min_thickness 0.25)
		(keepout
			(tracks not_allowed)
			(vias allowed)
			(pads allowed)
			(copperpour not_allowed)
			(footprints allowed)
		)
		(placement
			(enabled no)
			(sheetname "")
		)
		(fill
			(thermal_gap 0.5)
			(thermal_bridge_width 0.5)
			(island_removal_mode 0)
		)
		(polygon
			(pts
				(xy 426.706792 -251.47524) (xy 428.205392 -251.47524) (xy 428.205392 -251.995178) (xy 426.706792 -251.995178)
			)
		)
	)
	(zone
		(layer "In2.Cu")
		(hatch none 0.5)
		(connect_pads
			(clearance 0)
		)
		(min_thickness 0.25)
		(keepout
			(tracks not_allowed)
			(vias allowed)
			(pads allowed)
			(copperpour not_allowed)
			(footprints allowed)
		)
		(placement
			(enabled no)
			(sheetname "")
		)
		(fill
			(thermal_gap 0.5)
			(thermal_bridge_width 0.5)
			(island_removal_mode 0)
		)
		(polygon
			(pts
				(xy 163.678616 -208.975198) (xy 165.177216 -208.975198) (xy 165.177216 -209.495136) (xy 163.678616 -209.495136)
			)
		)
	)
	(zone
		(layer "In2.Cu")
		(hatch none 0.5)
		(connect_pads
			(clearance 0)
		)
		(min_thickness 0.25)
		(keepout
			(tracks not_allowed)
			(vias allowed)
			(pads allowed)
			(copperpour not_allowed)
			(footprints allowed)
		)
		(placement
			(enabled no)
			(sheetname "")
		)
		(fill
			(thermal_gap 0.5)
			(thermal_bridge_width 0.5)
			(island_removal_mode 0)
		)
		(polygon
			(pts
				(xy 167.778684 -307.575204) (xy 169.277284 -307.575204) (xy 169.277284 -308.095142) (xy 167.778684 -308.095142)
			)
		)
	)
	(zone
		(layer "In2.Cu")
		(hatch none 0.5)
		(connect_pads
			(clearance 0)
		)
		(min_thickness 0.25)
		(keepout
			(tracks not_allowed)
			(vias allowed)
			(pads allowed)
			(copperpour not_allowed)
			(footprints allowed)
		)
		(placement
			(enabled no)
			(sheetname "")
		)
		(fill
			(thermal_gap 0.5)
			(thermal_bridge_width 0.5)
			(island_removal_mode 0)
		)
		(polygon
			(pts
				(xy 197.954646 -279.525222) (xy 199.453246 -279.525222) (xy 199.453246 -280.04516) (xy 197.954646 -280.04516)
			)
		)
	)
	(zone
		(layer "In2.Cu")
		(hatch none 0.5)
		(connect_pads
			(clearance 0)
		)
		(min_thickness 0.25)
		(keepout
			(tracks not_allowed)
			(vias allowed)
			(pads allowed)
			(copperpour not_allowed)
			(footprints allowed)
		)
		(placement
			(enabled no)
			(sheetname "")
		)
		(fill
			(thermal_gap 0.5)
			(thermal_bridge_width 0.5)
			(island_removal_mode 0)
		)
		(polygon
			(pts
				(xy 423.262806 -299.925232) (xy 424.761406 -299.925232) (xy 424.761406 -300.44517) (xy 423.262806 -300.44517)
			)
		)
	)
	(zone
		(layer "In2.Cu")
		(hatch none 0.5)
		(connect_pads
			(clearance 0)
		)
		(min_thickness 0.25)
		(keepout
			(tracks not_allowed)
			(vias allowed)
			(pads allowed)
			(copperpour not_allowed)
			(footprints allowed)
		)
		(placement
			(enabled no)
			(sheetname "")
		)
		(fill
			(thermal_gap 0.5)
			(thermal_bridge_width 0.5)
			(island_removal_mode 0)
		)
		(polygon
			(pts
				(xy 302.518826 -314.375292) (xy 304.017426 -314.375292) (xy 304.017426 -314.89523) (xy 302.518826 -314.89523)
			)
		)
	)
	(zone
		(layer "In2.Cu")
		(hatch none 0.5)
		(connect_pads
			(clearance 0)
		)
		(min_thickness 0.25)
		(keepout
			(tracks not_allowed)
			(vias allowed)
			(pads allowed)
			(copperpour not_allowed)
			(footprints allowed)
		)
		(placement
			(enabled no)
			(sheetname "")
		)
		(fill
			(thermal_gap 0.5)
			(thermal_bridge_width 0.5)
			(island_removal_mode 0)
		)
		(polygon
			(pts
				(xy 279.886664 -213.225126) (xy 281.385264 -213.225126) (xy 281.385264 -213.745064) (xy 279.886664 -213.745064)
			)
		)
	)
	(zone
		(layer "In2.Cu")
		(hatch none 0.5)
		(connect_pads
			(clearance 0)
		)
		(min_thickness 0.25)
		(keepout
			(tracks not_allowed)
			(vias allowed)
			(pads allowed)
			(copperpour not_allowed)
			(footprints allowed)
		)
		(placement
			(enabled no)
			(sheetname "")
		)
		(fill
			(thermal_gap 0.5)
			(thermal_bridge_width 0.5)
			(island_removal_mode 0)
		)
		(polygon
			(pts
				(xy 302.518826 -225.975164) (xy 304.017426 -225.975164) (xy 304.017426 -226.495102) (xy 302.518826 -226.495102)
			)
		)
	)
	(zone
		(layer "In2.Cu")
		(hatch none 0.5)
		(connect_pads
			(clearance 0)
		)
		(min_thickness 0.25)
		(keepout
			(tracks not_allowed)
			(vias allowed)
			(pads allowed)
			(copperpour not_allowed)
			(footprints allowed)
		)
		(placement
			(enabled no)
			(sheetname "")
		)
		(fill
			(thermal_gap 0.5)
			(thermal_bridge_width 0.5)
			(island_removal_mode 0)
		)
		(polygon
			(pts
				(arc
					(start 431.061368 -11.91768)
					(mid 431.03905 -11.971562)
					(end 430.985168 -11.99388)
				)
				(arc
					(start 429.948594 -11.99388)
					(mid 429.894712 -11.971562)
					(end 429.872394 -11.91768)
				)
				(arc
					(start 429.872394 -10.51814)
					(mid 429.894712 -10.464258)
					(end 429.948594 -10.44194)
				)
				(arc
					(start 430.985168 -10.44194)
					(mid 431.03905 -10.464258)
					(end 431.061368 -10.51814)
				)
			)
		)
	)
	(zone
		(layer "In2.Cu")
		(hatch none 0.5)
		(connect_pads
			(clearance 0)
		)
		(min_thickness 0.25)
		(keepout
			(tracks not_allowed)
			(vias allowed)
			(pads allowed)
			(copperpour not_allowed)
			(footprints allowed)
		)
		(placement
			(enabled no)
			(sheetname "")
		)
		(fill
			(thermal_gap 0.5)
			(thermal_bridge_width 0.5)
			(island_removal_mode 0)
		)
		(polygon
			(pts
				(xy 423.262806 -301.625254) (xy 424.761406 -301.625254) (xy 424.761406 -302.145192) (xy 423.262806 -302.145192)
			)
		)
	)
	(zone
		(layer "In2.Cu")
		(hatch none 0.5)
		(connect_pads
			(clearance 0)
		)
		(min_thickness 0.25)
		(keepout
			(tracks not_allowed)
			(vias allowed)
			(pads allowed)
			(copperpour not_allowed)
			(footprints allowed)
		)
		(placement
			(enabled no)
			(sheetname "")
		)
		(fill
			(thermal_gap 0.5)
			(thermal_bridge_width 0.5)
			(island_removal_mode 0)
		)
		(polygon
			(pts
				(xy 302.518826 -241.275108) (xy 304.017426 -241.275108) (xy 304.017426 -241.795046) (xy 302.518826 -241.795046)
			)
		)
	)
	(zone
		(layer "In2.Cu")
		(hatch none 0.5)
		(connect_pads
			(clearance 0)
		)
		(min_thickness 0.25)
		(keepout
			(tracks not_allowed)
			(vias allowed)
			(pads allowed)
			(copperpour not_allowed)
			(footprints allowed)
		)
		(placement
			(enabled no)
			(sheetname "")
		)
		(fill
			(thermal_gap 0.5)
			(thermal_bridge_width 0.5)
			(island_removal_mode 0)
		)
		(polygon
			(pts
				(xy 415.718752 -200.475342) (xy 417.217352 -200.475342) (xy 417.217352 -200.99528) (xy 415.718752 -200.99528)
			)
		)
	)
	(zone
		(layer "In2.Cu")
		(hatch none 0.5)
		(connect_pads
			(clearance 0)
		)
		(min_thickness 0.25)
		(keepout
			(tracks not_allowed)
			(vias allowed)
			(pads allowed)
			(copperpour not_allowed)
			(footprints allowed)
		)
		(placement
			(enabled no)
			(sheetname "")
		)
		(fill
			(thermal_gap 0.5)
			(thermal_bridge_width 0.5)
			(island_removal_mode 0)
		)
		(polygon
			(pts
				(xy 54.578758 -291.425122) (xy 56.077358 -291.425122) (xy 56.077358 -291.94506) (xy 54.578758 -291.94506)
			)
		)
	)
	(zone
		(layer "In2.Cu")
		(hatch none 0.5)
		(connect_pads
			(clearance 0)
		)
		(min_thickness 0.25)
		(keepout
			(tracks not_allowed)
			(vias allowed)
			(pads allowed)
			(copperpour not_allowed)
			(footprints allowed)
		)
		(placement
			(enabled no)
			(sheetname "")
		)
		(fill
			(thermal_gap 0.5)
			(thermal_bridge_width 0.5)
			(island_removal_mode 0)
		)
		(polygon
			(pts
				(xy 197.954646 -284.625288) (xy 199.453246 -284.625288) (xy 199.453246 -285.145226) (xy 197.954646 -285.145226)
			)
		)
	)
	(zone
		(layer "In2.Cu")
		(hatch none 0.5)
		(connect_pads
			(clearance 0)
		)
		(min_thickness 0.25)
		(keepout
			(tracks not_allowed)
			(vias allowed)
			(pads allowed)
			(copperpour not_allowed)
			(footprints allowed)
		)
		(placement
			(enabled no)
			(sheetname "")
		)
		(fill
			(thermal_gap 0.5)
			(thermal_bridge_width 0.5)
			(island_removal_mode 0)
		)
		(polygon
			(pts
				(xy 411.618684 -291.425122) (xy 413.117284 -291.425122) (xy 413.117284 -291.94506) (xy 411.618684 -291.94506)
			)
		)
	)
	(zone
		(layer "In2.Cu")
		(hatch none 0.5)
		(connect_pads
			(clearance 0)
		)
		(min_thickness 0.25)
		(keepout
			(tracks not_allowed)
			(vias allowed)
			(pads allowed)
			(copperpour not_allowed)
			(footprints allowed)
		)
		(placement
			(enabled no)
			(sheetname "")
		)
		(fill
			(thermal_gap 0.5)
			(thermal_bridge_width 0.5)
			(island_removal_mode 0)
		)
		(polygon
			(pts
				(xy 411.618684 -207.275176) (xy 413.117284 -207.275176) (xy 413.117284 -207.795114) (xy 411.618684 -207.795114)
			)
		)
	)
	(zone
		(layer "In2.Cu")
		(hatch none 0.5)
		(connect_pads
			(clearance 0)
		)
		(min_thickness 0.25)
		(keepout
			(tracks allowed)
			(vias allowed)
			(pads allowed)
			(copperpour allowed)
			(footprints allowed)
		)
		(placement
			(enabled no)
			(sheetname "")
		)
		(fill
			(thermal_gap 0.5)
			(thermal_bridge_width 0.5)
			(island_removal_mode 0)
		)
		(polygon
			(pts
				(xy 336.48777 -337.374992) (xy 336.48777 -336.752692) (xy 337.03895 -336.752692) (xy 337.03895 -337.374992)
			)
		)
	)
	(zone
		(layer "In2.Cu")
		(hatch none 0.5)
		(connect_pads
			(clearance 0)
		)
		(min_thickness 0.25)
		(keepout
			(tracks not_allowed)
			(vias allowed)
			(pads allowed)
			(copperpour not_allowed)
			(footprints allowed)
		)
		(placement
			(enabled no)
			(sheetname "")
		)
		(fill
			(thermal_gap 0.5)
			(thermal_bridge_width 0.5)
			(island_removal_mode 0)
		)
		(polygon
			(pts
				(xy 441.7949 -203.875132) (xy 443.2935 -203.875132) (xy 443.2935 -204.39507) (xy 441.7949 -204.39507)
			)
		)
	)
	(zone
		(layer "In2.Cu")
		(hatch none 0.5)
		(connect_pads
			(clearance 0)
		)
		(min_thickness 0.25)
		(keepout
			(tracks not_allowed)
			(vias allowed)
			(pads allowed)
			(copperpour not_allowed)
			(footprints allowed)
		)
		(placement
			(enabled no)
			(sheetname "")
		)
		(fill
			(thermal_gap 0.5)
			(thermal_bridge_width 0.5)
			(island_removal_mode 0)
		)
		(polygon
			(pts
				(xy 197.954646 -234.475274) (xy 199.453246 -234.475274) (xy 199.453246 -234.995212) (xy 197.954646 -234.995212)
			)
		)
	)
	(zone
		(layer "In2.Cu")
		(hatch none 0.5)
		(connect_pads
			(clearance 0)
		)
		(min_thickness 0.25)
		(keepout
			(tracks not_allowed)
			(vias allowed)
			(pads allowed)
			(copperpour not_allowed)
			(footprints allowed)
		)
		(placement
			(enabled no)
			(sheetname "")
		)
		(fill
			(thermal_gap 0.5)
			(thermal_bridge_width 0.5)
			(island_removal_mode 0)
		)
		(polygon
			(pts
				(xy 415.718752 -262.525256) (xy 417.217352 -262.525256) (xy 417.217352 -263.045194) (xy 415.718752 -263.045194)
			)
		)
	)
	(zone
		(layer "In2.Cu")
		(hatch none 0.5)
		(connect_pads
			(clearance 0)
		)
		(min_thickness 0.25)
		(keepout
			(tracks not_allowed)
			(vias allowed)
			(pads allowed)
			(copperpour not_allowed)
			(footprints allowed)
		)
		(placement
			(enabled no)
			(sheetname "")
		)
		(fill
			(thermal_gap 0.5)
			(thermal_bridge_width 0.5)
			(island_removal_mode 0)
		)
		(polygon
			(pts
				(xy 453.438768 -301.625254) (xy 454.937368 -301.625254) (xy 454.937368 -302.145192) (xy 453.438768 -302.145192)
			)
		)
	)
	(zone
		(layer "In2.Cu")
		(hatch none 0.5)
		(connect_pads
			(clearance 0)
		)
		(min_thickness 0.25)
		(keepout
			(tracks not_allowed)
			(vias allowed)
			(pads allowed)
			(copperpour not_allowed)
			(footprints allowed)
		)
		(placement
			(enabled no)
			(sheetname "")
		)
		(fill
			(thermal_gap 0.5)
			(thermal_bridge_width 0.5)
			(island_removal_mode 0)
		)
		(polygon
			(pts
				(xy 423.262806 -238.725202) (xy 424.761406 -238.725202) (xy 424.761406 -239.24514) (xy 423.262806 -239.24514)
			)
		)
	)
	(zone
		(layer "In2.Cu")
		(hatch none 0.5)
		(connect_pads
			(clearance 0)
		)
		(min_thickness 0.25)
		(keepout
			(tracks not_allowed)
			(vias allowed)
			(pads allowed)
			(copperpour not_allowed)
			(footprints allowed)
		)
		(placement
			(enabled no)
			(sheetname "")
		)
		(fill
			(thermal_gap 0.5)
			(thermal_bridge_width 0.5)
			(island_removal_mode 0)
		)
		(polygon
			(pts
				(xy 163.678616 -225.975164) (xy 165.177216 -225.975164) (xy 165.177216 -226.495102) (xy 163.678616 -226.495102)
			)
		)
	)
	(zone
		(layer "In2.Cu")
		(hatch none 0.5)
		(connect_pads
			(clearance 0)
		)
		(min_thickness 0.25)
		(keepout
			(tracks not_allowed)
			(vias allowed)
			(pads allowed)
			(copperpour not_allowed)
			(footprints allowed)
		)
		(placement
			(enabled no)
			(sheetname "")
		)
		(fill
			(thermal_gap 0.5)
			(thermal_bridge_width 0.5)
			(island_removal_mode 0)
		)
		(polygon
			(pts
				(xy 430.80686 -254.025146) (xy 432.30546 -254.025146) (xy 432.30546 -254.545084) (xy 430.80686 -254.545084)
			)
		)
	)
	(zone
		(layer "In2.Cu")
		(hatch none 0.5)
		(connect_pads
			(clearance 0)
		)
		(min_thickness 0.25)
		(keepout
			(tracks not_allowed)
			(vias allowed)
			(pads allowed)
			(copperpour not_allowed)
			(footprints allowed)
		)
		(placement
			(enabled no)
			(sheetname "")
		)
		(fill
			(thermal_gap 0.5)
			(thermal_bridge_width 0.5)
			(island_removal_mode 0)
		)
		(polygon
			(pts
				(xy 175.322738 -250.625102) (xy 176.821338 -250.625102) (xy 176.821338 -251.14504) (xy 175.322738 -251.14504)
			)
		)
	)
	(zone
		(layer "In2.Cu")
		(hatch none 0.5)
		(connect_pads
			(clearance 0)
		)
		(min_thickness 0.25)
		(keepout
			(tracks not_allowed)
			(vias allowed)
			(pads allowed)
			(copperpour not_allowed)
			(footprints allowed)
		)
		(placement
			(enabled no)
			(sheetname "")
		)
		(fill
			(thermal_gap 0.5)
			(thermal_bridge_width 0.5)
			(island_removal_mode 0)
		)
		(polygon
			(pts
				(xy 283.986732 -298.22521) (xy 285.485332 -298.22521) (xy 285.485332 -298.745148) (xy 283.986732 -298.745148)
			)
		)
	)
	(zone
		(layer "In2.Cu")
		(hatch none 0.5)
		(connect_pads
			(clearance 0)
		)
		(min_thickness 0.25)
		(keepout
			(tracks not_allowed)
			(vias allowed)
			(pads allowed)
			(copperpour not_allowed)
			(footprints allowed)
		)
		(placement
			(enabled no)
			(sheetname "")
		)
		(fill
			(thermal_gap 0.5)
			(thermal_bridge_width 0.5)
			(island_removal_mode 0)
		)
		(polygon
			(pts
				(xy 197.954646 -299.925232) (xy 199.453246 -299.925232) (xy 199.453246 -300.44517) (xy 197.954646 -300.44517)
			)
		)
	)
	(zone
		(layer "In2.Cu")
		(hatch none 0.5)
		(connect_pads
			(clearance 0)
		)
		(min_thickness 0.25)
		(keepout
			(tracks not_allowed)
			(vias allowed)
			(pads allowed)
			(copperpour not_allowed)
			(footprints allowed)
		)
		(placement
			(enabled no)
			(sheetname "")
		)
		(fill
			(thermal_gap 0.5)
			(thermal_bridge_width 0.5)
			(island_removal_mode 0)
		)
		(polygon
			(pts
				(xy 294.974772 -295.675304) (xy 296.473372 -295.675304) (xy 296.473372 -296.195242) (xy 294.974772 -296.195242)
			)
		)
	)
	(zone
		(layer "In2.Cu")
		(hatch none 0.5)
		(connect_pads
			(clearance 0)
		)
		(min_thickness 0.25)
		(keepout
			(tracks not_allowed)
			(vias allowed)
			(pads allowed)
			(copperpour not_allowed)
			(footprints allowed)
		)
		(placement
			(enabled no)
			(sheetname "")
		)
		(fill
			(thermal_gap 0.5)
			(thermal_bridge_width 0.5)
			(island_removal_mode 0)
		)
		(polygon
			(pts
				(xy 36.046664 -276.125178) (xy 37.545264 -276.125178) (xy 37.545264 -276.645116) (xy 36.046664 -276.645116)
			)
		)
	)
	(zone
		(layer "In2.Cu")
		(hatch none 0.5)
		(connect_pads
			(clearance 0)
		)
		(min_thickness 0.25)
		(keepout
			(tracks not_allowed)
			(vias allowed)
			(pads allowed)
			(copperpour not_allowed)
			(footprints allowed)
		)
		(placement
			(enabled no)
			(sheetname "")
		)
		(fill
			(thermal_gap 0.5)
			(thermal_bridge_width 0.5)
			(island_removal_mode 0)
		)
		(polygon
			(pts
				(xy 167.778684 -303.325276) (xy 169.277284 -303.325276) (xy 169.277284 -303.845214) (xy 167.778684 -303.845214)
			)
		)
	)
	(zone
		(layer "In2.Cu")
		(hatch none 0.5)
		(connect_pads
			(clearance 0)
		)
		(min_thickness 0.25)
		(keepout
			(tracks not_allowed)
			(vias allowed)
			(pads allowed)
			(copperpour not_allowed)
			(footprints allowed)
		)
		(placement
			(enabled no)
			(sheetname "")
		)
		(fill
			(thermal_gap 0.5)
			(thermal_bridge_width 0.5)
			(island_removal_mode 0)
		)
		(polygon
			(pts
				(xy 171.22267 -237.02518) (xy 172.72127 -237.02518) (xy 172.72127 -237.545118) (xy 171.22267 -237.545118)
			)
		)
	)
	(zone
		(layer "In2.Cu")
		(hatch none 0.5)
		(connect_pads
			(clearance 0)
		)
		(min_thickness 0.25)
		(keepout
			(tracks not_allowed)
			(vias allowed)
			(pads allowed)
			(copperpour not_allowed)
			(footprints allowed)
		)
		(placement
			(enabled no)
			(sheetname "")
		)
		(fill
			(thermal_gap 0.5)
			(thermal_bridge_width 0.5)
			(island_removal_mode 0)
		)
		(polygon
			(pts
				(xy 283.986732 -210.67522) (xy 285.485332 -210.67522) (xy 285.485332 -211.195158) (xy 283.986732 -211.195158)
			)
		)
	)
	(zone
		(layer "In2.Cu")
		(hatch none 0.5)
		(connect_pads
			(clearance 0)
		)
		(min_thickness 0.25)
		(keepout
			(tracks not_allowed)
			(vias allowed)
			(pads allowed)
			(copperpour not_allowed)
			(footprints allowed)
		)
		(placement
			(enabled no)
			(sheetname "")
		)
		(fill
			(thermal_gap 0.5)
			(thermal_bridge_width 0.5)
			(island_removal_mode 0)
		)
		(polygon
			(pts
				(xy 193.854578 -216.62517) (xy 195.353178 -216.62517) (xy 195.353178 -217.145108) (xy 193.854578 -217.145108)
			)
		)
	)
	(zone
		(layer "In2.Cu")
		(hatch none 0.5)
		(connect_pads
			(clearance 0)
		)
		(min_thickness 0.25)
		(keepout
			(tracks not_allowed)
			(vias allowed)
			(pads allowed)
			(copperpour not_allowed)
			(footprints allowed)
		)
		(placement
			(enabled no)
			(sheetname "")
		)
		(fill
			(thermal_gap 0.5)
			(thermal_bridge_width 0.5)
			(island_removal_mode 0)
		)
		(polygon
			(pts
				(xy 190.410846 -225.12528) (xy 191.909446 -225.12528) (xy 191.909446 -225.645218) (xy 190.410846 -225.645218)
			)
		)
	)
	(zone
		(layer "In2.Cu")
		(hatch none 0.5)
		(connect_pads
			(clearance 0)
		)
		(min_thickness 0.25)
		(keepout
			(tracks not_allowed)
			(vias allowed)
			(pads allowed)
			(copperpour not_allowed)
			(footprints allowed)
		)
		(placement
			(enabled no)
			(sheetname "")
		)
		(fill
			(thermal_gap 0.5)
			(thermal_bridge_width 0.5)
			(island_removal_mode 0)
		)
		(polygon
			(pts
				(xy 272.342864 -205.575154) (xy 273.841464 -205.575154) (xy 273.841464 -206.095092) (xy 272.342864 -206.095092)
			)
		)
	)
	(zone
		(layer "In2.Cu")
		(hatch none 0.5)
		(connect_pads
			(clearance 0)
		)
		(min_thickness 0.25)
		(keepout
			(tracks not_allowed)
			(vias allowed)
			(pads allowed)
			(copperpour not_allowed)
			(footprints allowed)
		)
		(placement
			(enabled no)
			(sheetname "")
		)
		(fill
			(thermal_gap 0.5)
			(thermal_bridge_width 0.5)
			(island_removal_mode 0)
		)
		(polygon
			(pts
				(xy 20.95881 -242.125246) (xy 22.45741 -242.125246) (xy 22.45741 -242.645184) (xy 20.95881 -242.645184)
			)
		)
	)
	(zone
		(layer "In2.Cu")
		(hatch none 0.5)
		(connect_pads
			(clearance 0)
		)
		(min_thickness 0.25)
		(keepout
			(tracks not_allowed)
			(vias allowed)
			(pads allowed)
			(copperpour not_allowed)
			(footprints allowed)
		)
		(placement
			(enabled no)
			(sheetname "")
		)
		(fill
			(thermal_gap 0.5)
			(thermal_bridge_width 0.5)
			(island_removal_mode 0)
		)
		(polygon
			(pts
				(xy 171.22267 -244.675152) (xy 172.72127 -244.675152) (xy 172.72127 -245.19509) (xy 171.22267 -245.19509)
			)
		)
	)
	(zone
		(layer "In2.Cu")
		(hatch none 0.5)
		(connect_pads
			(clearance 0)
		)
		(min_thickness 0.25)
		(keepout
			(tracks not_allowed)
			(vias allowed)
			(pads allowed)
			(copperpour not_allowed)
			(footprints allowed)
		)
		(placement
			(enabled no)
			(sheetname "")
		)
		(fill
			(thermal_gap 0.5)
			(thermal_bridge_width 0.5)
			(island_removal_mode 0)
		)
		(polygon
			(pts
				(xy 423.262806 -282.925266) (xy 424.761406 -282.925266) (xy 424.761406 -283.445204) (xy 423.262806 -283.445204)
			)
		)
	)
	(zone
		(layer "In2.Cu")
		(hatch none 0.5)
		(connect_pads
			(clearance 0)
		)
		(min_thickness 0.25)
		(keepout
			(tracks not_allowed)
			(vias allowed)
			(pads allowed)
			(copperpour not_allowed)
			(footprints allowed)
		)
		(placement
			(enabled no)
			(sheetname "")
		)
		(fill
			(thermal_gap 0.5)
			(thermal_bridge_width 0.5)
			(island_removal_mode 0)
		)
		(polygon
			(pts
				(xy 58.678826 -201.325226) (xy 60.177426 -201.325226) (xy 60.177426 -201.845164) (xy 58.678826 -201.845164)
			)
		)
	)
	(zone
		(layer "In2.Cu")
		(hatch none 0.5)
		(connect_pads
			(clearance 0)
		)
		(min_thickness 0.25)
		(keepout
			(tracks not_allowed)
			(vias allowed)
			(pads allowed)
			(copperpour not_allowed)
			(footprints allowed)
		)
		(placement
			(enabled no)
			(sheetname "")
		)
		(fill
			(thermal_gap 0.5)
			(thermal_bridge_width 0.5)
			(island_removal_mode 0)
		)
		(polygon
			(pts
				(xy 430.80686 -312.67527) (xy 432.30546 -312.67527) (xy 432.30546 -313.195208) (xy 430.80686 -313.195208)
			)
		)
	)
	(zone
		(layer "In2.Cu")
		(hatch none 0.5)
		(connect_pads
			(clearance 0)
		)
		(min_thickness 0.25)
		(keepout
			(tracks not_allowed)
			(vias allowed)
			(pads allowed)
			(copperpour not_allowed)
			(footprints allowed)
		)
		(placement
			(enabled no)
			(sheetname "")
		)
		(fill
			(thermal_gap 0.5)
			(thermal_bridge_width 0.5)
			(island_removal_mode 0)
		)
		(polygon
			(pts
				(xy 441.7949 -248.075196) (xy 443.2935 -248.075196) (xy 443.2935 -248.595134) (xy 441.7949 -248.595134)
			)
		)
	)
	(zone
		(layer "In2.Cu")
		(hatch none 0.5)
		(connect_pads
			(clearance 0)
		)
		(min_thickness 0.25)
		(keepout
			(tracks not_allowed)
			(vias allowed)
			(pads allowed)
			(copperpour not_allowed)
			(footprints allowed)
		)
		(placement
			(enabled no)
			(sheetname "")
		)
		(fill
			(thermal_gap 0.5)
			(thermal_bridge_width 0.5)
			(island_removal_mode 0)
		)
		(polygon
			(pts
				(xy 299.07484 -197.075298) (xy 300.57344 -197.075298) (xy 300.57344 -197.595236) (xy 299.07484 -197.595236)
			)
		)
	)
	(zone
		(layer "In2.Cu")
		(hatch none 0.5)
		(connect_pads
			(clearance 0)
		)
		(min_thickness 0.25)
		(keepout
			(tracks not_allowed)
			(vias allowed)
			(pads allowed)
			(copperpour not_allowed)
			(footprints allowed)
		)
		(placement
			(enabled no)
			(sheetname "")
		)
		(fill
			(thermal_gap 0.5)
			(thermal_bridge_width 0.5)
			(island_removal_mode 0)
		)
		(polygon
			(pts
				(xy 276.442932 -265.9253) (xy 277.941532 -265.9253) (xy 277.941532 -266.445238) (xy 276.442932 -266.445238)
			)
		)
	)
	(zone
		(layer "In2.Cu")
		(hatch none 0.5)
		(connect_pads
			(clearance 0)
		)
		(min_thickness 0.25)
		(keepout
			(tracks not_allowed)
			(vias allowed)
			(pads allowed)
			(copperpour not_allowed)
			(footprints allowed)
		)
		(placement
			(enabled no)
			(sheetname "")
		)
		(fill
			(thermal_gap 0.5)
			(thermal_bridge_width 0.5)
			(island_removal_mode 0)
		)
		(polygon
			(pts
				(xy 445.894968 -242.125246) (xy 447.393568 -242.125246) (xy 447.393568 -242.645184) (xy 445.894968 -242.645184)
			)
		)
	)
	(zone
		(layer "In2.Cu")
		(hatch none 0.5)
		(connect_pads
			(clearance 0)
		)
		(min_thickness 0.25)
		(keepout
			(tracks not_allowed)
			(vias allowed)
			(pads allowed)
			(copperpour not_allowed)
			(footprints allowed)
		)
		(placement
			(enabled no)
			(sheetname "")
		)
		(fill
			(thermal_gap 0.5)
			(thermal_bridge_width 0.5)
			(island_removal_mode 0)
		)
		(polygon
			(pts
				(xy 438.350914 -294.825166) (xy 439.849514 -294.825166) (xy 439.849514 -295.345104) (xy 438.350914 -295.345104)
			)
		)
	)
	(zone
		(layer "In2.Cu")
		(hatch none 0.5)
		(connect_pads
			(clearance 0)
		)
		(min_thickness 0.25)
		(keepout
			(tracks not_allowed)
			(vias allowed)
			(pads allowed)
			(copperpour not_allowed)
			(footprints allowed)
		)
		(placement
			(enabled no)
			(sheetname "")
		)
		(fill
			(thermal_gap 0.5)
			(thermal_bridge_width 0.5)
			(island_removal_mode 0)
		)
		(polygon
			(pts
				(xy 28.50261 -245.52529) (xy 30.00121 -245.52529) (xy 30.00121 -246.045228) (xy 28.50261 -246.045228)
			)
		)
	)
	(zone
		(layer "In2.Cu")
		(hatch none 0.5)
		(connect_pads
			(clearance 0)
		)
		(min_thickness 0.25)
		(keepout
			(tracks not_allowed)
			(vias allowed)
			(pads allowed)
			(copperpour not_allowed)
			(footprints allowed)
		)
		(placement
			(enabled no)
			(sheetname "")
		)
		(fill
			(thermal_gap 0.5)
			(thermal_bridge_width 0.5)
			(island_removal_mode 0)
		)
		(polygon
			(pts
				(xy 36.046664 -301.625254) (xy 37.545264 -301.625254) (xy 37.545264 -302.145192) (xy 36.046664 -302.145192)
			)
		)
	)
	(zone
		(layer "In2.Cu")
		(hatch none 0.5)
		(connect_pads
			(clearance 0)
		)
		(min_thickness 0.25)
		(keepout
			(tracks not_allowed)
			(vias allowed)
			(pads allowed)
			(copperpour not_allowed)
			(footprints allowed)
		)
		(placement
			(enabled no)
			(sheetname "")
		)
		(fill
			(thermal_gap 0.5)
			(thermal_bridge_width 0.5)
			(island_removal_mode 0)
		)
		(polygon
			(pts
				(xy 302.518826 -295.675304) (xy 304.017426 -295.675304) (xy 304.017426 -296.195242) (xy 302.518826 -296.195242)
			)
		)
	)
	(zone
		(layer "In2.Cu")
		(hatch none 0.5)
		(connect_pads
			(clearance 0)
		)
		(min_thickness 0.25)
		(keepout
			(tracks not_allowed)
			(vias allowed)
			(pads allowed)
			(copperpour not_allowed)
			(footprints allowed)
		)
		(placement
			(enabled no)
			(sheetname "")
		)
		(fill
			(thermal_gap 0.5)
			(thermal_bridge_width 0.5)
			(island_removal_mode 0)
		)
		(polygon
			(pts
				(xy 186.310778 -293.125144) (xy 187.809378 -293.125144) (xy 187.809378 -293.645082) (xy 186.310778 -293.645082)
			)
		)
	)
	(zone
		(layer "In2.Cu")
		(hatch none 0.5)
		(connect_pads
			(clearance 0)
		)
		(min_thickness 0.25)
		(keepout
			(tracks not_allowed)
			(vias allowed)
			(pads allowed)
			(copperpour not_allowed)
			(footprints allowed)
		)
		(placement
			(enabled no)
			(sheetname "")
		)
		(fill
			(thermal_gap 0.5)
			(thermal_bridge_width 0.5)
			(island_removal_mode 0)
		)
		(polygon
			(pts
				(xy 291.530786 -304.17516) (xy 293.029386 -304.17516) (xy 293.029386 -304.695098) (xy 291.530786 -304.695098)
			)
		)
	)
	(zone
		(layer "In2.Cu")
		(hatch none 0.5)
		(connect_pads
			(clearance 0)
		)
		(min_thickness 0.25)
		(keepout
			(tracks not_allowed)
			(vias allowed)
			(pads allowed)
			(copperpour not_allowed)
			(footprints allowed)
		)
		(placement
			(enabled no)
			(sheetname "")
		)
		(fill
			(thermal_gap 0.5)
			(thermal_bridge_width 0.5)
			(island_removal_mode 0)
		)
		(polygon
			(pts
				(xy 449.3387 -242.97513) (xy 450.8373 -242.97513) (xy 450.8373 -243.495068) (xy 449.3387 -243.495068)
			)
		)
	)
	(zone
		(layer "In2.Cu")
		(hatch none 0.5)
		(connect_pads
			(clearance 0)
		)
		(min_thickness 0.25)
		(keepout
			(tracks not_allowed)
			(vias allowed)
			(pads allowed)
			(copperpour not_allowed)
			(footprints allowed)
		)
		(placement
			(enabled no)
			(sheetname "")
		)
		(fill
			(thermal_gap 0.5)
			(thermal_bridge_width 0.5)
			(island_removal_mode 0)
		)
		(polygon
			(pts
				(xy 426.706792 -294.825166) (xy 428.205392 -294.825166) (xy 428.205392 -295.345104) (xy 426.706792 -295.345104)
			)
		)
	)
	(zone
		(layer "In2.Cu")
		(hatch none 0.5)
		(connect_pads
			(clearance 0)
		)
		(min_thickness 0.25)
		(keepout
			(tracks not_allowed)
			(vias allowed)
			(pads allowed)
			(copperpour not_allowed)
			(footprints allowed)
		)
		(placement
			(enabled no)
			(sheetname "")
		)
		(fill
			(thermal_gap 0.5)
			(thermal_bridge_width 0.5)
			(island_removal_mode 0)
		)
		(polygon
			(pts
				(xy 449.3387 -220.025214) (xy 450.8373 -220.025214) (xy 450.8373 -220.545152) (xy 449.3387 -220.545152)
			)
		)
	)
	(zone
		(layer "In2.Cu")
		(hatch none 0.5)
		(connect_pads
			(clearance 0)
		)
		(min_thickness 0.25)
		(keepout
			(tracks not_allowed)
			(vias allowed)
			(pads allowed)
			(copperpour not_allowed)
			(footprints allowed)
		)
		(placement
			(enabled no)
			(sheetname "")
		)
		(fill
			(thermal_gap 0.5)
			(thermal_bridge_width 0.5)
			(island_removal_mode 0)
		)
		(polygon
			(pts
				(xy 51.134772 -254.025146) (xy 52.633372 -254.025146) (xy 52.633372 -254.545084) (xy 51.134772 -254.545084)
			)
		)
	)
	(zone
		(layer "In2.Cu")
		(hatch none 0.5)
		(connect_pads
			(clearance 0)
		)
		(min_thickness 0.25)
		(keepout
			(tracks not_allowed)
			(vias allowed)
			(pads allowed)
			(copperpour not_allowed)
			(footprints allowed)
		)
		(placement
			(enabled no)
			(sheetname "")
		)
		(fill
			(thermal_gap 0.5)
			(thermal_bridge_width 0.5)
			(island_removal_mode 0)
		)
		(polygon
			(pts
				(xy 51.134772 -231.07523) (xy 52.633372 -231.07523) (xy 52.633372 -231.595168) (xy 51.134772 -231.595168)
			)
		)
	)
	(zone
		(layer "In2.Cu")
		(hatch none 0.5)
		(connect_pads
			(clearance 0)
		)
		(min_thickness 0.25)
		(keepout
			(tracks not_allowed)
			(vias allowed)
			(pads allowed)
			(copperpour not_allowed)
			(footprints allowed)
		)
		(placement
			(enabled no)
			(sheetname "")
		)
		(fill
			(thermal_gap 0.5)
			(thermal_bridge_width 0.5)
			(island_removal_mode 0)
		)
		(polygon
			(pts
				(arc
					(start 298.56049 -385.11861)
					(mid 298.551254 -385.138534)
					(end 298.548044 -385.160266)
				)
				(arc
					(start 298.548044 -385.35483)
					(mid 298.570362 -385.408712)
					(end 298.624244 -385.43103)
				)
				(arc
					(start 299.310044 -385.43103)
					(mid 299.363926 -385.408712)
					(end 299.386244 -385.35483)
				)
				(arc
					(start 299.386244 -385.160266)
					(mid 299.383076 -385.138522)
					(end 299.373798 -385.11861)
				)
				(arc
					(start 299.181012 -384.822446)
					(mid 299.16879 -384.780762)
					(end 299.181266 -384.739134)
				)
				(arc
					(start 299.373798 -384.44551)
					(mid 299.383034 -384.425586)
					(end 299.386244 -384.403854)
				)
				(arc
					(start 299.386244 -384.20929)
					(mid 299.363926 -384.155408)
					(end 299.310044 -384.13309)
				)
				(arc
					(start 298.624244 -384.13309)
					(mid 298.570362 -384.155408)
					(end 298.548044 -384.20929)
				)
				(arc
					(start 298.548044 -384.405124)
					(mid 298.551212 -384.426868)
					(end 298.56049 -384.44678)
				)
				(arc
					(start 298.753022 -384.740404)
					(mid 298.765424 -384.78206)
					(end 298.753022 -384.823716)
				)
			)
		)
	)
	(zone
		(layer "In2.Cu")
		(hatch none 0.5)
		(connect_pads
			(clearance 0)
		)
		(min_thickness 0.25)
		(keepout
			(tracks not_allowed)
			(vias allowed)
			(pads allowed)
			(copperpour not_allowed)
			(footprints allowed)
		)
		(placement
			(enabled no)
			(sheetname "")
		)
		(fill
			(thermal_gap 0.5)
			(thermal_bridge_width 0.5)
			(island_removal_mode 0)
		)
		(polygon
			(pts
				(xy 423.262806 -294.825166) (xy 424.761406 -294.825166) (xy 424.761406 -295.345104) (xy 423.262806 -295.345104)
			)
		)
	)
	(zone
		(layer "In2.Cu")
		(hatch none 0.5)
		(connect_pads
			(clearance 0)
		)
		(min_thickness 0.25)
		(keepout
			(tracks not_allowed)
			(vias allowed)
			(pads allowed)
			(copperpour not_allowed)
			(footprints allowed)
		)
		(placement
			(enabled no)
			(sheetname "")
		)
		(fill
			(thermal_gap 0.5)
			(thermal_bridge_width 0.5)
			(island_removal_mode 0)
		)
		(polygon
			(pts
				(xy 279.886664 -313.525154) (xy 281.385264 -313.525154) (xy 281.385264 -314.045092) (xy 279.886664 -314.045092)
			)
		)
	)
	(zone
		(layer "In2.Cu")
		(hatch none 0.5)
		(connect_pads
			(clearance 0)
		)
		(min_thickness 0.25)
		(keepout
			(tracks not_allowed)
			(vias allowed)
			(pads allowed)
			(copperpour not_allowed)
			(footprints allowed)
		)
		(placement
			(enabled no)
			(sheetname "")
		)
		(fill
			(thermal_gap 0.5)
			(thermal_bridge_width 0.5)
			(island_removal_mode 0)
		)
		(polygon
			(pts
				(xy 426.706792 -316.075314) (xy 428.205392 -316.075314) (xy 428.205392 -316.595252) (xy 426.706792 -316.595252)
			)
		)
	)
	(zone
		(layer "In2.Cu")
		(hatch none 0.5)
		(connect_pads
			(clearance 0)
		)
		(min_thickness 0.25)
		(keepout
			(tracks allowed)
			(vias allowed)
			(pads allowed)
			(copperpour allowed)
			(footprints allowed)
		)
		(placement
			(enabled no)
			(sheetname "")
		)
		(fill
			(thermal_gap 0.5)
			(thermal_bridge_width 0.5)
			(island_removal_mode 0)
		)
		(polygon
			(pts
				(xy 416.974528 -161.170874) (xy 416.974528 -160.62452) (xy 417.526978 -160.62452) (xy 417.526978 -161.170874)
			)
		)
	)
	(zone
		(layer "In2.Cu")
		(hatch none 0.5)
		(connect_pads
			(clearance 0)
		)
		(min_thickness 0.25)
		(keepout
			(tracks not_allowed)
			(vias allowed)
			(pads allowed)
			(copperpour not_allowed)
			(footprints allowed)
		)
		(placement
			(enabled no)
			(sheetname "")
		)
		(fill
			(thermal_gap 0.5)
			(thermal_bridge_width 0.5)
			(island_removal_mode 0)
		)
		(polygon
			(pts
				(xy 299.07484 -275.275294) (xy 300.57344 -275.275294) (xy 300.57344 -275.795232) (xy 299.07484 -275.795232)
			)
		)
	)
	(zone
		(layer "In2.Cu")
		(hatch none 0.5)
		(connect_pads
			(clearance 0)
		)
		(min_thickness 0.25)
		(keepout
			(tracks not_allowed)
			(vias allowed)
			(pads allowed)
			(copperpour not_allowed)
			(footprints allowed)
		)
		(placement
			(enabled no)
			(sheetname "")
		)
		(fill
			(thermal_gap 0.5)
			(thermal_bridge_width 0.5)
			(island_removal_mode 0)
		)
		(polygon
			(pts
				(xy 276.442932 -240.425224) (xy 277.941532 -240.425224) (xy 277.941532 -240.945162) (xy 276.442932 -240.945162)
			)
		)
	)
	(zone
		(layer "In2.Cu")
		(hatch none 0.5)
		(connect_pads
			(clearance 0)
		)
		(min_thickness 0.25)
		(keepout
			(tracks not_allowed)
			(vias allowed)
			(pads allowed)
			(copperpour not_allowed)
			(footprints allowed)
		)
		(placement
			(enabled no)
			(sheetname "")
		)
		(fill
			(thermal_gap 0.5)
			(thermal_bridge_width 0.5)
			(island_removal_mode 0)
		)
		(polygon
			(pts
				(xy 302.518826 -293.125144) (xy 304.017426 -293.125144) (xy 304.017426 -293.645082) (xy 302.518826 -293.645082)
			)
		)
	)
	(zone
		(layer "In2.Cu")
		(hatch none 0.5)
		(connect_pads
			(clearance 0)
		)
		(min_thickness 0.25)
		(keepout
			(tracks not_allowed)
			(vias allowed)
			(pads allowed)
			(copperpour not_allowed)
			(footprints allowed)
		)
		(placement
			(enabled no)
			(sheetname "")
		)
		(fill
			(thermal_gap 0.5)
			(thermal_bridge_width 0.5)
			(island_removal_mode 0)
		)
		(polygon
			(pts
				(xy 268.898878 -226.825302) (xy 270.397478 -226.825302) (xy 270.397478 -227.34524) (xy 268.898878 -227.34524)
			)
		)
	)
	(zone
		(layer "In2.Cu")
		(hatch none 0.5)
		(connect_pads
			(clearance 0)
		)
		(min_thickness 0.25)
		(keepout
			(tracks not_allowed)
			(vias allowed)
			(pads allowed)
			(copperpour not_allowed)
			(footprints allowed)
		)
		(placement
			(enabled no)
			(sheetname "")
		)
		(fill
			(thermal_gap 0.5)
			(thermal_bridge_width 0.5)
			(island_removal_mode 0)
		)
		(polygon
			(pts
				(xy 175.322738 -307.575204) (xy 176.821338 -307.575204) (xy 176.821338 -308.095142) (xy 175.322738 -308.095142)
			)
		)
	)
	(zone
		(layer "In2.Cu")
		(hatch none 0.5)
		(connect_pads
			(clearance 0)
		)
		(min_thickness 0.25)
		(keepout
			(tracks not_allowed)
			(vias allowed)
			(pads allowed)
			(copperpour not_allowed)
			(footprints allowed)
		)
		(placement
			(enabled no)
			(sheetname "")
		)
		(fill
			(thermal_gap 0.5)
			(thermal_bridge_width 0.5)
			(island_removal_mode 0)
		)
		(polygon
			(pts
				(xy 171.22267 -316.075314) (xy 172.72127 -316.075314) (xy 172.72127 -316.595252) (xy 171.22267 -316.595252)
			)
		)
	)
	(zone
		(layer "In2.Cu")
		(hatch none 0.5)
		(connect_pads
			(clearance 0)
		)
		(min_thickness 0.25)
		(keepout
			(tracks not_allowed)
			(vias allowed)
			(pads allowed)
			(copperpour not_allowed)
			(footprints allowed)
		)
		(placement
			(enabled no)
			(sheetname "")
		)
		(fill
			(thermal_gap 0.5)
			(thermal_bridge_width 0.5)
			(island_removal_mode 0)
		)
		(polygon
			(pts
				(xy 28.50261 -252.325124) (xy 30.00121 -252.325124) (xy 30.00121 -252.845062) (xy 28.50261 -252.845062)
			)
		)
	)
	(zone
		(layer "In2.Cu")
		(hatch none 0.5)
		(connect_pads
			(clearance 0)
		)
		(min_thickness 0.25)
		(keepout
			(tracks not_allowed)
			(vias allowed)
			(pads allowed)
			(copperpour not_allowed)
			(footprints allowed)
		)
		(placement
			(enabled no)
			(sheetname "")
		)
		(fill
			(thermal_gap 0.5)
			(thermal_bridge_width 0.5)
			(island_removal_mode 0)
		)
		(polygon
			(pts
				(xy 24.402542 -214.925148) (xy 25.901142 -214.925148) (xy 25.901142 -215.445086) (xy 24.402542 -215.445086)
			)
		)
	)
	(zone
		(layer "In2.Cu")
		(hatch none 0.5)
		(connect_pads
			(clearance 0)
		)
		(min_thickness 0.25)
		(keepout
			(tracks not_allowed)
			(vias allowed)
			(pads allowed)
			(copperpour not_allowed)
			(footprints allowed)
		)
		(placement
			(enabled no)
			(sheetname "")
		)
		(fill
			(thermal_gap 0.5)
			(thermal_bridge_width 0.5)
			(island_removal_mode 0)
		)
		(polygon
			(pts
				(xy 430.80686 -243.825268) (xy 432.30546 -243.825268) (xy 432.30546 -244.345206) (xy 430.80686 -244.345206)
			)
		)
	)
	(zone
		(layer "In2.Cu")
		(hatch none 0.5)
		(connect_pads
			(clearance 0)
		)
		(min_thickness 0.25)
		(keepout
			(tracks not_allowed)
			(vias allowed)
			(pads allowed)
			(copperpour not_allowed)
			(footprints allowed)
		)
		(placement
			(enabled no)
			(sheetname "")
		)
		(fill
			(thermal_gap 0.5)
			(thermal_bridge_width 0.5)
			(island_removal_mode 0)
		)
		(polygon
			(pts
				(xy 449.3387 -305.025298) (xy 450.8373 -305.025298) (xy 450.8373 -305.545236) (xy 449.3387 -305.545236)
			)
		)
	)
	(zone
		(layer "In2.Cu")
		(hatch none 0.5)
		(connect_pads
			(clearance 0)
		)
		(min_thickness 0.25)
		(keepout
			(tracks not_allowed)
			(vias allowed)
			(pads allowed)
			(copperpour not_allowed)
			(footprints allowed)
		)
		(placement
			(enabled no)
			(sheetname "")
		)
		(fill
			(thermal_gap 0.5)
			(thermal_bridge_width 0.5)
			(island_removal_mode 0)
		)
		(polygon
			(pts
				(xy 430.80686 -203.025248) (xy 432.30546 -203.025248) (xy 432.30546 -203.545186) (xy 430.80686 -203.545186)
			)
		)
	)
	(zone
		(layer "In2.Cu")
		(hatch none 0.5)
		(connect_pads
			(clearance 0)
		)
		(min_thickness 0.25)
		(keepout
			(tracks not_allowed)
			(vias allowed)
			(pads allowed)
			(copperpour not_allowed)
			(footprints allowed)
		)
		(placement
			(enabled no)
			(sheetname "")
		)
		(fill
			(thermal_gap 0.5)
			(thermal_bridge_width 0.5)
			(island_removal_mode 0)
		)
		(polygon
			(pts
				(xy 441.7949 -227.675186) (xy 443.2935 -227.675186) (xy 443.2935 -228.195124) (xy 441.7949 -228.195124)
			)
		)
	)
	(zone
		(layer "In2.Cu")
		(hatch none 0.5)
		(connect_pads
			(clearance 0)
		)
		(min_thickness 0.25)
		(keepout
			(tracks not_allowed)
			(vias allowed)
			(pads allowed)
			(copperpour not_allowed)
			(footprints allowed)
		)
		(placement
			(enabled no)
			(sheetname "")
		)
		(fill
			(thermal_gap 0.5)
			(thermal_bridge_width 0.5)
			(island_removal_mode 0)
		)
		(polygon
			(pts
				(xy 441.7949 -213.225126) (xy 443.2935 -213.225126) (xy 443.2935 -213.745064) (xy 441.7949 -213.745064)
			)
		)
	)
	(zone
		(layer "In2.Cu")
		(hatch none 0.5)
		(connect_pads
			(clearance 0)
		)
		(min_thickness 0.25)
		(keepout
			(tracks not_allowed)
			(vias allowed)
			(pads allowed)
			(copperpour not_allowed)
			(footprints allowed)
		)
		(placement
			(enabled no)
			(sheetname "")
		)
		(fill
			(thermal_gap 0.5)
			(thermal_bridge_width 0.5)
			(island_removal_mode 0)
		)
		(polygon
			(pts
				(xy 411.618684 -205.575154) (xy 413.117284 -205.575154) (xy 413.117284 -206.095092) (xy 411.618684 -206.095092)
			)
		)
	)
	(zone
		(layer "In2.Cu")
		(hatch none 0.5)
		(connect_pads
			(clearance 0)
		)
		(min_thickness 0.25)
		(keepout
			(tracks not_allowed)
			(vias allowed)
			(pads allowed)
			(copperpour not_allowed)
			(footprints allowed)
		)
		(placement
			(enabled no)
			(sheetname "")
		)
		(fill
			(thermal_gap 0.5)
			(thermal_bridge_width 0.5)
			(island_removal_mode 0)
		)
		(polygon
			(pts
				(xy 175.322738 -225.12528) (xy 176.821338 -225.12528) (xy 176.821338 -225.645218) (xy 175.322738 -225.645218)
			)
		)
	)
	(zone
		(layer "In2.Cu")
		(hatch none 0.5)
		(connect_pads
			(clearance 0)
		)
		(min_thickness 0.25)
		(keepout
			(tracks not_allowed)
			(vias allowed)
			(pads allowed)
			(copperpour not_allowed)
			(footprints allowed)
		)
		(placement
			(enabled no)
			(sheetname "")
		)
		(fill
			(thermal_gap 0.5)
			(thermal_bridge_width 0.5)
			(island_removal_mode 0)
		)
		(polygon
			(pts
				(xy 51.134772 -243.825268) (xy 52.633372 -243.825268) (xy 52.633372 -244.345206) (xy 51.134772 -244.345206)
			)
		)
	)
	(zone
		(layer "In2.Cu")
		(hatch none 0.5)
		(connect_pads
			(clearance 0)
		)
		(min_thickness 0.25)
		(keepout
			(tracks not_allowed)
			(vias allowed)
			(pads allowed)
			(copperpour not_allowed)
			(footprints allowed)
		)
		(placement
			(enabled no)
			(sheetname "")
		)
		(fill
			(thermal_gap 0.5)
			(thermal_bridge_width 0.5)
			(island_removal_mode 0)
		)
		(polygon
			(pts
				(xy 54.578758 -299.075348) (xy 56.077358 -299.075348) (xy 56.077358 -299.595286) (xy 54.578758 -299.595286)
			)
		)
	)
	(zone
		(layer "In2.Cu")
		(hatch none 0.5)
		(connect_pads
			(clearance 0)
		)
		(min_thickness 0.25)
		(keepout
			(tracks not_allowed)
			(vias allowed)
			(pads allowed)
			(copperpour not_allowed)
			(footprints allowed)
		)
		(placement
			(enabled no)
			(sheetname "")
		)
		(fill
			(thermal_gap 0.5)
			(thermal_bridge_width 0.5)
			(island_removal_mode 0)
		)
		(polygon
			(pts
				(xy 190.410846 -285.475172) (xy 191.909446 -285.475172) (xy 191.909446 -285.99511) (xy 190.410846 -285.99511)
			)
		)
	)
	(zone
		(layer "In2.Cu")
		(hatch none 0.5)
		(connect_pads
			(clearance 0)
		)
		(min_thickness 0.25)
		(keepout
			(tracks not_allowed)
			(vias allowed)
			(pads allowed)
			(copperpour not_allowed)
			(footprints allowed)
		)
		(placement
			(enabled no)
			(sheetname "")
		)
		(fill
			(thermal_gap 0.5)
			(thermal_bridge_width 0.5)
			(island_removal_mode 0)
		)
		(polygon
			(pts
				(xy 419.162738 -210.67522) (xy 420.661338 -210.67522) (xy 420.661338 -211.195158) (xy 419.162738 -211.195158)
			)
		)
	)
	(zone
		(layer "In2.Cu")
		(hatch none 0.5)
		(connect_pads
			(clearance 0)
		)
		(min_thickness 0.25)
		(keepout
			(tracks not_allowed)
			(vias allowed)
			(pads allowed)
			(copperpour not_allowed)
			(footprints allowed)
		)
		(placement
			(enabled no)
			(sheetname "")
		)
		(fill
			(thermal_gap 0.5)
			(thermal_bridge_width 0.5)
			(island_removal_mode 0)
		)
		(polygon
			(pts
				(xy 36.046664 -208.125314) (xy 37.545264 -208.125314) (xy 37.545264 -208.645252) (xy 36.046664 -208.645252)
			)
		)
	)
	(zone
		(layer "In2.Cu")
		(hatch none 0.5)
		(connect_pads
			(clearance 0)
		)
		(min_thickness 0.25)
		(keepout
			(tracks not_allowed)
			(vias allowed)
			(pads allowed)
			(copperpour not_allowed)
			(footprints allowed)
		)
		(placement
			(enabled no)
			(sheetname "")
		)
		(fill
			(thermal_gap 0.5)
			(thermal_bridge_width 0.5)
			(island_removal_mode 0)
		)
		(polygon
			(pts
				(xy 283.986732 -312.67527) (xy 285.485332 -312.67527) (xy 285.485332 -313.195208) (xy 283.986732 -313.195208)
			)
		)
	)
	(zone
		(layer "In2.Cu")
		(hatch none 0.5)
		(connect_pads
			(clearance 0)
		)
		(min_thickness 0.25)
		(keepout
			(tracks not_allowed)
			(vias allowed)
			(pads allowed)
			(copperpour not_allowed)
			(footprints allowed)
		)
		(placement
			(enabled no)
			(sheetname "")
		)
		(fill
			(thermal_gap 0.5)
			(thermal_bridge_width 0.5)
			(island_removal_mode 0)
		)
		(polygon
			(pts
				(xy 423.262806 -293.975282) (xy 424.761406 -293.975282) (xy 424.761406 -294.49522) (xy 423.262806 -294.49522)
			)
		)
	)
	(zone
		(layer "In2.Cu")
		(hatch none 0.5)
		(connect_pads
			(clearance 0)
		)
		(min_thickness 0.25)
		(keepout
			(tracks not_allowed)
			(vias allowed)
			(pads allowed)
			(copperpour not_allowed)
			(footprints allowed)
		)
		(placement
			(enabled no)
			(sheetname "")
		)
		(fill
			(thermal_gap 0.5)
			(thermal_bridge_width 0.5)
			(island_removal_mode 0)
		)
		(polygon
			(pts
				(xy 186.310778 -316.075314) (xy 187.809378 -316.075314) (xy 187.809378 -316.595252) (xy 186.310778 -316.595252)
			)
		)
	)
	(zone
		(layer "In2.Cu")
		(hatch none 0.5)
		(connect_pads
			(clearance 0)
		)
		(min_thickness 0.25)
		(keepout
			(tracks allowed)
			(vias allowed)
			(pads allowed)
			(copperpour allowed)
			(footprints allowed)
		)
		(placement
			(enabled no)
			(sheetname "")
		)
		(fill
			(thermal_gap 0.5)
			(thermal_bridge_width 0.5)
			(island_removal_mode 0)
		)
		(polygon
			(pts
				(xy 98.35261 -338.548218) (xy 98.35261 -337.925918) (xy 98.90379 -337.925918) (xy 98.90379 -338.548218)
			)
		)
	)
	(zone
		(layer "In2.Cu")
		(hatch none 0.5)
		(connect_pads
			(clearance 0)
		)
		(min_thickness 0.25)
		(keepout
			(tracks not_allowed)
			(vias allowed)
			(pads allowed)
			(copperpour not_allowed)
			(footprints allowed)
		)
		(placement
			(enabled no)
			(sheetname "")
		)
		(fill
			(thermal_gap 0.5)
			(thermal_bridge_width 0.5)
			(island_removal_mode 0)
		)
		(polygon
			(pts
				(xy 31.946596 -280.375106) (xy 33.445196 -280.375106) (xy 33.445196 -280.895044) (xy 31.946596 -280.895044)
			)
		)
	)
	(zone
		(layer "In2.Cu")
		(hatch none 0.5)
		(connect_pads
			(clearance 0)
		)
		(min_thickness 0.25)
		(keepout
			(tracks not_allowed)
			(vias allowed)
			(pads allowed)
			(copperpour not_allowed)
			(footprints allowed)
		)
		(placement
			(enabled no)
			(sheetname "")
		)
		(fill
			(thermal_gap 0.5)
			(thermal_bridge_width 0.5)
			(island_removal_mode 0)
		)
		(polygon
			(pts
				(xy 51.134772 -234.475274) (xy 52.633372 -234.475274) (xy 52.633372 -234.995212) (xy 51.134772 -234.995212)
			)
		)
	)
	(zone
		(layer "In2.Cu")
		(hatch none 0.5)
		(connect_pads
			(clearance 0)
		)
		(min_thickness 0.25)
		(keepout
			(tracks not_allowed)
			(vias allowed)
			(pads allowed)
			(copperpour not_allowed)
			(footprints allowed)
		)
		(placement
			(enabled no)
			(sheetname "")
		)
		(fill
			(thermal_gap 0.5)
			(thermal_bridge_width 0.5)
			(island_removal_mode 0)
		)
		(polygon
			(pts
				(xy 190.410846 -316.925198) (xy 191.909446 -316.925198) (xy 191.909446 -317.445136) (xy 190.410846 -317.445136)
			)
		)
	)
	(zone
		(layer "In2.Cu")
		(hatch none 0.5)
		(connect_pads
			(clearance 0)
		)
		(min_thickness 0.25)
		(keepout
			(tracks not_allowed)
			(vias allowed)
			(pads allowed)
			(copperpour not_allowed)
			(footprints allowed)
		)
		(placement
			(enabled no)
			(sheetname "")
		)
		(fill
			(thermal_gap 0.5)
			(thermal_bridge_width 0.5)
			(island_removal_mode 0)
		)
		(polygon
			(pts
				(xy 287.430718 -289.725354) (xy 288.929318 -289.725354) (xy 288.929318 -290.245292) (xy 287.430718 -290.245292)
			)
		)
	)
	(zone
		(layer "In2.Cu")
		(hatch none 0.5)
		(connect_pads
			(clearance 0)
		)
		(min_thickness 0.25)
		(keepout
			(tracks not_allowed)
			(vias allowed)
			(pads allowed)
			(copperpour not_allowed)
			(footprints allowed)
		)
		(placement
			(enabled no)
			(sheetname "")
		)
		(fill
			(thermal_gap 0.5)
			(thermal_bridge_width 0.5)
			(island_removal_mode 0)
		)
		(polygon
			(pts
				(xy 197.954646 -212.375242) (xy 199.453246 -212.375242) (xy 199.453246 -212.89518) (xy 197.954646 -212.89518)
			)
		)
	)
	(zone
		(layer "In2.Cu")
		(hatch none 0.5)
		(connect_pads
			(clearance 0)
		)
		(min_thickness 0.25)
		(keepout
			(tracks not_allowed)
			(vias allowed)
			(pads allowed)
			(copperpour not_allowed)
			(footprints allowed)
		)
		(placement
			(enabled no)
			(sheetname "")
		)
		(fill
			(thermal_gap 0.5)
			(thermal_bridge_width 0.5)
			(island_removal_mode 0)
		)
		(polygon
			(pts
				(xy 201.398632 -291.425122) (xy 202.897232 -291.425122) (xy 202.897232 -291.94506) (xy 201.398632 -291.94506)
			)
		)
	)
	(zone
		(layer "In2.Cu")
		(hatch none 0.5)
		(connect_pads
			(clearance 0)
		)
		(min_thickness 0.25)
		(keepout
			(tracks not_allowed)
			(vias allowed)
			(pads allowed)
			(copperpour not_allowed)
			(footprints allowed)
		)
		(placement
			(enabled no)
			(sheetname "")
		)
		(fill
			(thermal_gap 0.5)
			(thermal_bridge_width 0.5)
			(island_removal_mode 0)
		)
		(polygon
			(pts
				(xy 20.95881 -271.87525) (xy 22.45741 -271.87525) (xy 22.45741 -272.395188) (xy 20.95881 -272.395188)
			)
		)
	)
	(zone
		(layer "In2.Cu")
		(hatch none 0.5)
		(connect_pads
			(clearance 0)
		)
		(min_thickness 0.25)
		(keepout
			(tracks not_allowed)
			(vias allowed)
			(pads allowed)
			(copperpour not_allowed)
			(footprints allowed)
		)
		(placement
			(enabled no)
			(sheetname "")
		)
		(fill
			(thermal_gap 0.5)
			(thermal_bridge_width 0.5)
			(island_removal_mode 0)
		)
		(polygon
			(pts
				(xy 51.134772 -271.87525) (xy 52.633372 -271.87525) (xy 52.633372 -272.395188) (xy 51.134772 -272.395188)
			)
		)
	)
	(zone
		(layer "In2.Cu")
		(hatch none 0.5)
		(connect_pads
			(clearance 0)
		)
		(min_thickness 0.25)
		(keepout
			(tracks not_allowed)
			(vias allowed)
			(pads allowed)
			(copperpour not_allowed)
			(footprints allowed)
		)
		(placement
			(enabled no)
			(sheetname "")
		)
		(fill
			(thermal_gap 0.5)
			(thermal_bridge_width 0.5)
			(island_removal_mode 0)
		)
		(polygon
			(pts
				(xy 24.402542 -288.025332) (xy 25.901142 -288.025332) (xy 25.901142 -288.54527) (xy 24.402542 -288.54527)
			)
		)
	)
	(zone
		(layer "In2.Cu")
		(hatch none 0.5)
		(connect_pads
			(clearance 0)
		)
		(min_thickness 0.25)
		(keepout
			(tracks not_allowed)
			(vias allowed)
			(pads allowed)
			(copperpour not_allowed)
			(footprints allowed)
		)
		(placement
			(enabled no)
			(sheetname "")
		)
		(fill
			(thermal_gap 0.5)
			(thermal_bridge_width 0.5)
			(island_removal_mode 0)
		)
		(polygon
			(pts
				(xy 16.858742 -280.375106) (xy 18.357342 -280.375106) (xy 18.357342 -280.895044) (xy 16.858742 -280.895044)
			)
		)
	)
	(zone
		(layer "In2.Cu")
		(hatch none 0.5)
		(connect_pads
			(clearance 0)
		)
		(min_thickness 0.25)
		(keepout
			(tracks not_allowed)
			(vias allowed)
			(pads allowed)
			(copperpour not_allowed)
			(footprints allowed)
		)
		(placement
			(enabled no)
			(sheetname "")
		)
		(fill
			(thermal_gap 0.5)
			(thermal_bridge_width 0.5)
			(island_removal_mode 0)
		)
		(polygon
			(pts
				(xy 430.80686 -298.22521) (xy 432.30546 -298.22521) (xy 432.30546 -298.745148) (xy 430.80686 -298.745148)
			)
		)
	)
	(zone
		(layer "In2.Cu")
		(hatch none 0.5)
		(connect_pads
			(clearance 0)
		)
		(min_thickness 0.25)
		(keepout
			(tracks not_allowed)
			(vias allowed)
			(pads allowed)
			(copperpour not_allowed)
			(footprints allowed)
		)
		(placement
			(enabled no)
			(sheetname "")
		)
		(fill
			(thermal_gap 0.5)
			(thermal_bridge_width 0.5)
			(island_removal_mode 0)
		)
		(polygon
			(pts
				(xy 190.410846 -245.52529) (xy 191.909446 -245.52529) (xy 191.909446 -246.045228) (xy 190.410846 -246.045228)
			)
		)
	)
	(zone
		(layer "In2.Cu")
		(hatch none 0.5)
		(connect_pads
			(clearance 0)
		)
		(min_thickness 0.25)
		(keepout
			(tracks not_allowed)
			(vias allowed)
			(pads allowed)
			(copperpour not_allowed)
			(footprints allowed)
		)
		(placement
			(enabled no)
			(sheetname "")
		)
		(fill
			(thermal_gap 0.5)
			(thermal_bridge_width 0.5)
			(island_removal_mode 0)
		)
		(polygon
			(pts
				(xy 423.262806 -310.975248) (xy 424.761406 -310.975248) (xy 424.761406 -311.495186) (xy 423.262806 -311.495186)
			)
		)
	)
	(zone
		(layer "In2.Cu")
		(hatch none 0.5)
		(connect_pads
			(clearance 0)
		)
		(min_thickness 0.25)
		(keepout
			(tracks not_allowed)
			(vias allowed)
			(pads allowed)
			(copperpour not_allowed)
			(footprints allowed)
		)
		(placement
			(enabled no)
			(sheetname "")
		)
		(fill
			(thermal_gap 0.5)
			(thermal_bridge_width 0.5)
			(island_removal_mode 0)
		)
		(polygon
			(pts
				(xy 276.442932 -275.275294) (xy 277.941532 -275.275294) (xy 277.941532 -275.795232) (xy 276.442932 -275.795232)
			)
		)
	)
	(zone
		(layer "In2.Cu")
		(hatch none 0.5)
		(connect_pads
			(clearance 0)
		)
		(min_thickness 0.25)
		(keepout
			(tracks not_allowed)
			(vias allowed)
			(pads allowed)
			(copperpour not_allowed)
			(footprints allowed)
		)
		(placement
			(enabled no)
			(sheetname "")
		)
		(fill
			(thermal_gap 0.5)
			(thermal_bridge_width 0.5)
			(island_removal_mode 0)
		)
		(polygon
			(pts
				(xy 419.162738 -248.075196) (xy 420.661338 -248.075196) (xy 420.661338 -248.595134) (xy 419.162738 -248.595134)
			)
		)
	)
	(zone
		(layer "In2.Cu")
		(hatch none 0.5)
		(connect_pads
			(clearance 0)
		)
		(min_thickness 0.25)
		(keepout
			(tracks not_allowed)
			(vias allowed)
			(pads allowed)
			(copperpour not_allowed)
			(footprints allowed)
		)
		(placement
			(enabled no)
			(sheetname "")
		)
		(fill
			(thermal_gap 0.5)
			(thermal_bridge_width 0.5)
			(island_removal_mode 0)
		)
		(polygon
			(pts
				(xy 54.578758 -295.675304) (xy 56.077358 -295.675304) (xy 56.077358 -296.195242) (xy 54.578758 -296.195242)
			)
		)
	)
	(zone
		(layer "In2.Cu")
		(hatch none 0.5)
		(connect_pads
			(clearance 0)
		)
		(min_thickness 0.25)
		(keepout
			(tracks not_allowed)
			(vias allowed)
			(pads allowed)
			(copperpour not_allowed)
			(footprints allowed)
		)
		(placement
			(enabled no)
			(sheetname "")
		)
		(fill
			(thermal_gap 0.5)
			(thermal_bridge_width 0.5)
			(island_removal_mode 0)
		)
		(polygon
			(pts
				(xy 175.322738 -264.225278) (xy 176.821338 -264.225278) (xy 176.821338 -264.745216) (xy 175.322738 -264.745216)
			)
		)
	)
	(zone
		(layer "In2.Cu")
		(hatch none 0.5)
		(connect_pads
			(clearance 0)
		)
		(min_thickness 0.25)
		(keepout
			(tracks not_allowed)
			(vias allowed)
			(pads allowed)
			(copperpour not_allowed)
			(footprints allowed)
		)
		(placement
			(enabled no)
			(sheetname "")
		)
		(fill
			(thermal_gap 0.5)
			(thermal_bridge_width 0.5)
			(island_removal_mode 0)
		)
		(polygon
			(pts
				(xy 16.858742 -208.975198) (xy 18.357342 -208.975198) (xy 18.357342 -209.495136) (xy 16.858742 -209.495136)
			)
		)
	)
	(zone
		(layer "In2.Cu")
		(hatch none 0.5)
		(connect_pads
			(clearance 0)
		)
		(min_thickness 0.25)
		(keepout
			(tracks not_allowed)
			(vias allowed)
			(pads allowed)
			(copperpour not_allowed)
			(footprints allowed)
		)
		(placement
			(enabled no)
			(sheetname "")
		)
		(fill
			(thermal_gap 0.5)
			(thermal_bridge_width 0.5)
			(island_removal_mode 0)
		)
		(polygon
			(pts
				(xy 302.518826 -220.875098) (xy 304.017426 -220.875098) (xy 304.017426 -221.395036) (xy 302.518826 -221.395036)
			)
		)
	)
	(zone
		(layer "In2.Cu")
		(hatch none 0.5)
		(connect_pads
			(clearance 0)
		)
		(min_thickness 0.25)
		(keepout
			(tracks not_allowed)
			(vias allowed)
			(pads allowed)
			(copperpour not_allowed)
			(footprints allowed)
		)
		(placement
			(enabled no)
			(sheetname "")
		)
		(fill
			(thermal_gap 0.5)
			(thermal_bridge_width 0.5)
			(island_removal_mode 0)
		)
		(polygon
			(pts
				(xy 186.310778 -241.275108) (xy 187.809378 -241.275108) (xy 187.809378 -241.795046) (xy 186.310778 -241.795046)
			)
		)
	)
	(zone
		(layer "In2.Cu")
		(hatch none 0.5)
		(connect_pads
			(clearance 0)
		)
		(min_thickness 0.25)
		(keepout
			(tracks not_allowed)
			(vias allowed)
			(pads allowed)
			(copperpour not_allowed)
			(footprints allowed)
		)
		(placement
			(enabled no)
			(sheetname "")
		)
		(fill
			(thermal_gap 0.5)
			(thermal_bridge_width 0.5)
			(island_removal_mode 0)
		)
		(polygon
			(pts
				(xy 51.134772 -219.17533) (xy 52.633372 -219.17533) (xy 52.633372 -219.695268) (xy 51.134772 -219.695268)
			)
		)
	)
	(zone
		(layer "In2.Cu")
		(hatch none 0.5)
		(connect_pads
			(clearance 0)
		)
		(min_thickness 0.25)
		(keepout
			(tracks not_allowed)
			(vias allowed)
			(pads allowed)
			(copperpour not_allowed)
			(footprints allowed)
		)
		(placement
			(enabled no)
			(sheetname "")
		)
		(fill
			(thermal_gap 0.5)
			(thermal_bridge_width 0.5)
			(island_removal_mode 0)
		)
		(polygon
			(pts
				(xy 283.986732 -294.825166) (xy 285.485332 -294.825166) (xy 285.485332 -295.345104) (xy 283.986732 -295.345104)
			)
		)
	)
	(zone
		(layer "In2.Cu")
		(hatch none 0.5)
		(connect_pads
			(clearance 0)
		)
		(min_thickness 0.25)
		(keepout
			(tracks not_allowed)
			(vias allowed)
			(pads allowed)
			(copperpour not_allowed)
			(footprints allowed)
		)
		(placement
			(enabled no)
			(sheetname "")
		)
		(fill
			(thermal_gap 0.5)
			(thermal_bridge_width 0.5)
			(island_removal_mode 0)
		)
		(polygon
			(pts
				(xy 186.310778 -266.775184) (xy 187.809378 -266.775184) (xy 187.809378 -267.295122) (xy 186.310778 -267.295122)
			)
		)
	)
	(zone
		(layer "In2.Cu")
		(hatch none 0.5)
		(connect_pads
			(clearance 0)
		)
		(min_thickness 0.25)
		(keepout
			(tracks not_allowed)
			(vias allowed)
			(pads allowed)
			(copperpour not_allowed)
			(footprints allowed)
		)
		(placement
			(enabled no)
			(sheetname "")
		)
		(fill
			(thermal_gap 0.5)
			(thermal_bridge_width 0.5)
			(island_removal_mode 0)
		)
		(polygon
			(pts
				(xy 16.858742 -299.075348) (xy 18.357342 -299.075348) (xy 18.357342 -299.595286) (xy 16.858742 -299.595286)
			)
		)
	)
	(zone
		(layer "In2.Cu")
		(hatch none 0.5)
		(connect_pads
			(clearance 0)
		)
		(min_thickness 0.25)
		(keepout
			(tracks not_allowed)
			(vias allowed)
			(pads allowed)
			(copperpour not_allowed)
			(footprints allowed)
		)
		(placement
			(enabled no)
			(sheetname "")
		)
		(fill
			(thermal_gap 0.5)
			(thermal_bridge_width 0.5)
			(island_removal_mode 0)
		)
		(polygon
			(pts
				(xy 186.310778 -263.37514) (xy 187.809378 -263.37514) (xy 187.809378 -263.895078) (xy 186.310778 -263.895078)
			)
		)
	)
	(zone
		(layer "In2.Cu")
		(hatch none 0.5)
		(connect_pads
			(clearance 0)
		)
		(min_thickness 0.25)
		(keepout
			(tracks not_allowed)
			(vias allowed)
			(pads allowed)
			(copperpour not_allowed)
			(footprints allowed)
		)
		(placement
			(enabled no)
			(sheetname "")
		)
		(fill
			(thermal_gap 0.5)
			(thermal_bridge_width 0.5)
			(island_removal_mode 0)
		)
		(polygon
			(pts
				(xy 302.518826 -238.725202) (xy 304.017426 -238.725202) (xy 304.017426 -239.24514) (xy 302.518826 -239.24514)
			)
		)
	)
	(zone
		(layer "In2.Cu")
		(hatch none 0.5)
		(connect_pads
			(clearance 0)
		)
		(min_thickness 0.25)
		(keepout
			(tracks allowed)
			(vias allowed)
			(pads allowed)
			(copperpour allowed)
			(footprints allowed)
		)
		(placement
			(enabled no)
			(sheetname "")
		)
		(fill
			(thermal_gap 0.5)
			(thermal_bridge_width 0.5)
			(island_removal_mode 0)
		)
		(polygon
			(pts
				(xy 93.12656 -180.078888) (xy 93.12656 -179.532534) (xy 93.67901 -179.532534) (xy 93.67901 -180.078888)
			)
		)
	)
	(zone
		(layer "In2.Cu")
		(hatch none 0.5)
		(connect_pads
			(clearance 0)
		)
		(min_thickness 0.25)
		(keepout
			(tracks not_allowed)
			(vias allowed)
			(pads allowed)
			(copperpour not_allowed)
			(footprints allowed)
		)
		(placement
			(enabled no)
			(sheetname "")
		)
		(fill
			(thermal_gap 0.5)
			(thermal_bridge_width 0.5)
			(island_removal_mode 0)
		)
		(polygon
			(pts
				(xy 453.438768 -312.67527) (xy 454.937368 -312.67527) (xy 454.937368 -313.195208) (xy 453.438768 -313.195208)
			)
		)
	)
	(zone
		(layer "In2.Cu")
		(hatch none 0.5)
		(connect_pads
			(clearance 0)
		)
		(min_thickness 0.25)
		(keepout
			(tracks not_allowed)
			(vias allowed)
			(pads allowed)
			(copperpour not_allowed)
			(footprints allowed)
		)
		(placement
			(enabled no)
			(sheetname "")
		)
		(fill
			(thermal_gap 0.5)
			(thermal_bridge_width 0.5)
			(island_removal_mode 0)
		)
		(polygon
			(pts
				(xy 434.250846 -283.77515) (xy 435.749446 -283.77515) (xy 435.749446 -284.295088) (xy 434.250846 -284.295088)
			)
		)
	)
	(zone
		(layer "In2.Cu")
		(hatch none 0.5)
		(connect_pads
			(clearance 0)
		)
		(min_thickness 0.25)
		(keepout
			(tracks not_allowed)
			(vias allowed)
			(pads allowed)
			(copperpour not_allowed)
			(footprints allowed)
		)
		(placement
			(enabled no)
			(sheetname "")
		)
		(fill
			(thermal_gap 0.5)
			(thermal_bridge_width 0.5)
			(island_removal_mode 0)
		)
		(polygon
			(pts
				(xy 167.778684 -220.025214) (xy 169.277284 -220.025214) (xy 169.277284 -220.545152) (xy 167.778684 -220.545152)
			)
		)
	)
	(zone
		(layer "In2.Cu")
		(hatch none 0.5)
		(connect_pads
			(clearance 0)
		)
		(min_thickness 0.25)
		(keepout
			(tracks not_allowed)
			(vias allowed)
			(pads allowed)
			(copperpour not_allowed)
			(footprints allowed)
		)
		(placement
			(enabled no)
			(sheetname "")
		)
		(fill
			(thermal_gap 0.5)
			(thermal_bridge_width 0.5)
			(island_removal_mode 0)
		)
		(polygon
			(pts
				(xy 430.80686 -282.925266) (xy 432.30546 -282.925266) (xy 432.30546 -283.445204) (xy 430.80686 -283.445204)
			)
		)
	)
	(zone
		(layer "In2.Cu")
		(hatch none 0.5)
		(connect_pads
			(clearance 0)
		)
		(min_thickness 0.25)
		(keepout
			(tracks not_allowed)
			(vias allowed)
			(pads allowed)
			(copperpour not_allowed)
			(footprints allowed)
		)
		(placement
			(enabled no)
			(sheetname "")
		)
		(fill
			(thermal_gap 0.5)
			(thermal_bridge_width 0.5)
			(island_removal_mode 0)
		)
		(polygon
			(pts
				(xy 197.954646 -292.27526) (xy 199.453246 -292.27526) (xy 199.453246 -292.795198) (xy 197.954646 -292.795198)
			)
		)
	)
	(zone
		(layer "In2.Cu")
		(hatch none 0.5)
		(connect_pads
			(clearance 0)
		)
		(min_thickness 0.25)
		(keepout
			(tracks not_allowed)
			(vias allowed)
			(pads allowed)
			(copperpour not_allowed)
			(footprints allowed)
		)
		(placement
			(enabled no)
			(sheetname "")
		)
		(fill
			(thermal_gap 0.5)
			(thermal_bridge_width 0.5)
			(island_removal_mode 0)
		)
		(polygon
			(pts
				(xy 186.310778 -207.275176) (xy 187.809378 -207.275176) (xy 187.809378 -207.795114) (xy 186.310778 -207.795114)
			)
		)
	)
	(zone
		(layer "In2.Cu")
		(hatch none 0.5)
		(connect_pads
			(clearance 0)
		)
		(min_thickness 0.25)
		(keepout
			(tracks not_allowed)
			(vias allowed)
			(pads allowed)
			(copperpour not_allowed)
			(footprints allowed)
		)
		(placement
			(enabled no)
			(sheetname "")
		)
		(fill
			(thermal_gap 0.5)
			(thermal_bridge_width 0.5)
			(island_removal_mode 0)
		)
		(polygon
			(pts
				(xy 51.134772 -245.52529) (xy 52.633372 -245.52529) (xy 52.633372 -246.045228) (xy 51.134772 -246.045228)
			)
		)
	)
	(zone
		(layer "In2.Cu")
		(hatch none 0.5)
		(connect_pads
			(clearance 0)
		)
		(min_thickness 0.25)
		(keepout
			(tracks not_allowed)
			(vias allowed)
			(pads allowed)
			(copperpour not_allowed)
			(footprints allowed)
		)
		(placement
			(enabled no)
			(sheetname "")
		)
		(fill
			(thermal_gap 0.5)
			(thermal_bridge_width 0.5)
			(island_removal_mode 0)
		)
		(polygon
			(pts
				(xy 302.518826 -276.125178) (xy 304.017426 -276.125178) (xy 304.017426 -276.645116) (xy 302.518826 -276.645116)
			)
		)
	)
	(zone
		(layer "In2.Cu")
		(hatch none 0.5)
		(connect_pads
			(clearance 0)
		)
		(min_thickness 0.25)
		(keepout
			(tracks not_allowed)
			(vias allowed)
			(pads allowed)
			(copperpour not_allowed)
			(footprints allowed)
		)
		(placement
			(enabled no)
			(sheetname "")
		)
		(fill
			(thermal_gap 0.5)
			(thermal_bridge_width 0.5)
			(island_removal_mode 0)
		)
		(polygon
			(pts
				(xy 31.946596 -293.125144) (xy 33.445196 -293.125144) (xy 33.445196 -293.645082) (xy 31.946596 -293.645082)
			)
		)
	)
	(zone
		(layer "In2.Cu")
		(hatch none 0.5)
		(connect_pads
			(clearance 0)
		)
		(min_thickness 0.25)
		(keepout
			(tracks not_allowed)
			(vias allowed)
			(pads allowed)
			(copperpour not_allowed)
			(footprints allowed)
		)
		(placement
			(enabled no)
			(sheetname "")
		)
		(fill
			(thermal_gap 0.5)
			(thermal_bridge_width 0.5)
			(island_removal_mode 0)
		)
		(polygon
			(pts
				(xy 24.402542 -242.97513) (xy 25.901142 -242.97513) (xy 25.901142 -243.495068) (xy 24.402542 -243.495068)
			)
		)
	)
	(zone
		(layer "In2.Cu")
		(hatch none 0.5)
		(connect_pads
			(clearance 0)
		)
		(min_thickness 0.25)
		(keepout
			(tracks not_allowed)
			(vias allowed)
			(pads allowed)
			(copperpour not_allowed)
			(footprints allowed)
		)
		(placement
			(enabled no)
			(sheetname "")
		)
		(fill
			(thermal_gap 0.5)
			(thermal_bridge_width 0.5)
			(island_removal_mode 0)
		)
		(polygon
			(pts
				(xy 411.618684 -316.075314) (xy 413.117284 -316.075314) (xy 413.117284 -316.595252) (xy 411.618684 -316.595252)
			)
		)
	)
	(zone
		(layer "In2.Cu")
		(hatch none 0.5)
		(connect_pads
			(clearance 0)
		)
		(min_thickness 0.25)
		(keepout
			(tracks not_allowed)
			(vias allowed)
			(pads allowed)
			(copperpour not_allowed)
			(footprints allowed)
		)
		(placement
			(enabled no)
			(sheetname "")
		)
		(fill
			(thermal_gap 0.5)
			(thermal_bridge_width 0.5)
			(island_removal_mode 0)
		)
		(polygon
			(pts
				(xy 201.398632 -308.425342) (xy 202.897232 -308.425342) (xy 202.897232 -308.94528) (xy 201.398632 -308.94528)
			)
		)
	)
	(zone
		(layer "In2.Cu")
		(hatch none 0.5)
		(connect_pads
			(clearance 0)
		)
		(min_thickness 0.25)
		(keepout
			(tracks not_allowed)
			(vias allowed)
			(pads allowed)
			(copperpour not_allowed)
			(footprints allowed)
		)
		(placement
			(enabled no)
			(sheetname "")
		)
		(fill
			(thermal_gap 0.5)
			(thermal_bridge_width 0.5)
			(island_removal_mode 0)
		)
		(polygon
			(pts
				(xy 415.718752 -236.175296) (xy 417.217352 -236.175296) (xy 417.217352 -236.695234) (xy 415.718752 -236.695234)
			)
		)
	)
	(zone
		(layer "In2.Cu")
		(hatch none 0.5)
		(connect_pads
			(clearance 0)
		)
		(min_thickness 0.25)
		(keepout
			(tracks not_allowed)
			(vias allowed)
			(pads allowed)
			(copperpour not_allowed)
			(footprints allowed)
		)
		(placement
			(enabled no)
			(sheetname "")
		)
		(fill
			(thermal_gap 0.5)
			(thermal_bridge_width 0.5)
			(island_removal_mode 0)
		)
		(polygon
			(pts
				(xy 299.07484 -309.275226) (xy 300.57344 -309.275226) (xy 300.57344 -309.795164) (xy 299.07484 -309.795164)
			)
		)
	)
	(zone
		(layer "In2.Cu")
		(hatch none 0.5)
		(connect_pads
			(clearance 0)
		)
		(min_thickness 0.25)
		(keepout
			(tracks not_allowed)
			(vias allowed)
			(pads allowed)
			(copperpour not_allowed)
			(footprints allowed)
		)
		(placement
			(enabled no)
			(sheetname "")
		)
		(fill
			(thermal_gap 0.5)
			(thermal_bridge_width 0.5)
			(island_removal_mode 0)
		)
		(polygon
			(pts
				(xy 24.402542 -308.425342) (xy 25.901142 -308.425342) (xy 25.901142 -308.94528) (xy 24.402542 -308.94528)
			)
		)
	)
	(zone
		(layer "In2.Cu")
		(hatch none 0.5)
		(connect_pads
			(clearance 0)
		)
		(min_thickness 0.25)
		(keepout
			(tracks not_allowed)
			(vias allowed)
			(pads allowed)
			(copperpour not_allowed)
			(footprints allowed)
		)
		(placement
			(enabled no)
			(sheetname "")
		)
		(fill
			(thermal_gap 0.5)
			(thermal_bridge_width 0.5)
			(island_removal_mode 0)
		)
		(polygon
			(pts
				(xy 430.80686 -309.275226) (xy 432.30546 -309.275226) (xy 432.30546 -309.795164) (xy 430.80686 -309.795164)
			)
		)
	)
	(zone
		(layer "In2.Cu")
		(hatch none 0.5)
		(connect_pads
			(clearance 0)
		)
		(min_thickness 0.25)
		(keepout
			(tracks not_allowed)
			(vias allowed)
			(pads allowed)
			(copperpour not_allowed)
			(footprints allowed)
		)
		(placement
			(enabled no)
			(sheetname "")
		)
		(fill
			(thermal_gap 0.5)
			(thermal_bridge_width 0.5)
			(island_removal_mode 0)
		)
		(polygon
			(pts
				(xy 294.974772 -278.675338) (xy 296.473372 -278.675338) (xy 296.473372 -279.195276) (xy 294.974772 -279.195276)
			)
		)
	)
	(zone
		(layer "In2.Cu")
		(hatch none 0.5)
		(connect_pads
			(clearance 0)
		)
		(min_thickness 0.25)
		(keepout
			(tracks not_allowed)
			(vias allowed)
			(pads allowed)
			(copperpour not_allowed)
			(footprints allowed)
		)
		(placement
			(enabled no)
			(sheetname "")
		)
		(fill
			(thermal_gap 0.5)
			(thermal_bridge_width 0.5)
			(island_removal_mode 0)
		)
		(polygon
			(pts
				(xy 441.7949 -274.425156) (xy 443.2935 -274.425156) (xy 443.2935 -274.945094) (xy 441.7949 -274.945094)
			)
		)
	)
	(zone
		(layer "In2.Cu")
		(hatch none 0.5)
		(connect_pads
			(clearance 0)
		)
		(min_thickness 0.25)
		(keepout
			(tracks not_allowed)
			(vias allowed)
			(pads allowed)
			(copperpour not_allowed)
			(footprints allowed)
		)
		(placement
			(enabled no)
			(sheetname "")
		)
		(fill
			(thermal_gap 0.5)
			(thermal_bridge_width 0.5)
			(island_removal_mode 0)
		)
		(polygon
			(pts
				(xy 186.310778 -244.675152) (xy 187.809378 -244.675152) (xy 187.809378 -245.19509) (xy 186.310778 -245.19509)
			)
		)
	)
	(zone
		(layer "In2.Cu")
		(hatch none 0.5)
		(connect_pads
			(clearance 0)
		)
		(min_thickness 0.25)
		(keepout
			(tracks not_allowed)
			(vias allowed)
			(pads allowed)
			(copperpour not_allowed)
			(footprints allowed)
		)
		(placement
			(enabled no)
			(sheetname "")
		)
		(fill
			(thermal_gap 0.5)
			(thermal_bridge_width 0.5)
			(island_removal_mode 0)
		)
		(polygon
			(pts
				(xy 306.618894 -296.525188) (xy 308.117494 -296.525188) (xy 308.117494 -297.045126) (xy 306.618894 -297.045126)
			)
		)
	)
	(zone
		(layer "In2.Cu")
		(hatch none 0.5)
		(connect_pads
			(clearance 0)
		)
		(min_thickness 0.25)
		(keepout
			(tracks not_allowed)
			(vias allowed)
			(pads allowed)
			(copperpour not_allowed)
			(footprints allowed)
		)
		(placement
			(enabled no)
			(sheetname "")
		)
		(fill
			(thermal_gap 0.5)
			(thermal_bridge_width 0.5)
			(island_removal_mode 0)
		)
		(polygon
			(pts
				(xy 141.045184 -32.0167)
				(arc
					(start 141.045184 -32.156908)
					(mid 141.074393 -32.22679)
					(end 141.144498 -32.25546)
				)
				(arc
					(start 141.445742 -32.25546)
					(mid 141.515847 -32.22679)
					(end 141.545056 -32.156908)
				)
				(xy 141.545056 -32.0167) (xy 141.485112 -32.0167)
				(arc
					(start 141.485112 -31.447486)
					(mid 141.528611 -31.411117)
					(end 141.545056 -31.356808)
				)
				(arc
					(start 141.545056 -31.096712)
					(mid 141.528737 -31.04232)
					(end 141.485112 -31.006034)
				)
				(xy 141.485112 -30.43682) (xy 141.545056 -30.43682)
				(arc
					(start 141.545056 -30.296612)
					(mid 141.515847 -30.22673)
					(end 141.445742 -30.19806)
				)
				(arc
					(start 141.144498 -30.19806)
					(mid 141.074393 -30.22673)
					(end 141.045184 -30.296612)
				)
				(xy 141.045184 -30.43682) (xy 141.105128 -30.43682)
				(arc
					(start 141.105128 -31.006034)
					(mid 141.061629 -31.042403)
					(end 141.045184 -31.096712)
				)
				(arc
					(start 141.045184 -31.356808)
					(mid 141.061503 -31.4112)
					(end 141.105128 -31.447486)
				)
				(xy 141.105128 -32.0167)
			)
		)
	)
	(zone
		(layer "In2.Cu")
		(hatch none 0.5)
		(connect_pads
			(clearance 0)
		)
		(min_thickness 0.25)
		(keepout
			(tracks not_allowed)
			(vias allowed)
			(pads allowed)
			(copperpour not_allowed)
			(footprints allowed)
		)
		(placement
			(enabled no)
			(sheetname "")
		)
		(fill
			(thermal_gap 0.5)
			(thermal_bridge_width 0.5)
			(island_removal_mode 0)
		)
		(polygon
			(pts
				(xy 28.50261 -209.825336) (xy 30.00121 -209.825336) (xy 30.00121 -210.345274) (xy 28.50261 -210.345274)
			)
		)
	)
	(zone
		(layer "In2.Cu")
		(hatch none 0.5)
		(connect_pads
			(clearance 0)
		)
		(min_thickness 0.25)
		(keepout
			(tracks not_allowed)
			(vias allowed)
			(pads allowed)
			(copperpour not_allowed)
			(footprints allowed)
		)
		(placement
			(enabled no)
			(sheetname "")
		)
		(fill
			(thermal_gap 0.5)
			(thermal_bridge_width 0.5)
			(island_removal_mode 0)
		)
		(polygon
			(pts
				(xy 16.858742 -293.125144) (xy 18.357342 -293.125144) (xy 18.357342 -293.645082) (xy 16.858742 -293.645082)
			)
		)
	)
	(zone
		(layer "In2.Cu")
		(hatch none 0.5)
		(connect_pads
			(clearance 0)
		)
		(min_thickness 0.25)
		(keepout
			(tracks not_allowed)
			(vias allowed)
			(pads allowed)
			(copperpour not_allowed)
			(footprints allowed)
		)
		(placement
			(enabled no)
			(sheetname "")
		)
		(fill
			(thermal_gap 0.5)
			(thermal_bridge_width 0.5)
			(island_removal_mode 0)
		)
		(polygon
			(pts
				(xy 190.410846 -265.9253) (xy 191.909446 -265.9253) (xy 191.909446 -266.445238) (xy 190.410846 -266.445238)
			)
		)
	)
	(zone
		(layer "In2.Cu")
		(hatch none 0.5)
		(connect_pads
			(clearance 0)
		)
		(min_thickness 0.25)
		(keepout
			(tracks not_allowed)
			(vias allowed)
			(pads allowed)
			(copperpour not_allowed)
			(footprints allowed)
		)
		(placement
			(enabled no)
			(sheetname "")
		)
		(fill
			(thermal_gap 0.5)
			(thermal_bridge_width 0.5)
			(island_removal_mode 0)
		)
		(polygon
			(pts
				(xy 58.678826 -252.325124) (xy 60.177426 -252.325124) (xy 60.177426 -252.845062) (xy 58.678826 -252.845062)
			)
		)
	)
	(zone
		(layer "In2.Cu")
		(hatch none 0.5)
		(connect_pads
			(clearance 0)
		)
		(min_thickness 0.25)
		(keepout
			(tracks not_allowed)
			(vias allowed)
			(pads allowed)
			(copperpour not_allowed)
			(footprints allowed)
		)
		(placement
			(enabled no)
			(sheetname "")
		)
		(fill
			(thermal_gap 0.5)
			(thermal_bridge_width 0.5)
			(island_removal_mode 0)
		)
		(polygon
			(pts
				(xy 163.678616 -297.375326) (xy 165.177216 -297.375326) (xy 165.177216 -297.895264) (xy 163.678616 -297.895264)
			)
		)
	)
	(zone
		(layer "In2.Cu")
		(hatch none 0.5)
		(connect_pads
			(clearance 0)
		)
		(min_thickness 0.25)
		(keepout
			(tracks not_allowed)
			(vias allowed)
			(pads allowed)
			(copperpour not_allowed)
			(footprints allowed)
		)
		(placement
			(enabled no)
			(sheetname "")
		)
		(fill
			(thermal_gap 0.5)
			(thermal_bridge_width 0.5)
			(island_removal_mode 0)
		)
		(polygon
			(pts
				(xy 28.50261 -229.375208) (xy 30.00121 -229.375208) (xy 30.00121 -229.895146) (xy 28.50261 -229.895146)
			)
		)
	)
	(zone
		(layer "In2.Cu")
		(hatch none 0.5)
		(connect_pads
			(clearance 0)
		)
		(min_thickness 0.25)
		(keepout
			(tracks not_allowed)
			(vias allowed)
			(pads allowed)
			(copperpour not_allowed)
			(footprints allowed)
		)
		(placement
			(enabled no)
			(sheetname "")
		)
		(fill
			(thermal_gap 0.5)
			(thermal_bridge_width 0.5)
			(island_removal_mode 0)
		)
		(polygon
			(pts
				(xy 411.618684 -208.975198) (xy 413.117284 -208.975198) (xy 413.117284 -209.495136) (xy 411.618684 -209.495136)
			)
		)
	)
	(zone
		(layer "In2.Cu")
		(hatch none 0.5)
		(connect_pads
			(clearance 0)
		)
		(min_thickness 0.25)
		(keepout
			(tracks not_allowed)
			(vias allowed)
			(pads allowed)
			(copperpour not_allowed)
			(footprints allowed)
		)
		(placement
			(enabled no)
			(sheetname "")
		)
		(fill
			(thermal_gap 0.5)
			(thermal_bridge_width 0.5)
			(island_removal_mode 0)
		)
		(polygon
			(pts
				(xy 445.894968 -313.525154) (xy 447.393568 -313.525154) (xy 447.393568 -314.045092) (xy 445.894968 -314.045092)
			)
		)
	)
	(zone
		(layer "In2.Cu")
		(hatch none 0.5)
		(connect_pads
			(clearance 0)
		)
		(min_thickness 0.25)
		(keepout
			(tracks not_allowed)
			(vias allowed)
			(pads allowed)
			(copperpour not_allowed)
			(footprints allowed)
		)
		(placement
			(enabled no)
			(sheetname "")
		)
		(fill
			(thermal_gap 0.5)
			(thermal_bridge_width 0.5)
			(island_removal_mode 0)
		)
		(polygon
			(pts
				(xy 453.438768 -203.025248) (xy 454.937368 -203.025248) (xy 454.937368 -203.545186) (xy 453.438768 -203.545186)
			)
		)
	)
	(zone
		(layer "In2.Cu")
		(hatch none 0.5)
		(connect_pads
			(clearance 0)
		)
		(min_thickness 0.25)
		(keepout
			(tracks not_allowed)
			(vias allowed)
			(pads allowed)
			(copperpour not_allowed)
			(footprints allowed)
		)
		(placement
			(enabled no)
			(sheetname "")
		)
		(fill
			(thermal_gap 0.5)
			(thermal_bridge_width 0.5)
			(island_removal_mode 0)
		)
		(polygon
			(pts
				(xy 272.342864 -225.975164) (xy 273.841464 -225.975164) (xy 273.841464 -226.495102) (xy 272.342864 -226.495102)
			)
		)
	)
	(zone
		(layer "In2.Cu")
		(hatch none 0.5)
		(connect_pads
			(clearance 0)
		)
		(min_thickness 0.25)
		(keepout
			(tracks not_allowed)
			(vias allowed)
			(pads allowed)
			(copperpour not_allowed)
			(footprints allowed)
		)
		(placement
			(enabled no)
			(sheetname "")
		)
		(fill
			(thermal_gap 0.5)
			(thermal_bridge_width 0.5)
			(island_removal_mode 0)
		)
		(polygon
			(pts
				(xy 291.530786 -276.125178) (xy 293.029386 -276.125178) (xy 293.029386 -276.645116) (xy 291.530786 -276.645116)
			)
		)
	)
	(zone
		(layer "In2.Cu")
		(hatch none 0.5)
		(connect_pads
			(clearance 0)
		)
		(min_thickness 0.25)
		(keepout
			(tracks not_allowed)
			(vias allowed)
			(pads allowed)
			(copperpour not_allowed)
			(footprints allowed)
		)
		(placement
			(enabled no)
			(sheetname "")
		)
		(fill
			(thermal_gap 0.5)
			(thermal_bridge_width 0.5)
			(island_removal_mode 0)
		)
		(polygon
			(pts
				(xy 287.430718 -210.67522) (xy 288.929318 -210.67522) (xy 288.929318 -211.195158) (xy 287.430718 -211.195158)
			)
		)
	)
	(zone
		(layer "In2.Cu")
		(hatch none 0.5)
		(connect_pads
			(clearance 0)
		)
		(min_thickness 0.25)
		(keepout
			(tracks not_allowed)
			(vias allowed)
			(pads allowed)
			(copperpour not_allowed)
			(footprints allowed)
		)
		(placement
			(enabled no)
			(sheetname "")
		)
		(fill
			(thermal_gap 0.5)
			(thermal_bridge_width 0.5)
			(island_removal_mode 0)
		)
		(polygon
			(pts
				(xy 145.383504 -31.97733)
				(arc
					(start 145.383504 -32.117538)
					(mid 145.412713 -32.18742)
					(end 145.482818 -32.21609)
				)
				(arc
					(start 145.784062 -32.21609)
					(mid 145.854167 -32.18742)
					(end 145.883376 -32.117538)
				)
				(xy 145.883376 -31.97733) (xy 145.823432 -31.97733)
				(arc
					(start 145.823432 -31.408116)
					(mid 145.866931 -31.371747)
					(end 145.883376 -31.317438)
				)
				(arc
					(start 145.883376 -31.057342)
					(mid 145.867057 -31.00295)
					(end 145.823432 -30.966664)
				)
				(xy 145.823432 -30.39745) (xy 145.883376 -30.39745)
				(arc
					(start 145.883376 -30.257242)
					(mid 145.854167 -30.18736)
					(end 145.784062 -30.15869)
				)
				(arc
					(start 145.482818 -30.15869)
					(mid 145.412713 -30.18736)
					(end 145.383504 -30.257242)
				)
				(xy 145.383504 -30.39745) (xy 145.443448 -30.39745)
				(arc
					(start 145.443448 -30.966664)
					(mid 145.399949 -31.003033)
					(end 145.383504 -31.057342)
				)
				(arc
					(start 145.383504 -31.317438)
					(mid 145.399823 -31.37183)
					(end 145.443448 -31.408116)
				)
				(xy 145.443448 -31.97733)
			)
		)
	)
	(zone
		(layer "In2.Cu")
		(hatch none 0.5)
		(connect_pads
			(clearance 0)
		)
		(min_thickness 0.25)
		(keepout
			(tracks not_allowed)
			(vias allowed)
			(pads allowed)
			(copperpour not_allowed)
			(footprints allowed)
		)
		(placement
			(enabled no)
			(sheetname "")
		)
		(fill
			(thermal_gap 0.5)
			(thermal_bridge_width 0.5)
			(island_removal_mode 0)
		)
		(polygon
			(pts
				(xy 167.778684 -206.425292) (xy 169.277284 -206.425292) (xy 169.277284 -206.94523) (xy 167.778684 -206.94523)
			)
		)
	)
	(zone
		(layer "In2.Cu")
		(hatch none 0.5)
		(connect_pads
			(clearance 0)
		)
		(min_thickness 0.25)
		(keepout
			(tracks not_allowed)
			(vias allowed)
			(pads allowed)
			(copperpour not_allowed)
			(footprints allowed)
		)
		(placement
			(enabled no)
			(sheetname "")
		)
		(fill
			(thermal_gap 0.5)
			(thermal_bridge_width 0.5)
			(island_removal_mode 0)
		)
		(polygon
			(pts
				(xy 51.134772 -284.625288) (xy 52.633372 -284.625288) (xy 52.633372 -285.145226) (xy 51.134772 -285.145226)
			)
		)
	)
	(zone
		(layer "In2.Cu")
		(hatch none 0.5)
		(connect_pads
			(clearance 0)
		)
		(min_thickness 0.25)
		(keepout
			(tracks not_allowed)
			(vias allowed)
			(pads allowed)
			(copperpour not_allowed)
			(footprints allowed)
		)
		(placement
			(enabled no)
			(sheetname "")
		)
		(fill
			(thermal_gap 0.5)
			(thermal_bridge_width 0.5)
			(island_removal_mode 0)
		)
		(polygon
			(pts
				(xy 438.350914 -303.325276) (xy 439.849514 -303.325276) (xy 439.849514 -303.845214) (xy 438.350914 -303.845214)
			)
		)
	)
	(zone
		(layer "In2.Cu")
		(hatch none 0.5)
		(connect_pads
			(clearance 0)
		)
		(min_thickness 0.25)
		(keepout
			(tracks not_allowed)
			(vias allowed)
			(pads allowed)
			(copperpour not_allowed)
			(footprints allowed)
		)
		(placement
			(enabled no)
			(sheetname "")
		)
		(fill
			(thermal_gap 0.5)
			(thermal_bridge_width 0.5)
			(island_removal_mode 0)
		)
		(polygon
			(pts
				(xy 190.410846 -275.275294) (xy 191.909446 -275.275294) (xy 191.909446 -275.795232) (xy 190.410846 -275.795232)
			)
		)
	)
	(zone
		(layer "In2.Cu")
		(hatch none 0.5)
		(connect_pads
			(clearance 0)
		)
		(min_thickness 0.25)
		(keepout
			(tracks allowed)
			(vias allowed)
			(pads allowed)
			(copperpour allowed)
			(footprints allowed)
		)
		(placement
			(enabled no)
			(sheetname "")
		)
		(fill
			(thermal_gap 0.5)
			(thermal_bridge_width 0.5)
			(island_removal_mode 0)
		)
		(polygon
			(pts
				(xy 391.853928 -180.14696) (xy 391.853928 -179.600606) (xy 392.406378 -179.600606) (xy 392.406378 -180.14696)
			)
		)
	)
	(zone
		(layer "In2.Cu")
		(hatch none 0.5)
		(connect_pads
			(clearance 0)
		)
		(min_thickness 0.25)
		(keepout
			(tracks not_allowed)
			(vias allowed)
			(pads allowed)
			(copperpour not_allowed)
			(footprints allowed)
		)
		(placement
			(enabled no)
			(sheetname "")
		)
		(fill
			(thermal_gap 0.5)
			(thermal_bridge_width 0.5)
			(island_removal_mode 0)
		)
		(polygon
			(pts
				(xy 16.858742 -218.325192) (xy 18.357342 -218.325192) (xy 18.357342 -218.84513) (xy 16.858742 -218.84513)
			)
		)
	)
	(zone
		(layer "In2.Cu")
		(hatch none 0.5)
		(connect_pads
			(clearance 0)
		)
		(min_thickness 0.25)
		(keepout
			(tracks not_allowed)
			(vias allowed)
			(pads allowed)
			(copperpour not_allowed)
			(footprints allowed)
		)
		(placement
			(enabled no)
			(sheetname "")
		)
		(fill
			(thermal_gap 0.5)
			(thermal_bridge_width 0.5)
			(island_removal_mode 0)
		)
		(polygon
			(pts
				(xy 28.50261 -313.525154) (xy 30.00121 -313.525154) (xy 30.00121 -314.045092) (xy 28.50261 -314.045092)
			)
		)
	)
	(zone
		(layer "In2.Cu")
		(hatch none 0.5)
		(connect_pads
			(clearance 0)
		)
		(min_thickness 0.25)
		(keepout
			(tracks not_allowed)
			(vias allowed)
			(pads allowed)
			(copperpour not_allowed)
			(footprints allowed)
		)
		(placement
			(enabled no)
			(sheetname "")
		)
		(fill
			(thermal_gap 0.5)
			(thermal_bridge_width 0.5)
			(island_removal_mode 0)
		)
		(polygon
			(pts
				(xy 276.442932 -262.525256) (xy 277.941532 -262.525256) (xy 277.941532 -263.045194) (xy 276.442932 -263.045194)
			)
		)
	)
	(zone
		(layer "In2.Cu")
		(hatch none 0.5)
		(connect_pads
			(clearance 0)
		)
		(min_thickness 0.25)
		(keepout
			(tracks not_allowed)
			(vias allowed)
			(pads allowed)
			(copperpour not_allowed)
			(footprints allowed)
		)
		(placement
			(enabled no)
			(sheetname "")
		)
		(fill
			(thermal_gap 0.5)
			(thermal_bridge_width 0.5)
			(island_removal_mode 0)
		)
		(polygon
			(pts
				(xy 36.046664 -281.225244) (xy 37.545264 -281.225244) (xy 37.545264 -281.745182) (xy 36.046664 -281.745182)
			)
		)
	)
	(zone
		(layer "In2.Cu")
		(hatch none 0.5)
		(connect_pads
			(clearance 0)
		)
		(min_thickness 0.25)
		(keepout
			(tracks not_allowed)
			(vias allowed)
			(pads allowed)
			(copperpour not_allowed)
			(footprints allowed)
		)
		(placement
			(enabled no)
			(sheetname "")
		)
		(fill
			(thermal_gap 0.5)
			(thermal_bridge_width 0.5)
			(island_removal_mode 0)
		)
		(polygon
			(pts
				(xy 423.262806 -262.525256) (xy 424.761406 -262.525256) (xy 424.761406 -263.045194) (xy 423.262806 -263.045194)
			)
		)
	)
	(zone
		(layer "In2.Cu")
		(hatch none 0.5)
		(connect_pads
			(clearance 0)
		)
		(min_thickness 0.25)
		(keepout
			(tracks not_allowed)
			(vias allowed)
			(pads allowed)
			(copperpour not_allowed)
			(footprints allowed)
		)
		(placement
			(enabled no)
			(sheetname "")
		)
		(fill
			(thermal_gap 0.5)
			(thermal_bridge_width 0.5)
			(island_removal_mode 0)
		)
		(polygon
			(pts
				(xy 16.858742 -237.02518) (xy 18.357342 -237.02518) (xy 18.357342 -237.545118) (xy 16.858742 -237.545118)
			)
		)
	)
	(zone
		(layer "In2.Cu")
		(hatch none 0.5)
		(connect_pads
			(clearance 0)
		)
		(min_thickness 0.25)
		(keepout
			(tracks not_allowed)
			(vias allowed)
			(pads allowed)
			(copperpour not_allowed)
			(footprints allowed)
		)
		(placement
			(enabled no)
			(sheetname "")
		)
		(fill
			(thermal_gap 0.5)
			(thermal_bridge_width 0.5)
			(island_removal_mode 0)
		)
		(polygon
			(pts
				(xy 291.530786 -275.275294) (xy 293.029386 -275.275294) (xy 293.029386 -275.795232) (xy 291.530786 -275.795232)
			)
		)
	)
	(zone
		(layer "In2.Cu")
		(hatch none 0.5)
		(connect_pads
			(clearance 0)
		)
		(min_thickness 0.25)
		(keepout
			(tracks not_allowed)
			(vias allowed)
			(pads allowed)
			(copperpour not_allowed)
			(footprints allowed)
		)
		(placement
			(enabled no)
			(sheetname "")
		)
		(fill
			(thermal_gap 0.5)
			(thermal_bridge_width 0.5)
			(island_removal_mode 0)
		)
		(polygon
			(pts
				(xy 54.578758 -289.725354) (xy 56.077358 -289.725354) (xy 56.077358 -290.245292) (xy 54.578758 -290.245292)
			)
		)
	)
	(zone
		(layer "In2.Cu")
		(hatch none 0.5)
		(connect_pads
			(clearance 0)
		)
		(min_thickness 0.25)
		(keepout
			(tracks not_allowed)
			(vias allowed)
			(pads allowed)
			(copperpour not_allowed)
			(footprints allowed)
		)
		(placement
			(enabled no)
			(sheetname "")
		)
		(fill
			(thermal_gap 0.5)
			(thermal_bridge_width 0.5)
			(island_removal_mode 0)
		)
		(polygon
			(pts
				(xy 20.95881 -247.225312) (xy 22.45741 -247.225312) (xy 22.45741 -247.74525) (xy 20.95881 -247.74525)
			)
		)
	)
	(zone
		(layer "In2.Cu")
		(hatch none 0.5)
		(connect_pads
			(clearance 0)
		)
		(min_thickness 0.25)
		(keepout
			(tracks not_allowed)
			(vias allowed)
			(pads allowed)
			(copperpour not_allowed)
			(footprints allowed)
		)
		(placement
			(enabled no)
			(sheetname "")
		)
		(fill
			(thermal_gap 0.5)
			(thermal_bridge_width 0.5)
			(island_removal_mode 0)
		)
		(polygon
			(pts
				(xy 415.718752 -226.825302) (xy 417.217352 -226.825302) (xy 417.217352 -227.34524) (xy 415.718752 -227.34524)
			)
		)
	)
	(zone
		(layer "In2.Cu")
		(hatch none 0.5)
		(connect_pads
			(clearance 0)
		)
		(min_thickness 0.25)
		(keepout
			(tracks not_allowed)
			(vias allowed)
			(pads allowed)
			(copperpour not_allowed)
			(footprints allowed)
		)
		(placement
			(enabled no)
			(sheetname "")
		)
		(fill
			(thermal_gap 0.5)
			(thermal_bridge_width 0.5)
			(island_removal_mode 0)
		)
		(polygon
			(pts
				(xy 167.778684 -250.625102) (xy 169.277284 -250.625102) (xy 169.277284 -251.14504) (xy 167.778684 -251.14504)
			)
		)
	)
	(zone
		(layer "In2.Cu")
		(hatch none 0.5)
		(connect_pads
			(clearance 0)
		)
		(min_thickness 0.25)
		(keepout
			(tracks not_allowed)
			(vias allowed)
			(pads allowed)
			(copperpour not_allowed)
			(footprints allowed)
		)
		(placement
			(enabled no)
			(sheetname "")
		)
		(fill
			(thermal_gap 0.5)
			(thermal_bridge_width 0.5)
			(island_removal_mode 0)
		)
		(polygon
			(pts
				(xy 201.398632 -272.725134) (xy 202.897232 -272.725134) (xy 202.897232 -273.245072) (xy 201.398632 -273.245072)
			)
		)
	)
	(zone
		(layer "In2.Cu")
		(hatch none 0.5)
		(connect_pads
			(clearance 0)
		)
		(min_thickness 0.25)
		(keepout
			(tracks not_allowed)
			(vias allowed)
			(pads allowed)
			(copperpour not_allowed)
			(footprints allowed)
		)
		(placement
			(enabled no)
			(sheetname "")
		)
		(fill
			(thermal_gap 0.5)
			(thermal_bridge_width 0.5)
			(island_removal_mode 0)
		)
		(polygon
			(pts
				(xy 276.442932 -223.425258) (xy 277.941532 -223.425258) (xy 277.941532 -223.945196) (xy 276.442932 -223.945196)
			)
		)
	)
	(zone
		(layer "In2.Cu")
		(hatch none 0.5)
		(connect_pads
			(clearance 0)
		)
		(min_thickness 0.25)
		(keepout
			(tracks not_allowed)
			(vias allowed)
			(pads allowed)
			(copperpour not_allowed)
			(footprints allowed)
		)
		(placement
			(enabled no)
			(sheetname "")
		)
		(fill
			(thermal_gap 0.5)
			(thermal_bridge_width 0.5)
			(island_removal_mode 0)
		)
		(polygon
			(pts
				(xy 294.974772 -238.725202) (xy 296.473372 -238.725202) (xy 296.473372 -239.24514) (xy 294.974772 -239.24514)
			)
		)
	)
	(zone
		(layer "In2.Cu")
		(hatch none 0.5)
		(connect_pads
			(clearance 0)
		)
		(min_thickness 0.25)
		(keepout
			(tracks not_allowed)
			(vias allowed)
			(pads allowed)
			(copperpour not_allowed)
			(footprints allowed)
		)
		(placement
			(enabled no)
			(sheetname "")
		)
		(fill
			(thermal_gap 0.5)
			(thermal_bridge_width 0.5)
			(island_removal_mode 0)
		)
		(polygon
			(pts
				(xy 268.898878 -247.225312) (xy 270.397478 -247.225312) (xy 270.397478 -247.74525) (xy 268.898878 -247.74525)
			)
		)
	)
	(zone
		(layer "In2.Cu")
		(hatch none 0.5)
		(connect_pads
			(clearance 0)
		)
		(min_thickness 0.25)
		(keepout
			(tracks not_allowed)
			(vias allowed)
			(pads allowed)
			(copperpour not_allowed)
			(footprints allowed)
		)
		(placement
			(enabled no)
			(sheetname "")
		)
		(fill
			(thermal_gap 0.5)
			(thermal_bridge_width 0.5)
			(island_removal_mode 0)
		)
		(polygon
			(pts
				(xy 306.618894 -245.52529) (xy 308.117494 -245.52529) (xy 308.117494 -246.045228) (xy 306.618894 -246.045228)
			)
		)
	)
	(zone
		(layer "In2.Cu")
		(hatch none 0.5)
		(connect_pads
			(clearance 0)
		)
		(min_thickness 0.25)
		(keepout
			(tracks not_allowed)
			(vias allowed)
			(pads allowed)
			(copperpour not_allowed)
			(footprints allowed)
		)
		(placement
			(enabled no)
			(sheetname "")
		)
		(fill
			(thermal_gap 0.5)
			(thermal_bridge_width 0.5)
			(island_removal_mode 0)
		)
		(polygon
			(pts
				(xy 279.886664 -268.475206) (xy 281.385264 -268.475206) (xy 281.385264 -268.995144) (xy 279.886664 -268.995144)
			)
		)
	)
	(zone
		(layer "In2.Cu")
		(hatch none 0.5)
		(connect_pads
			(clearance 0)
		)
		(min_thickness 0.25)
		(keepout
			(tracks not_allowed)
			(vias allowed)
			(pads allowed)
			(copperpour not_allowed)
			(footprints allowed)
		)
		(placement
			(enabled no)
			(sheetname "")
		)
		(fill
			(thermal_gap 0.5)
			(thermal_bridge_width 0.5)
			(island_removal_mode 0)
		)
		(polygon
			(pts
				(xy 306.618894 -221.725236) (xy 308.117494 -221.725236) (xy 308.117494 -222.245174) (xy 306.618894 -222.245174)
			)
		)
	)
	(zone
		(layer "In2.Cu")
		(hatch none 0.5)
		(connect_pads
			(clearance 0)
		)
		(min_thickness 0.25)
		(keepout
			(tracks not_allowed)
			(vias allowed)
			(pads allowed)
			(copperpour not_allowed)
			(footprints allowed)
		)
		(placement
			(enabled no)
			(sheetname "")
		)
		(fill
			(thermal_gap 0.5)
			(thermal_bridge_width 0.5)
			(island_removal_mode 0)
		)
		(polygon
			(pts
				(xy 299.07484 -228.525324) (xy 300.57344 -228.525324) (xy 300.57344 -229.045262) (xy 299.07484 -229.045262)
			)
		)
	)
	(zone
		(layer "In2.Cu")
		(hatch none 0.5)
		(connect_pads
			(clearance 0)
		)
		(min_thickness 0.25)
		(keepout
			(tracks allowed)
			(vias allowed)
			(pads allowed)
			(copperpour allowed)
			(footprints allowed)
		)
		(placement
			(enabled no)
			(sheetname "")
		)
		(fill
			(thermal_gap 0.5)
			(thermal_bridge_width 0.5)
			(island_removal_mode 0)
		)
		(polygon
			(pts
				(xy 90.55481 -337.379818) (xy 90.55481 -336.757518) (xy 91.10599 -336.757518) (xy 91.10599 -337.379818)
			)
		)
	)
	(zone
		(layer "In2.Cu")
		(hatch none 0.5)
		(connect_pads
			(clearance 0)
		)
		(min_thickness 0.25)
		(keepout
			(tracks not_allowed)
			(vias allowed)
			(pads allowed)
			(copperpour not_allowed)
			(footprints allowed)
		)
		(placement
			(enabled no)
			(sheetname "")
		)
		(fill
			(thermal_gap 0.5)
			(thermal_bridge_width 0.5)
			(island_removal_mode 0)
		)
		(polygon
			(pts
				(xy 11.171682 -106.67238)
				(arc
					(start 11.171682 -106.812588)
					(mid 11.200891 -106.88247)
					(end 11.270996 -106.91114)
				)
				(arc
					(start 11.57224 -106.91114)
					(mid 11.642345 -106.88247)
					(end 11.671554 -106.812588)
				)
				(xy 11.671554 -106.67238) (xy 11.61161 -106.67238)
				(arc
					(start 11.61161 -106.103166)
					(mid 11.655109 -106.066797)
					(end 11.671554 -106.012488)
				)
				(arc
					(start 11.671554 -105.752392)
					(mid 11.655235 -105.698)
					(end 11.61161 -105.661714)
				)
				(xy 11.61161 -105.0925) (xy 11.671554 -105.0925)
				(arc
					(start 11.671554 -104.952292)
					(mid 11.642345 -104.88241)
					(end 11.57224 -104.85374)
				)
				(arc
					(start 11.270996 -104.85374)
					(mid 11.200891 -104.88241)
					(end 11.171682 -104.952292)
				)
				(xy 11.171682 -105.0925) (xy 11.231626 -105.0925)
				(arc
					(start 11.231626 -105.661714)
					(mid 11.188127 -105.698083)
					(end 11.171682 -105.752392)
				)
				(arc
					(start 11.171682 -106.012488)
					(mid 11.188001 -106.06688)
					(end 11.231626 -106.103166)
				)
				(xy 11.231626 -106.67238)
			)
		)
	)
	(zone
		(layer "In2.Cu")
		(hatch none 0.5)
		(connect_pads
			(clearance 0)
		)
		(min_thickness 0.25)
		(keepout
			(tracks not_allowed)
			(vias allowed)
			(pads allowed)
			(copperpour not_allowed)
			(footprints allowed)
		)
		(placement
			(enabled no)
			(sheetname "")
		)
		(fill
			(thermal_gap 0.5)
			(thermal_bridge_width 0.5)
			(island_removal_mode 0)
		)
		(polygon
			(pts
				(xy 201.398632 -305.025298) (xy 202.897232 -305.025298) (xy 202.897232 -305.545236) (xy 201.398632 -305.545236)
			)
		)
	)
	(zone
		(layer "In2.Cu")
		(hatch none 0.5)
		(connect_pads
			(clearance 0)
		)
		(min_thickness 0.25)
		(keepout
			(tracks not_allowed)
			(vias allowed)
			(pads allowed)
			(copperpour not_allowed)
			(footprints allowed)
		)
		(placement
			(enabled no)
			(sheetname "")
		)
		(fill
			(thermal_gap 0.5)
			(thermal_bridge_width 0.5)
			(island_removal_mode 0)
		)
		(polygon
			(pts
				(xy 58.678826 -275.275294) (xy 60.177426 -275.275294) (xy 60.177426 -275.795232) (xy 58.678826 -275.795232)
			)
		)
	)
	(zone
		(layer "In2.Cu")
		(hatch none 0.5)
		(connect_pads
			(clearance 0)
		)
		(min_thickness 0.25)
		(keepout
			(tracks not_allowed)
			(vias allowed)
			(pads allowed)
			(copperpour not_allowed)
			(footprints allowed)
		)
		(placement
			(enabled no)
			(sheetname "")
		)
		(fill
			(thermal_gap 0.5)
			(thermal_bridge_width 0.5)
			(island_removal_mode 0)
		)
		(polygon
			(pts
				(xy 276.442932 -232.775252) (xy 277.941532 -232.775252) (xy 277.941532 -233.29519) (xy 276.442932 -233.29519)
			)
		)
	)
	(zone
		(layer "In2.Cu")
		(hatch none 0.5)
		(connect_pads
			(clearance 0)
		)
		(min_thickness 0.25)
		(keepout
			(tracks not_allowed)
			(vias allowed)
			(pads allowed)
			(copperpour not_allowed)
			(footprints allowed)
		)
		(placement
			(enabled no)
			(sheetname "")
		)
		(fill
			(thermal_gap 0.5)
			(thermal_bridge_width 0.5)
			(island_removal_mode 0)
		)
		(polygon
			(pts
				(xy 449.3387 -313.525154) (xy 450.8373 -313.525154) (xy 450.8373 -314.045092) (xy 449.3387 -314.045092)
			)
		)
	)
	(zone
		(layer "In2.Cu")
		(hatch none 0.5)
		(connect_pads
			(clearance 0)
		)
		(min_thickness 0.25)
		(keepout
			(tracks not_allowed)
			(vias allowed)
			(pads allowed)
			(copperpour not_allowed)
			(footprints allowed)
		)
		(placement
			(enabled no)
			(sheetname "")
		)
		(fill
			(thermal_gap 0.5)
			(thermal_bridge_width 0.5)
			(island_removal_mode 0)
		)
		(polygon
			(pts
				(xy 423.262806 -313.525154) (xy 424.761406 -313.525154) (xy 424.761406 -314.045092) (xy 423.262806 -314.045092)
			)
		)
	)
	(zone
		(layer "In2.Cu")
		(hatch none 0.5)
		(connect_pads
			(clearance 0)
		)
		(min_thickness 0.25)
		(keepout
			(tracks not_allowed)
			(vias allowed)
			(pads allowed)
			(copperpour not_allowed)
			(footprints allowed)
		)
		(placement
			(enabled no)
			(sheetname "")
		)
		(fill
			(thermal_gap 0.5)
			(thermal_bridge_width 0.5)
			(island_removal_mode 0)
		)
		(polygon
			(pts
				(xy 445.894968 -209.825336) (xy 447.393568 -209.825336) (xy 447.393568 -210.345274) (xy 445.894968 -210.345274)
			)
		)
	)
	(zone
		(layer "In2.Cu")
		(hatch none 0.5)
		(connect_pads
			(clearance 0)
		)
		(min_thickness 0.25)
		(keepout
			(tracks not_allowed)
			(vias allowed)
			(pads allowed)
			(copperpour not_allowed)
			(footprints allowed)
		)
		(placement
			(enabled no)
			(sheetname "")
		)
		(fill
			(thermal_gap 0.5)
			(thermal_bridge_width 0.5)
			(island_removal_mode 0)
		)
		(polygon
			(pts
				(xy 430.80686 -198.77532) (xy 432.30546 -198.77532) (xy 432.30546 -199.295258) (xy 430.80686 -199.295258)
			)
		)
	)
	(zone
		(layer "In2.Cu")
		(hatch none 0.5)
		(connect_pads
			(clearance 0)
		)
		(min_thickness 0.25)
		(keepout
			(tracks not_allowed)
			(vias allowed)
			(pads allowed)
			(copperpour not_allowed)
			(footprints allowed)
		)
		(placement
			(enabled no)
			(sheetname "")
		)
		(fill
			(thermal_gap 0.5)
			(thermal_bridge_width 0.5)
			(island_removal_mode 0)
		)
		(polygon
			(pts
				(xy 419.162738 -239.57534) (xy 420.661338 -239.57534) (xy 420.661338 -240.095278) (xy 419.162738 -240.095278)
			)
		)
	)
	(zone
		(layer "In2.Cu")
		(hatch none 0.5)
		(connect_pads
			(clearance 0)
		)
		(min_thickness 0.25)
		(keepout
			(tracks not_allowed)
			(vias allowed)
			(pads allowed)
			(copperpour not_allowed)
			(footprints allowed)
		)
		(placement
			(enabled no)
			(sheetname "")
		)
		(fill
			(thermal_gap 0.5)
			(thermal_bridge_width 0.5)
			(island_removal_mode 0)
		)
		(polygon
			(pts
				(xy 31.946596 -214.925148) (xy 33.445196 -214.925148) (xy 33.445196 -215.445086) (xy 31.946596 -215.445086)
			)
		)
	)
	(zone
		(layer "In2.Cu")
		(hatch none 0.5)
		(connect_pads
			(clearance 0)
		)
		(min_thickness 0.25)
		(keepout
			(tracks not_allowed)
			(vias allowed)
			(pads allowed)
			(copperpour not_allowed)
			(footprints allowed)
		)
		(placement
			(enabled no)
			(sheetname "")
		)
		(fill
			(thermal_gap 0.5)
			(thermal_bridge_width 0.5)
			(island_removal_mode 0)
		)
		(polygon
			(pts
				(xy 419.162738 -205.575154) (xy 420.661338 -205.575154) (xy 420.661338 -206.095092) (xy 419.162738 -206.095092)
			)
		)
	)
	(zone
		(layer "In2.Cu")
		(hatch none 0.5)
		(connect_pads
			(clearance 0)
		)
		(min_thickness 0.25)
		(keepout
			(tracks not_allowed)
			(vias allowed)
			(pads allowed)
			(copperpour not_allowed)
			(footprints allowed)
		)
		(placement
			(enabled no)
			(sheetname "")
		)
		(fill
			(thermal_gap 0.5)
			(thermal_bridge_width 0.5)
			(island_removal_mode 0)
		)
		(polygon
			(pts
				(xy 299.07484 -204.72527) (xy 300.57344 -204.72527) (xy 300.57344 -205.245208) (xy 299.07484 -205.245208)
			)
		)
	)
	(zone
		(layer "In2.Cu")
		(hatch none 0.5)
		(connect_pads
			(clearance 0)
		)
		(min_thickness 0.25)
		(keepout
			(tracks not_allowed)
			(vias allowed)
			(pads allowed)
			(copperpour not_allowed)
			(footprints allowed)
		)
		(placement
			(enabled no)
			(sheetname "")
		)
		(fill
			(thermal_gap 0.5)
			(thermal_bridge_width 0.5)
			(island_removal_mode 0)
		)
		(polygon
			(pts
				(xy 306.618894 -315.225176) (xy 308.117494 -315.225176) (xy 308.117494 -315.745114) (xy 306.618894 -315.745114)
			)
		)
	)
	(zone
		(layer "In2.Cu")
		(hatch none 0.5)
		(connect_pads
			(clearance 0)
		)
		(min_thickness 0.25)
		(keepout
			(tracks not_allowed)
			(vias allowed)
			(pads allowed)
			(copperpour not_allowed)
			(footprints allowed)
		)
		(placement
			(enabled no)
			(sheetname "")
		)
		(fill
			(thermal_gap 0.5)
			(thermal_bridge_width 0.5)
			(island_removal_mode 0)
		)
		(polygon
			(pts
				(xy 438.350914 -301.625254) (xy 439.849514 -301.625254) (xy 439.849514 -302.145192) (xy 438.350914 -302.145192)
			)
		)
	)
	(zone
		(layer "In2.Cu")
		(hatch none 0.5)
		(connect_pads
			(clearance 0)
		)
		(min_thickness 0.25)
		(keepout
			(tracks not_allowed)
			(vias allowed)
			(pads allowed)
			(copperpour not_allowed)
			(footprints allowed)
		)
		(placement
			(enabled no)
			(sheetname "")
		)
		(fill
			(thermal_gap 0.5)
			(thermal_bridge_width 0.5)
			(island_removal_mode 0)
		)
		(polygon
			(pts
				(xy 54.578758 -311.825132) (xy 56.077358 -311.825132) (xy 56.077358 -312.34507) (xy 54.578758 -312.34507)
			)
		)
	)
	(zone
		(layer "In2.Cu")
		(hatch none 0.5)
		(connect_pads
			(clearance 0)
		)
		(min_thickness 0.25)
		(keepout
			(tracks not_allowed)
			(vias allowed)
			(pads allowed)
			(copperpour not_allowed)
			(footprints allowed)
		)
		(placement
			(enabled no)
			(sheetname "")
		)
		(fill
			(thermal_gap 0.5)
			(thermal_bridge_width 0.5)
			(island_removal_mode 0)
		)
		(polygon
			(pts
				(xy 36.046664 -206.425292) (xy 37.545264 -206.425292) (xy 37.545264 -206.94523) (xy 36.046664 -206.94523)
			)
		)
	)
	(zone
		(layer "In2.Cu")
		(hatch none 0.5)
		(connect_pads
			(clearance 0)
		)
		(min_thickness 0.25)
		(keepout
			(tracks not_allowed)
			(vias allowed)
			(pads allowed)
			(copperpour not_allowed)
			(footprints allowed)
		)
		(placement
			(enabled no)
			(sheetname "")
		)
		(fill
			(thermal_gap 0.5)
			(thermal_bridge_width 0.5)
			(island_removal_mode 0)
		)
		(polygon
			(pts
				(xy 434.250846 -302.475138) (xy 435.749446 -302.475138) (xy 435.749446 -302.995076) (xy 434.250846 -302.995076)
			)
		)
	)
	(zone
		(layer "In2.Cu")
		(hatch none 0.5)
		(connect_pads
			(clearance 0)
		)
		(min_thickness 0.25)
		(keepout
			(tracks not_allowed)
			(vias allowed)
			(pads allowed)
			(copperpour not_allowed)
			(footprints allowed)
		)
		(placement
			(enabled no)
			(sheetname "")
		)
		(fill
			(thermal_gap 0.5)
			(thermal_bridge_width 0.5)
			(island_removal_mode 0)
		)
		(polygon
			(pts
				(xy 283.986732 -232.775252) (xy 285.485332 -232.775252) (xy 285.485332 -233.29519) (xy 283.986732 -233.29519)
			)
		)
	)
	(zone
		(layer "In2.Cu")
		(hatch none 0.5)
		(connect_pads
			(clearance 0)
		)
		(min_thickness 0.25)
		(keepout
			(tracks not_allowed)
			(vias allowed)
			(pads allowed)
			(copperpour not_allowed)
			(footprints allowed)
		)
		(placement
			(enabled no)
			(sheetname "")
		)
		(fill
			(thermal_gap 0.5)
			(thermal_bridge_width 0.5)
			(island_removal_mode 0)
		)
		(polygon
			(pts
				(xy 445.894968 -206.425292) (xy 447.393568 -206.425292) (xy 447.393568 -206.94523) (xy 445.894968 -206.94523)
			)
		)
	)
	(zone
		(layer "In2.Cu")
		(hatch none 0.5)
		(connect_pads
			(clearance 0)
		)
		(min_thickness 0.25)
		(keepout
			(tracks not_allowed)
			(vias allowed)
			(pads allowed)
			(copperpour not_allowed)
			(footprints allowed)
		)
		(placement
			(enabled no)
			(sheetname "")
		)
		(fill
			(thermal_gap 0.5)
			(thermal_bridge_width 0.5)
			(island_removal_mode 0)
		)
		(polygon
			(pts
				(xy 175.322738 -285.475172) (xy 176.821338 -285.475172) (xy 176.821338 -285.99511) (xy 175.322738 -285.99511)
			)
		)
	)
	(zone
		(layer "In2.Cu")
		(hatch none 0.5)
		(connect_pads
			(clearance 0)
		)
		(min_thickness 0.25)
		(keepout
			(tracks not_allowed)
			(vias allowed)
			(pads allowed)
			(copperpour not_allowed)
			(footprints allowed)
		)
		(placement
			(enabled no)
			(sheetname "")
		)
		(fill
			(thermal_gap 0.5)
			(thermal_bridge_width 0.5)
			(island_removal_mode 0)
		)
		(polygon
			(pts
				(xy 36.046664 -288.875216) (xy 37.545264 -288.875216) (xy 37.545264 -289.395154) (xy 36.046664 -289.395154)
			)
		)
	)
	(zone
		(layer "In2.Cu")
		(hatch none 0.5)
		(connect_pads
			(clearance 0)
		)
		(min_thickness 0.25)
		(keepout
			(tracks not_allowed)
			(vias allowed)
			(pads allowed)
			(copperpour not_allowed)
			(footprints allowed)
		)
		(placement
			(enabled no)
			(sheetname "")
		)
		(fill
			(thermal_gap 0.5)
			(thermal_bridge_width 0.5)
			(island_removal_mode 0)
		)
		(polygon
			(pts
				(xy 445.894968 -254.025146) (xy 447.393568 -254.025146) (xy 447.393568 -254.545084) (xy 445.894968 -254.545084)
			)
		)
	)
	(zone
		(layer "In2.Cu")
		(hatch none 0.5)
		(connect_pads
			(clearance 0)
		)
		(min_thickness 0.25)
		(keepout
			(tracks not_allowed)
			(vias allowed)
			(pads allowed)
			(copperpour not_allowed)
			(footprints allowed)
		)
		(placement
			(enabled no)
			(sheetname "")
		)
		(fill
			(thermal_gap 0.5)
			(thermal_bridge_width 0.5)
			(island_removal_mode 0)
		)
		(polygon
			(pts
				(xy 36.046664 -271.87525) (xy 37.545264 -271.87525) (xy 37.545264 -272.395188) (xy 36.046664 -272.395188)
			)
		)
	)
	(zone
		(layer "In2.Cu")
		(hatch none 0.5)
		(connect_pads
			(clearance 0)
		)
		(min_thickness 0.25)
		(keepout
			(tracks not_allowed)
			(vias allowed)
			(pads allowed)
			(copperpour not_allowed)
			(footprints allowed)
		)
		(placement
			(enabled no)
			(sheetname "")
		)
		(fill
			(thermal_gap 0.5)
			(thermal_bridge_width 0.5)
			(island_removal_mode 0)
		)
		(polygon
			(pts
				(xy 171.22267 -242.97513) (xy 172.72127 -242.97513) (xy 172.72127 -243.495068) (xy 171.22267 -243.495068)
			)
		)
	)
	(zone
		(layer "In2.Cu")
		(hatch none 0.5)
		(connect_pads
			(clearance 0)
		)
		(min_thickness 0.25)
		(keepout
			(tracks not_allowed)
			(vias allowed)
			(pads allowed)
			(copperpour not_allowed)
			(footprints allowed)
		)
		(placement
			(enabled no)
			(sheetname "")
		)
		(fill
			(thermal_gap 0.5)
			(thermal_bridge_width 0.5)
			(island_removal_mode 0)
		)
		(polygon
			(pts
				(xy 16.858742 -242.97513) (xy 18.357342 -242.97513) (xy 18.357342 -243.495068) (xy 16.858742 -243.495068)
			)
		)
	)
	(zone
		(layer "In2.Cu")
		(hatch none 0.5)
		(connect_pads
			(clearance 0)
		)
		(min_thickness 0.25)
		(keepout
			(tracks not_allowed)
			(vias allowed)
			(pads allowed)
			(copperpour not_allowed)
			(footprints allowed)
		)
		(placement
			(enabled no)
			(sheetname "")
		)
		(fill
			(thermal_gap 0.5)
			(thermal_bridge_width 0.5)
			(island_removal_mode 0)
		)
		(polygon
			(pts
				(xy 283.986732 -273.575272) (xy 285.485332 -273.575272) (xy 285.485332 -274.09521) (xy 283.986732 -274.09521)
			)
		)
	)
	(zone
		(layer "In2.Cu")
		(hatch none 0.5)
		(connect_pads
			(clearance 0)
		)
		(min_thickness 0.25)
		(keepout
			(tracks not_allowed)
			(vias allowed)
			(pads allowed)
			(copperpour not_allowed)
			(footprints allowed)
		)
		(placement
			(enabled no)
			(sheetname "")
		)
		(fill
			(thermal_gap 0.5)
			(thermal_bridge_width 0.5)
			(island_removal_mode 0)
		)
		(polygon
			(pts
				(xy 268.898878 -223.425258) (xy 270.397478 -223.425258) (xy 270.397478 -223.945196) (xy 268.898878 -223.945196)
			)
		)
	)
	(zone
		(layer "In2.Cu")
		(hatch none 0.5)
		(connect_pads
			(clearance 0)
		)
		(min_thickness 0.25)
		(keepout
			(tracks not_allowed)
			(vias allowed)
			(pads allowed)
			(copperpour not_allowed)
			(footprints allowed)
		)
		(placement
			(enabled no)
			(sheetname "")
		)
		(fill
			(thermal_gap 0.5)
			(thermal_bridge_width 0.5)
			(island_removal_mode 0)
		)
		(polygon
			(pts
				(xy 449.3387 -297.375326) (xy 450.8373 -297.375326) (xy 450.8373 -297.895264) (xy 449.3387 -297.895264)
			)
		)
	)
	(zone
		(layer "In2.Cu")
		(hatch none 0.5)
		(connect_pads
			(clearance 0)
		)
		(min_thickness 0.25)
		(keepout
			(tracks not_allowed)
			(vias allowed)
			(pads allowed)
			(copperpour not_allowed)
			(footprints allowed)
		)
		(placement
			(enabled no)
			(sheetname "")
		)
		(fill
			(thermal_gap 0.5)
			(thermal_bridge_width 0.5)
			(island_removal_mode 0)
		)
		(polygon
			(pts
				(xy 201.398632 -265.075162) (xy 202.897232 -265.075162) (xy 202.897232 -265.5951) (xy 201.398632 -265.5951)
			)
		)
	)
	(zone
		(layer "In2.Cu")
		(hatch none 0.5)
		(connect_pads
			(clearance 0)
		)
		(min_thickness 0.25)
		(keepout
			(tracks not_allowed)
			(vias allowed)
			(pads allowed)
			(copperpour not_allowed)
			(footprints allowed)
		)
		(placement
			(enabled no)
			(sheetname "")
		)
		(fill
			(thermal_gap 0.5)
			(thermal_bridge_width 0.5)
			(island_removal_mode 0)
		)
		(polygon
			(pts
				(xy 175.322738 -303.325276) (xy 176.821338 -303.325276) (xy 176.821338 -303.845214) (xy 175.322738 -303.845214)
			)
		)
	)
	(zone
		(layer "In2.Cu")
		(hatch none 0.5)
		(connect_pads
			(clearance 0)
		)
		(min_thickness 0.25)
		(keepout
			(tracks not_allowed)
			(vias allowed)
			(pads allowed)
			(copperpour not_allowed)
			(footprints allowed)
		)
		(placement
			(enabled no)
			(sheetname "")
		)
		(fill
			(thermal_gap 0.5)
			(thermal_bridge_width 0.5)
			(island_removal_mode 0)
		)
		(polygon
			(pts
				(xy 197.954646 -282.925266) (xy 199.453246 -282.925266) (xy 199.453246 -283.445204) (xy 197.954646 -283.445204)
			)
		)
	)
	(zone
		(layer "In2.Cu")
		(hatch none 0.5)
		(connect_pads
			(clearance 0)
		)
		(min_thickness 0.25)
		(keepout
			(tracks not_allowed)
			(vias allowed)
			(pads allowed)
			(copperpour not_allowed)
			(footprints allowed)
		)
		(placement
			(enabled no)
			(sheetname "")
		)
		(fill
			(thermal_gap 0.5)
			(thermal_bridge_width 0.5)
			(island_removal_mode 0)
		)
		(polygon
			(pts
				(xy 54.578758 -239.57534) (xy 56.077358 -239.57534) (xy 56.077358 -240.095278) (xy 54.578758 -240.095278)
			)
		)
	)
	(zone
		(layer "In2.Cu")
		(hatch none 0.5)
		(connect_pads
			(clearance 0)
		)
		(min_thickness 0.25)
		(keepout
			(tracks not_allowed)
			(vias allowed)
			(pads allowed)
			(copperpour not_allowed)
			(footprints allowed)
		)
		(placement
			(enabled no)
			(sheetname "")
		)
		(fill
			(thermal_gap 0.5)
			(thermal_bridge_width 0.5)
			(island_removal_mode 0)
		)
		(polygon
			(pts
				(xy 453.438768 -236.175296) (xy 454.937368 -236.175296) (xy 454.937368 -236.695234) (xy 453.438768 -236.695234)
			)
		)
	)
	(zone
		(layer "In2.Cu")
		(hatch none 0.5)
		(connect_pads
			(clearance 0)
		)
		(min_thickness 0.25)
		(keepout
			(tracks not_allowed)
			(vias allowed)
			(pads allowed)
			(copperpour not_allowed)
			(footprints allowed)
		)
		(placement
			(enabled no)
			(sheetname "")
		)
		(fill
			(thermal_gap 0.5)
			(thermal_bridge_width 0.5)
			(island_removal_mode 0)
		)
		(polygon
			(pts
				(xy 426.706792 -311.825132) (xy 428.205392 -311.825132) (xy 428.205392 -312.34507) (xy 426.706792 -312.34507)
			)
		)
	)
	(zone
		(layer "In2.Cu")
		(hatch none 0.5)
		(connect_pads
			(clearance 0)
		)
		(min_thickness 0.25)
		(keepout
			(tracks not_allowed)
			(vias allowed)
			(pads allowed)
			(copperpour not_allowed)
			(footprints allowed)
		)
		(placement
			(enabled no)
			(sheetname "")
		)
		(fill
			(thermal_gap 0.5)
			(thermal_bridge_width 0.5)
			(island_removal_mode 0)
		)
		(polygon
			(pts
				(xy 434.250846 -220.025214) (xy 435.749446 -220.025214) (xy 435.749446 -220.545152) (xy 434.250846 -220.545152)
			)
		)
	)
	(zone
		(layer "In2.Cu")
		(hatch none 0.5)
		(connect_pads
			(clearance 0)
		)
		(min_thickness 0.25)
		(keepout
			(tracks not_allowed)
			(vias allowed)
			(pads allowed)
			(copperpour not_allowed)
			(footprints allowed)
		)
		(placement
			(enabled no)
			(sheetname "")
		)
		(fill
			(thermal_gap 0.5)
			(thermal_bridge_width 0.5)
			(island_removal_mode 0)
		)
		(polygon
			(pts
				(xy 268.898878 -269.325344) (xy 270.397478 -269.325344) (xy 270.397478 -269.845282) (xy 268.898878 -269.845282)
			)
		)
	)
	(zone
		(layer "In2.Cu")
		(hatch none 0.5)
		(connect_pads
			(clearance 0)
		)
		(min_thickness 0.25)
		(keepout
			(tracks not_allowed)
			(vias allowed)
			(pads allowed)
			(copperpour not_allowed)
			(footprints allowed)
		)
		(placement
			(enabled no)
			(sheetname "")
		)
		(fill
			(thermal_gap 0.5)
			(thermal_bridge_width 0.5)
			(island_removal_mode 0)
		)
		(polygon
			(pts
				(xy 54.578758 -207.275176) (xy 56.077358 -207.275176) (xy 56.077358 -207.795114) (xy 54.578758 -207.795114)
			)
		)
	)
	(zone
		(layer "In2.Cu")
		(hatch none 0.5)
		(connect_pads
			(clearance 0)
		)
		(min_thickness 0.25)
		(keepout
			(tracks not_allowed)
			(vias allowed)
			(pads allowed)
			(copperpour not_allowed)
			(footprints allowed)
		)
		(placement
			(enabled no)
			(sheetname "")
		)
		(fill
			(thermal_gap 0.5)
			(thermal_bridge_width 0.5)
			(island_removal_mode 0)
		)
		(polygon
			(pts
				(xy 36.046664 -245.52529) (xy 37.545264 -245.52529) (xy 37.545264 -246.045228) (xy 36.046664 -246.045228)
			)
		)
	)
	(zone
		(layer "In2.Cu")
		(hatch none 0.5)
		(connect_pads
			(clearance 0)
		)
		(min_thickness 0.25)
		(keepout
			(tracks not_allowed)
			(vias allowed)
			(pads allowed)
			(copperpour not_allowed)
			(footprints allowed)
		)
		(placement
			(enabled no)
			(sheetname "")
		)
		(fill
			(thermal_gap 0.5)
			(thermal_bridge_width 0.5)
			(island_removal_mode 0)
		)
		(polygon
			(pts
				(xy 197.954646 -285.475172) (xy 199.453246 -285.475172) (xy 199.453246 -285.99511) (xy 197.954646 -285.99511)
			)
		)
	)
	(zone
		(layer "In2.Cu")
		(hatch none 0.5)
		(connect_pads
			(clearance 0)
		)
		(min_thickness 0.25)
		(keepout
			(tracks not_allowed)
			(vias allowed)
			(pads allowed)
			(copperpour not_allowed)
			(footprints allowed)
		)
		(placement
			(enabled no)
			(sheetname "")
		)
		(fill
			(thermal_gap 0.5)
			(thermal_bridge_width 0.5)
			(island_removal_mode 0)
		)
		(polygon
			(pts
				(xy 58.678826 -304.17516) (xy 60.177426 -304.17516) (xy 60.177426 -304.695098) (xy 58.678826 -304.695098)
			)
		)
	)
	(zone
		(layer "In2.Cu")
		(hatch none 0.5)
		(connect_pads
			(clearance 0)
		)
		(min_thickness 0.25)
		(keepout
			(tracks not_allowed)
			(vias allowed)
			(pads allowed)
			(copperpour not_allowed)
			(footprints allowed)
		)
		(placement
			(enabled no)
			(sheetname "")
		)
		(fill
			(thermal_gap 0.5)
			(thermal_bridge_width 0.5)
			(island_removal_mode 0)
		)
		(polygon
			(pts
				(xy 47.034704 -242.97513) (xy 48.533304 -242.97513) (xy 48.533304 -243.495068) (xy 47.034704 -243.495068)
			)
		)
	)
	(zone
		(layer "In2.Cu")
		(hatch none 0.5)
		(connect_pads
			(clearance 0)
		)
		(min_thickness 0.25)
		(keepout
			(tracks allowed)
			(vias allowed)
			(pads allowed)
			(copperpour allowed)
			(footprints allowed)
		)
		(placement
			(enabled no)
			(sheetname "")
		)
		(fill
			(thermal_gap 0.5)
			(thermal_bridge_width 0.5)
			(island_removal_mode 0)
		)
		(polygon
			(pts
				(xy 56.97601 -349.859092) (xy 56.97601 -349.236792) (xy 57.52719 -349.236792) (xy 57.52719 -349.859092)
			)
		)
	)
	(zone
		(layer "In2.Cu")
		(hatch none 0.5)
		(connect_pads
			(clearance 0)
		)
		(min_thickness 0.25)
		(keepout
			(tracks not_allowed)
			(vias allowed)
			(pads allowed)
			(copperpour not_allowed)
			(footprints allowed)
		)
		(placement
			(enabled no)
			(sheetname "")
		)
		(fill
			(thermal_gap 0.5)
			(thermal_bridge_width 0.5)
			(island_removal_mode 0)
		)
		(polygon
			(pts
				(xy 291.530786 -221.725236) (xy 293.029386 -221.725236) (xy 293.029386 -222.245174) (xy 291.530786 -222.245174)
			)
		)
	)
	(zone
		(layer "In2.Cu")
		(hatch none 0.5)
		(connect_pads
			(clearance 0)
		)
		(min_thickness 0.25)
		(keepout
			(tracks not_allowed)
			(vias allowed)
			(pads allowed)
			(copperpour not_allowed)
			(footprints allowed)
		)
		(placement
			(enabled no)
			(sheetname "")
		)
		(fill
			(thermal_gap 0.5)
			(thermal_bridge_width 0.5)
			(island_removal_mode 0)
		)
		(polygon
			(pts
				(xy 28.50261 -220.025214) (xy 30.00121 -220.025214) (xy 30.00121 -220.545152) (xy 28.50261 -220.545152)
			)
		)
	)
	(zone
		(layer "In2.Cu")
		(hatch none 0.5)
		(connect_pads
			(clearance 0)
		)
		(min_thickness 0.25)
		(keepout
			(tracks not_allowed)
			(vias allowed)
			(pads allowed)
			(copperpour not_allowed)
			(footprints allowed)
		)
		(placement
			(enabled no)
			(sheetname "")
		)
		(fill
			(thermal_gap 0.5)
			(thermal_bridge_width 0.5)
			(island_removal_mode 0)
		)
		(polygon
			(pts
				(xy 193.854578 -246.375174) (xy 195.353178 -246.375174) (xy 195.353178 -246.895112) (xy 193.854578 -246.895112)
			)
		)
	)
	(zone
		(layer "In2.Cu")
		(hatch none 0.5)
		(connect_pads
			(clearance 0)
		)
		(min_thickness 0.25)
		(keepout
			(tracks not_allowed)
			(vias allowed)
			(pads allowed)
			(copperpour not_allowed)
			(footprints allowed)
		)
		(placement
			(enabled no)
			(sheetname "")
		)
		(fill
			(thermal_gap 0.5)
			(thermal_bridge_width 0.5)
			(island_removal_mode 0)
		)
		(polygon
			(pts
				(xy 299.07484 -276.125178) (xy 300.57344 -276.125178) (xy 300.57344 -276.645116) (xy 299.07484 -276.645116)
			)
		)
	)
	(zone
		(layer "In2.Cu")
		(hatch none 0.5)
		(connect_pads
			(clearance 0)
		)
		(min_thickness 0.25)
		(keepout
			(tracks not_allowed)
			(vias allowed)
			(pads allowed)
			(copperpour not_allowed)
			(footprints allowed)
		)
		(placement
			(enabled no)
			(sheetname "")
		)
		(fill
			(thermal_gap 0.5)
			(thermal_bridge_width 0.5)
			(island_removal_mode 0)
		)
		(polygon
			(pts
				(xy 171.22267 -214.925148) (xy 172.72127 -214.925148) (xy 172.72127 -215.445086) (xy 171.22267 -215.445086)
			)
		)
	)
	(zone
		(layer "In2.Cu")
		(hatch none 0.5)
		(connect_pads
			(clearance 0)
		)
		(min_thickness 0.25)
		(keepout
			(tracks not_allowed)
			(vias allowed)
			(pads allowed)
			(copperpour not_allowed)
			(footprints allowed)
		)
		(placement
			(enabled no)
			(sheetname "")
		)
		(fill
			(thermal_gap 0.5)
			(thermal_bridge_width 0.5)
			(island_removal_mode 0)
		)
		(polygon
			(pts
				(xy 411.618684 -272.725134) (xy 413.117284 -272.725134) (xy 413.117284 -273.245072) (xy 411.618684 -273.245072)
			)
		)
	)
	(zone
		(layer "In2.Cu")
		(hatch none 0.5)
		(connect_pads
			(clearance 0)
		)
		(min_thickness 0.25)
		(keepout
			(tracks not_allowed)
			(vias allowed)
			(pads allowed)
			(copperpour not_allowed)
			(footprints allowed)
		)
		(placement
			(enabled no)
			(sheetname "")
		)
		(fill
			(thermal_gap 0.5)
			(thermal_bridge_width 0.5)
			(island_removal_mode 0)
		)
		(polygon
			(pts
				(xy 24.402542 -229.375208) (xy 25.901142 -229.375208) (xy 25.901142 -229.895146) (xy 24.402542 -229.895146)
			)
		)
	)
	(zone
		(layer "In2.Cu")
		(hatch none 0.5)
		(connect_pads
			(clearance 0)
		)
		(min_thickness 0.25)
		(keepout
			(tracks not_allowed)
			(vias allowed)
			(pads allowed)
			(copperpour not_allowed)
			(footprints allowed)
		)
		(placement
			(enabled no)
			(sheetname "")
		)
		(fill
			(thermal_gap 0.5)
			(thermal_bridge_width 0.5)
			(island_removal_mode 0)
		)
		(polygon
			(pts
				(xy 24.402542 -265.075162) (xy 25.901142 -265.075162) (xy 25.901142 -265.5951) (xy 24.402542 -265.5951)
			)
		)
	)
	(zone
		(layer "In2.Cu")
		(hatch none 0.5)
		(connect_pads
			(clearance 0)
		)
		(min_thickness 0.25)
		(keepout
			(tracks not_allowed)
			(vias allowed)
			(pads allowed)
			(copperpour not_allowed)
			(footprints allowed)
		)
		(placement
			(enabled no)
			(sheetname "")
		)
		(fill
			(thermal_gap 0.5)
			(thermal_bridge_width 0.5)
			(island_removal_mode 0)
		)
		(polygon
			(pts
				(xy 415.718752 -250.625102) (xy 417.217352 -250.625102) (xy 417.217352 -251.14504) (xy 415.718752 -251.14504)
			)
		)
	)
	(zone
		(layer "In2.Cu")
		(hatch none 0.5)
		(connect_pads
			(clearance 0)
		)
		(min_thickness 0.25)
		(keepout
			(tracks not_allowed)
			(vias allowed)
			(pads allowed)
			(copperpour not_allowed)
			(footprints allowed)
		)
		(placement
			(enabled no)
			(sheetname "")
		)
		(fill
			(thermal_gap 0.5)
			(thermal_bridge_width 0.5)
			(island_removal_mode 0)
		)
		(polygon
			(pts
				(xy 54.578758 -208.975198) (xy 56.077358 -208.975198) (xy 56.077358 -209.495136) (xy 54.578758 -209.495136)
			)
		)
	)
	(zone
		(layer "In2.Cu")
		(hatch none 0.5)
		(connect_pads
			(clearance 0)
		)
		(min_thickness 0.25)
		(keepout
			(tracks not_allowed)
			(vias allowed)
			(pads allowed)
			(copperpour not_allowed)
			(footprints allowed)
		)
		(placement
			(enabled no)
			(sheetname "")
		)
		(fill
			(thermal_gap 0.5)
			(thermal_bridge_width 0.5)
			(island_removal_mode 0)
		)
		(polygon
			(pts
				(xy 28.50261 -281.225244) (xy 30.00121 -281.225244) (xy 30.00121 -281.745182) (xy 28.50261 -281.745182)
			)
		)
	)
	(zone
		(layer "In2.Cu")
		(hatch none 0.5)
		(connect_pads
			(clearance 0)
		)
		(min_thickness 0.25)
		(keepout
			(tracks not_allowed)
			(vias allowed)
			(pads allowed)
			(copperpour not_allowed)
			(footprints allowed)
		)
		(placement
			(enabled no)
			(sheetname "")
		)
		(fill
			(thermal_gap 0.5)
			(thermal_bridge_width 0.5)
			(island_removal_mode 0)
		)
		(polygon
			(pts
				(xy 438.350914 -262.525256) (xy 439.849514 -262.525256) (xy 439.849514 -263.045194) (xy 438.350914 -263.045194)
			)
		)
	)
	(zone
		(layer "In2.Cu")
		(hatch none 0.5)
		(connect_pads
			(clearance 0)
		)
		(min_thickness 0.25)
		(keepout
			(tracks not_allowed)
			(vias allowed)
			(pads allowed)
			(copperpour not_allowed)
			(footprints allowed)
		)
		(placement
			(enabled no)
			(sheetname "")
		)
		(fill
			(thermal_gap 0.5)
			(thermal_bridge_width 0.5)
			(island_removal_mode 0)
		)
		(polygon
			(pts
				(xy 419.162738 -266.775184) (xy 420.661338 -266.775184) (xy 420.661338 -267.295122) (xy 419.162738 -267.295122)
			)
		)
	)
	(zone
		(layer "In2.Cu")
		(hatch none 0.5)
		(connect_pads
			(clearance 0)
		)
		(min_thickness 0.25)
		(keepout
			(tracks not_allowed)
			(vias allowed)
			(pads allowed)
			(copperpour not_allowed)
			(footprints allowed)
		)
		(placement
			(enabled no)
			(sheetname "")
		)
		(fill
			(thermal_gap 0.5)
			(thermal_bridge_width 0.5)
			(island_removal_mode 0)
		)
		(polygon
			(pts
				(xy 58.678826 -288.875216) (xy 60.177426 -288.875216) (xy 60.177426 -289.395154) (xy 58.678826 -289.395154)
			)
		)
	)
	(zone
		(layer "In2.Cu")
		(hatch none 0.5)
		(connect_pads
			(clearance 0)
		)
		(min_thickness 0.25)
		(keepout
			(tracks not_allowed)
			(vias allowed)
			(pads allowed)
			(copperpour not_allowed)
			(footprints allowed)
		)
		(placement
			(enabled no)
			(sheetname "")
		)
		(fill
			(thermal_gap 0.5)
			(thermal_bridge_width 0.5)
			(island_removal_mode 0)
		)
		(polygon
			(pts
				(xy 175.322738 -200.475342) (xy 176.821338 -200.475342) (xy 176.821338 -200.99528) (xy 175.322738 -200.99528)
			)
		)
	)
	(zone
		(layer "In2.Cu")
		(hatch none 0.5)
		(connect_pads
			(clearance 0)
		)
		(min_thickness 0.25)
		(keepout
			(tracks not_allowed)
			(vias allowed)
			(pads allowed)
			(copperpour not_allowed)
			(footprints allowed)
		)
		(placement
			(enabled no)
			(sheetname "")
		)
		(fill
			(thermal_gap 0.5)
			(thermal_bridge_width 0.5)
			(island_removal_mode 0)
		)
		(polygon
			(pts
				(xy 16.858742 -253.175262) (xy 18.357342 -253.175262) (xy 18.357342 -253.6952) (xy 16.858742 -253.6952)
			)
		)
	)
	(zone
		(layer "In2.Cu")
		(hatch none 0.5)
		(connect_pads
			(clearance 0)
		)
		(min_thickness 0.25)
		(keepout
			(tracks not_allowed)
			(vias allowed)
			(pads allowed)
			(copperpour not_allowed)
			(footprints allowed)
		)
		(placement
			(enabled no)
			(sheetname "")
		)
		(fill
			(thermal_gap 0.5)
			(thermal_bridge_width 0.5)
			(island_removal_mode 0)
		)
		(polygon
			(pts
				(xy 423.262806 -247.225312) (xy 424.761406 -247.225312) (xy 424.761406 -247.74525) (xy 423.262806 -247.74525)
			)
		)
	)
	(zone
		(layer "In2.Cu")
		(hatch none 0.5)
		(connect_pads
			(clearance 0)
		)
		(min_thickness 0.25)
		(keepout
			(tracks not_allowed)
			(vias allowed)
			(pads allowed)
			(copperpour not_allowed)
			(footprints allowed)
		)
		(placement
			(enabled no)
			(sheetname "")
		)
		(fill
			(thermal_gap 0.5)
			(thermal_bridge_width 0.5)
			(island_removal_mode 0)
		)
		(polygon
			(pts
				(xy 449.3387 -304.17516) (xy 450.8373 -304.17516) (xy 450.8373 -304.695098) (xy 449.3387 -304.695098)
			)
		)
	)
	(zone
		(layer "In2.Cu")
		(hatch none 0.5)
		(connect_pads
			(clearance 0)
		)
		(min_thickness 0.25)
		(keepout
			(tracks not_allowed)
			(vias allowed)
			(pads allowed)
			(copperpour not_allowed)
			(footprints allowed)
		)
		(placement
			(enabled no)
			(sheetname "")
		)
		(fill
			(thermal_gap 0.5)
			(thermal_bridge_width 0.5)
			(island_removal_mode 0)
		)
		(polygon
			(pts
				(xy 306.618894 -250.625102) (xy 308.117494 -250.625102) (xy 308.117494 -251.14504) (xy 306.618894 -251.14504)
			)
		)
	)
	(zone
		(layer "In2.Cu")
		(hatch none 0.5)
		(connect_pads
			(clearance 0)
		)
		(min_thickness 0.25)
		(keepout
			(tracks not_allowed)
			(vias allowed)
			(pads allowed)
			(copperpour not_allowed)
			(footprints allowed)
		)
		(placement
			(enabled no)
			(sheetname "")
		)
		(fill
			(thermal_gap 0.5)
			(thermal_bridge_width 0.5)
			(island_removal_mode 0)
		)
		(polygon
			(pts
				(xy 294.974772 -208.975198) (xy 296.473372 -208.975198) (xy 296.473372 -209.495136) (xy 294.974772 -209.495136)
			)
		)
	)
	(zone
		(layer "In2.Cu")
		(hatch none 0.5)
		(connect_pads
			(clearance 0)
		)
		(min_thickness 0.25)
		(keepout
			(tracks not_allowed)
			(vias allowed)
			(pads allowed)
			(copperpour not_allowed)
			(footprints allowed)
		)
		(placement
			(enabled no)
			(sheetname "")
		)
		(fill
			(thermal_gap 0.5)
			(thermal_bridge_width 0.5)
			(island_removal_mode 0)
		)
		(polygon
			(pts
				(xy 58.678826 -226.825302) (xy 60.177426 -226.825302) (xy 60.177426 -227.34524) (xy 58.678826 -227.34524)
			)
		)
	)
	(zone
		(layer "In2.Cu")
		(hatch none 0.5)
		(connect_pads
			(clearance 0)
		)
		(min_thickness 0.25)
		(keepout
			(tracks not_allowed)
			(vias allowed)
			(pads allowed)
			(copperpour not_allowed)
			(footprints allowed)
		)
		(placement
			(enabled no)
			(sheetname "")
		)
		(fill
			(thermal_gap 0.5)
			(thermal_bridge_width 0.5)
			(island_removal_mode 0)
		)
		(polygon
			(pts
				(xy 423.262806 -206.425292) (xy 424.761406 -206.425292) (xy 424.761406 -206.94523) (xy 423.262806 -206.94523)
			)
		)
	)
	(zone
		(layer "In2.Cu")
		(hatch none 0.5)
		(connect_pads
			(clearance 0)
		)
		(min_thickness 0.25)
		(keepout
			(tracks not_allowed)
			(vias allowed)
			(pads allowed)
			(copperpour not_allowed)
			(footprints allowed)
		)
		(placement
			(enabled no)
			(sheetname "")
		)
		(fill
			(thermal_gap 0.5)
			(thermal_bridge_width 0.5)
			(island_removal_mode 0)
		)
		(polygon
			(pts
				(xy 434.250846 -225.975164) (xy 435.749446 -225.975164) (xy 435.749446 -226.495102) (xy 434.250846 -226.495102)
			)
		)
	)
	(zone
		(layer "In2.Cu")
		(hatch none 0.5)
		(connect_pads
			(clearance 0)
		)
		(min_thickness 0.25)
		(keepout
			(tracks not_allowed)
			(vias allowed)
			(pads allowed)
			(copperpour not_allowed)
			(footprints allowed)
		)
		(placement
			(enabled no)
			(sheetname "")
		)
		(fill
			(thermal_gap 0.5)
			(thermal_bridge_width 0.5)
			(island_removal_mode 0)
		)
		(polygon
			(pts
				(xy 453.438768 -201.325226) (xy 454.937368 -201.325226) (xy 454.937368 -201.845164) (xy 453.438768 -201.845164)
			)
		)
	)
	(zone
		(layer "In2.Cu")
		(hatch none 0.5)
		(connect_pads
			(clearance 0)
		)
		(min_thickness 0.25)
		(keepout
			(tracks not_allowed)
			(vias allowed)
			(pads allowed)
			(copperpour not_allowed)
			(footprints allowed)
		)
		(placement
			(enabled no)
			(sheetname "")
		)
		(fill
			(thermal_gap 0.5)
			(thermal_bridge_width 0.5)
			(island_removal_mode 0)
		)
		(polygon
			(pts
				(xy 24.402542 -268.475206) (xy 25.901142 -268.475206) (xy 25.901142 -268.995144) (xy 24.402542 -268.995144)
			)
		)
	)
	(zone
		(layer "In2.Cu")
		(hatch none 0.5)
		(connect_pads
			(clearance 0)
		)
		(min_thickness 0.25)
		(keepout
			(tracks not_allowed)
			(vias allowed)
			(pads allowed)
			(copperpour not_allowed)
			(footprints allowed)
		)
		(placement
			(enabled no)
			(sheetname "")
		)
		(fill
			(thermal_gap 0.5)
			(thermal_bridge_width 0.5)
			(island_removal_mode 0)
		)
		(polygon
			(pts
				(xy 186.310778 -288.025332) (xy 187.809378 -288.025332) (xy 187.809378 -288.54527) (xy 186.310778 -288.54527)
			)
		)
	)
	(zone
		(layer "In2.Cu")
		(hatch none 0.5)
		(connect_pads
			(clearance 0)
		)
		(min_thickness 0.25)
		(keepout
			(tracks not_allowed)
			(vias allowed)
			(pads allowed)
			(copperpour not_allowed)
			(footprints allowed)
		)
		(placement
			(enabled no)
			(sheetname "")
		)
		(fill
			(thermal_gap 0.5)
			(thermal_bridge_width 0.5)
			(island_removal_mode 0)
		)
		(polygon
			(pts
				(xy 291.530786 -223.425258) (xy 293.029386 -223.425258) (xy 293.029386 -223.945196) (xy 291.530786 -223.945196)
			)
		)
	)
	(zone
		(layer "In2.Cu")
		(hatch none 0.5)
		(connect_pads
			(clearance 0)
		)
		(min_thickness 0.25)
		(keepout
			(tracks not_allowed)
			(vias allowed)
			(pads allowed)
			(copperpour not_allowed)
			(footprints allowed)
		)
		(placement
			(enabled no)
			(sheetname "")
		)
		(fill
			(thermal_gap 0.5)
			(thermal_bridge_width 0.5)
			(island_removal_mode 0)
		)
		(polygon
			(pts
				(xy 294.974772 -197.925182) (xy 296.473372 -197.925182) (xy 296.473372 -198.44512) (xy 294.974772 -198.44512)
			)
		)
	)
	(zone
		(layer "In2.Cu")
		(hatch none 0.5)
		(connect_pads
			(clearance 0)
		)
		(min_thickness 0.25)
		(keepout
			(tracks not_allowed)
			(vias allowed)
			(pads allowed)
			(copperpour not_allowed)
			(footprints allowed)
		)
		(placement
			(enabled no)
			(sheetname "")
		)
		(fill
			(thermal_gap 0.5)
			(thermal_bridge_width 0.5)
			(island_removal_mode 0)
		)
		(polygon
			(pts
				(xy 453.438768 -208.125314) (xy 454.937368 -208.125314) (xy 454.937368 -208.645252) (xy 453.438768 -208.645252)
			)
		)
	)
	(zone
		(layer "In2.Cu")
		(hatch none 0.5)
		(connect_pads
			(clearance 0)
		)
		(min_thickness 0.25)
		(keepout
			(tracks not_allowed)
			(vias allowed)
			(pads allowed)
			(copperpour not_allowed)
			(footprints allowed)
		)
		(placement
			(enabled no)
			(sheetname "")
		)
		(fill
			(thermal_gap 0.5)
			(thermal_bridge_width 0.5)
			(island_removal_mode 0)
		)
		(polygon
			(pts
				(xy 190.410846 -220.025214) (xy 191.909446 -220.025214) (xy 191.909446 -220.545152) (xy 190.410846 -220.545152)
			)
		)
	)
	(zone
		(layer "In2.Cu")
		(hatch none 0.5)
		(connect_pads
			(clearance 0)
		)
		(min_thickness 0.25)
		(keepout
			(tracks not_allowed)
			(vias allowed)
			(pads allowed)
			(copperpour not_allowed)
			(footprints allowed)
		)
		(placement
			(enabled no)
			(sheetname "")
		)
		(fill
			(thermal_gap 0.5)
			(thermal_bridge_width 0.5)
			(island_removal_mode 0)
		)
		(polygon
			(pts
				(xy 445.894968 -250.625102) (xy 447.393568 -250.625102) (xy 447.393568 -251.14504) (xy 445.894968 -251.14504)
			)
		)
	)
	(zone
		(layer "In2.Cu")
		(hatch none 0.5)
		(connect_pads
			(clearance 0)
		)
		(min_thickness 0.25)
		(keepout
			(tracks not_allowed)
			(vias allowed)
			(pads allowed)
			(copperpour not_allowed)
			(footprints allowed)
		)
		(placement
			(enabled no)
			(sheetname "")
		)
		(fill
			(thermal_gap 0.5)
			(thermal_bridge_width 0.5)
			(island_removal_mode 0)
		)
		(polygon
			(pts
				(xy 291.530786 -204.72527) (xy 293.029386 -204.72527) (xy 293.029386 -205.245208) (xy 291.530786 -205.245208)
			)
		)
	)
	(zone
		(layer "In2.Cu")
		(hatch none 0.5)
		(connect_pads
			(clearance 0)
		)
		(min_thickness 0.25)
		(keepout
			(tracks not_allowed)
			(vias allowed)
			(pads allowed)
			(copperpour not_allowed)
			(footprints allowed)
		)
		(placement
			(enabled no)
			(sheetname "")
		)
		(fill
			(thermal_gap 0.5)
			(thermal_bridge_width 0.5)
			(island_removal_mode 0)
		)
		(polygon
			(pts
				(xy 449.3387 -225.975164) (xy 450.8373 -225.975164) (xy 450.8373 -226.495102) (xy 449.3387 -226.495102)
			)
		)
	)
	(zone
		(layer "In2.Cu")
		(hatch none 0.5)
		(connect_pads
			(clearance 0)
		)
		(min_thickness 0.25)
		(keepout
			(tracks not_allowed)
			(vias allowed)
			(pads allowed)
			(copperpour not_allowed)
			(footprints allowed)
		)
		(placement
			(enabled no)
			(sheetname "")
		)
		(fill
			(thermal_gap 0.5)
			(thermal_bridge_width 0.5)
			(island_removal_mode 0)
		)
		(polygon
			(pts
				(xy 186.310778 -302.475138) (xy 187.809378 -302.475138) (xy 187.809378 -302.995076) (xy 186.310778 -302.995076)
			)
		)
	)
	(zone
		(layer "In2.Cu")
		(hatch none 0.5)
		(connect_pads
			(clearance 0)
		)
		(min_thickness 0.25)
		(keepout
			(tracks not_allowed)
			(vias allowed)
			(pads allowed)
			(copperpour not_allowed)
			(footprints allowed)
		)
		(placement
			(enabled no)
			(sheetname "")
		)
		(fill
			(thermal_gap 0.5)
			(thermal_bridge_width 0.5)
			(island_removal_mode 0)
		)
		(polygon
			(pts
				(xy 31.946596 -231.925114) (xy 33.445196 -231.925114) (xy 33.445196 -232.445052) (xy 31.946596 -232.445052)
			)
		)
	)
	(zone
		(layer "In2.Cu")
		(hatch none 0.5)
		(connect_pads
			(clearance 0)
		)
		(min_thickness 0.25)
		(keepout
			(tracks not_allowed)
			(vias allowed)
			(pads allowed)
			(copperpour not_allowed)
			(footprints allowed)
		)
		(placement
			(enabled no)
			(sheetname "")
		)
		(fill
			(thermal_gap 0.5)
			(thermal_bridge_width 0.5)
			(island_removal_mode 0)
		)
		(polygon
			(pts
				(xy 175.322738 -304.17516) (xy 176.821338 -304.17516) (xy 176.821338 -304.695098) (xy 175.322738 -304.695098)
			)
		)
	)
	(zone
		(layer "In2.Cu")
		(hatch none 0.5)
		(connect_pads
			(clearance 0)
		)
		(min_thickness 0.25)
		(keepout
			(tracks not_allowed)
			(vias allowed)
			(pads allowed)
			(copperpour not_allowed)
			(footprints allowed)
		)
		(placement
			(enabled no)
			(sheetname "")
		)
		(fill
			(thermal_gap 0.5)
			(thermal_bridge_width 0.5)
			(island_removal_mode 0)
		)
		(polygon
			(pts
				(xy 306.618894 -271.87525) (xy 308.117494 -271.87525) (xy 308.117494 -272.395188) (xy 306.618894 -272.395188)
			)
		)
	)
	(zone
		(layer "In2.Cu")
		(hatch none 0.5)
		(connect_pads
			(clearance 0)
		)
		(min_thickness 0.25)
		(keepout
			(tracks not_allowed)
			(vias allowed)
			(pads allowed)
			(copperpour not_allowed)
			(footprints allowed)
		)
		(placement
			(enabled no)
			(sheetname "")
		)
		(fill
			(thermal_gap 0.5)
			(thermal_bridge_width 0.5)
			(island_removal_mode 0)
		)
		(polygon
			(pts
				(xy 453.438768 -219.17533) (xy 454.937368 -219.17533) (xy 454.937368 -219.695268) (xy 453.438768 -219.695268)
			)
		)
	)
	(zone
		(layer "In2.Cu")
		(hatch none 0.5)
		(connect_pads
			(clearance 0)
		)
		(min_thickness 0.25)
		(keepout
			(tracks not_allowed)
			(vias allowed)
			(pads allowed)
			(copperpour not_allowed)
			(footprints allowed)
		)
		(placement
			(enabled no)
			(sheetname "")
		)
		(fill
			(thermal_gap 0.5)
			(thermal_bridge_width 0.5)
			(island_removal_mode 0)
		)
		(polygon
			(pts
				(xy 167.778684 -305.875182) (xy 169.277284 -305.875182) (xy 169.277284 -306.39512) (xy 167.778684 -306.39512)
			)
		)
	)
	(zone
		(layer "In2.Cu")
		(hatch none 0.5)
		(connect_pads
			(clearance 0)
		)
		(min_thickness 0.25)
		(keepout
			(tracks not_allowed)
			(vias allowed)
			(pads allowed)
			(copperpour not_allowed)
			(footprints allowed)
		)
		(placement
			(enabled no)
			(sheetname "")
		)
		(fill
			(thermal_gap 0.5)
			(thermal_bridge_width 0.5)
			(island_removal_mode 0)
		)
		(polygon
			(pts
				(xy 430.80686 -287.175194) (xy 432.30546 -287.175194) (xy 432.30546 -287.695132) (xy 430.80686 -287.695132)
			)
		)
	)
	(zone
		(layer "In2.Cu")
		(hatch none 0.5)
		(connect_pads
			(clearance 0)
		)
		(min_thickness 0.25)
		(keepout
			(tracks not_allowed)
			(vias allowed)
			(pads allowed)
			(copperpour not_allowed)
			(footprints allowed)
		)
		(placement
			(enabled no)
			(sheetname "")
		)
		(fill
			(thermal_gap 0.5)
			(thermal_bridge_width 0.5)
			(island_removal_mode 0)
		)
		(polygon
			(pts
				(xy 24.402542 -310.12511) (xy 25.901142 -310.12511) (xy 25.901142 -310.645048) (xy 24.402542 -310.645048)
			)
		)
	)
	(zone
		(layer "In2.Cu")
		(hatch none 0.5)
		(connect_pads
			(clearance 0)
		)
		(min_thickness 0.25)
		(keepout
			(tracks not_allowed)
			(vias allowed)
			(pads allowed)
			(copperpour not_allowed)
			(footprints allowed)
		)
		(placement
			(enabled no)
			(sheetname "")
		)
		(fill
			(thermal_gap 0.5)
			(thermal_bridge_width 0.5)
			(island_removal_mode 0)
		)
		(polygon
			(pts
				(xy 434.250846 -261.675118) (xy 435.749446 -261.675118) (xy 435.749446 -262.195056) (xy 434.250846 -262.195056)
			)
		)
	)
	(zone
		(layer "In2.Cu")
		(hatch none 0.5)
		(connect_pads
			(clearance 0)
		)
		(min_thickness 0.25)
		(keepout
			(tracks not_allowed)
			(vias allowed)
			(pads allowed)
			(copperpour not_allowed)
			(footprints allowed)
		)
		(placement
			(enabled no)
			(sheetname "")
		)
		(fill
			(thermal_gap 0.5)
			(thermal_bridge_width 0.5)
			(island_removal_mode 0)
		)
		(polygon
			(pts
				(arc
					(start 298.56049 -390.65581)
					(mid 298.551254 -390.675734)
					(end 298.548044 -390.697466)
				)
				(arc
					(start 298.548044 -390.89203)
					(mid 298.570362 -390.945912)
					(end 298.624244 -390.96823)
				)
				(arc
					(start 299.310044 -390.96823)
					(mid 299.363926 -390.945912)
					(end 299.386244 -390.89203)
				)
				(arc
					(start 299.386244 -390.697466)
					(mid 299.383076 -390.675722)
					(end 299.373798 -390.65581)
				)
				(arc
					(start 299.181012 -390.359646)
					(mid 299.16879 -390.317962)
					(end 299.181266 -390.276334)
				)
				(arc
					(start 299.373798 -389.98271)
					(mid 299.383034 -389.962786)
					(end 299.386244 -389.941054)
				)
				(arc
					(start 299.386244 -389.74649)
					(mid 299.363926 -389.692608)
					(end 299.310044 -389.67029)
				)
				(arc
					(start 298.624244 -389.67029)
					(mid 298.570362 -389.692608)
					(end 298.548044 -389.74649)
				)
				(arc
					(start 298.548044 -389.942324)
					(mid 298.551212 -389.964068)
					(end 298.56049 -389.98398)
				)
				(arc
					(start 298.753022 -390.277604)
					(mid 298.765424 -390.31926)
					(end 298.753022 -390.360916)
				)
			)
		)
	)
	(zone
		(layer "In2.Cu")
		(hatch none 0.5)
		(connect_pads
			(clearance 0)
		)
		(min_thickness 0.25)
		(keepout
			(tracks not_allowed)
			(vias allowed)
			(pads allowed)
			(copperpour not_allowed)
			(footprints allowed)
		)
		(placement
			(enabled no)
			(sheetname "")
		)
		(fill
			(thermal_gap 0.5)
			(thermal_bridge_width 0.5)
			(island_removal_mode 0)
		)
		(polygon
			(pts
				(xy 28.50261 -290.575238) (xy 30.00121 -290.575238) (xy 30.00121 -291.095176) (xy 28.50261 -291.095176)
			)
		)
	)
	(zone
		(layer "In2.Cu")
		(hatch none 0.5)
		(connect_pads
			(clearance 0)
		)
		(min_thickness 0.25)
		(keepout
			(tracks not_allowed)
			(vias allowed)
			(pads allowed)
			(copperpour not_allowed)
			(footprints allowed)
		)
		(placement
			(enabled no)
			(sheetname "")
		)
		(fill
			(thermal_gap 0.5)
			(thermal_bridge_width 0.5)
			(island_removal_mode 0)
		)
		(polygon
			(pts
				(xy 449.3387 -233.625136) (xy 450.8373 -233.625136) (xy 450.8373 -234.145074) (xy 449.3387 -234.145074)
			)
		)
	)
	(zone
		(layer "In2.Cu")
		(hatch none 0.5)
		(connect_pads
			(clearance 0)
		)
		(min_thickness 0.25)
		(keepout
			(tracks not_allowed)
			(vias allowed)
			(pads allowed)
			(copperpour not_allowed)
			(footprints allowed)
		)
		(placement
			(enabled no)
			(sheetname "")
		)
		(fill
			(thermal_gap 0.5)
			(thermal_bridge_width 0.5)
			(island_removal_mode 0)
		)
		(polygon
			(pts
				(xy 441.7949 -214.925148) (xy 443.2935 -214.925148) (xy 443.2935 -215.445086) (xy 441.7949 -215.445086)
			)
		)
	)
	(zone
		(layer "In2.Cu")
		(hatch none 0.5)
		(connect_pads
			(clearance 0)
		)
		(min_thickness 0.25)
		(keepout
			(tracks not_allowed)
			(vias allowed)
			(pads allowed)
			(copperpour not_allowed)
			(footprints allowed)
		)
		(placement
			(enabled no)
			(sheetname "")
		)
		(fill
			(thermal_gap 0.5)
			(thermal_bridge_width 0.5)
			(island_removal_mode 0)
		)
		(polygon
			(pts
				(xy 272.342864 -220.025214) (xy 273.841464 -220.025214) (xy 273.841464 -220.545152) (xy 272.342864 -220.545152)
			)
		)
	)
	(zone
		(layer "In2.Cu")
		(hatch none 0.5)
		(connect_pads
			(clearance 0)
		)
		(min_thickness 0.25)
		(keepout
			(tracks not_allowed)
			(vias allowed)
			(pads allowed)
			(copperpour not_allowed)
			(footprints allowed)
		)
		(placement
			(enabled no)
			(sheetname "")
		)
		(fill
			(thermal_gap 0.5)
			(thermal_bridge_width 0.5)
			(island_removal_mode 0)
		)
		(polygon
			(pts
				(xy 171.22267 -304.17516) (xy 172.72127 -304.17516) (xy 172.72127 -304.695098) (xy 171.22267 -304.695098)
			)
		)
	)
	(zone
		(layer "In2.Cu")
		(hatch none 0.5)
		(connect_pads
			(clearance 0)
		)
		(min_thickness 0.25)
		(keepout
			(tracks not_allowed)
			(vias allowed)
			(pads allowed)
			(copperpour not_allowed)
			(footprints allowed)
		)
		(placement
			(enabled no)
			(sheetname "")
		)
		(fill
			(thermal_gap 0.5)
			(thermal_bridge_width 0.5)
			(island_removal_mode 0)
		)
		(polygon
			(pts
				(xy 438.350914 -228.525324) (xy 439.849514 -228.525324) (xy 439.849514 -229.045262) (xy 438.350914 -229.045262)
			)
		)
	)
	(zone
		(layer "In2.Cu")
		(hatch none 0.5)
		(connect_pads
			(clearance 0)
		)
		(min_thickness 0.25)
		(keepout
			(tracks not_allowed)
			(vias allowed)
			(pads allowed)
			(copperpour not_allowed)
			(footprints allowed)
		)
		(placement
			(enabled no)
			(sheetname "")
		)
		(fill
			(thermal_gap 0.5)
			(thermal_bridge_width 0.5)
			(island_removal_mode 0)
		)
		(polygon
			(pts
				(xy 426.706792 -300.775116) (xy 428.205392 -300.775116) (xy 428.205392 -301.295054) (xy 426.706792 -301.295054)
			)
		)
	)
	(zone
		(layer "In2.Cu")
		(hatch none 0.5)
		(connect_pads
			(clearance 0)
		)
		(min_thickness 0.25)
		(keepout
			(tracks not_allowed)
			(vias allowed)
			(pads allowed)
			(copperpour not_allowed)
			(footprints allowed)
		)
		(placement
			(enabled no)
			(sheetname "")
		)
		(fill
			(thermal_gap 0.5)
			(thermal_bridge_width 0.5)
			(island_removal_mode 0)
		)
		(polygon
			(pts
				(xy 186.310778 -231.925114) (xy 187.809378 -231.925114) (xy 187.809378 -232.445052) (xy 186.310778 -232.445052)
			)
		)
	)
	(zone
		(layer "In2.Cu")
		(hatch none 0.5)
		(connect_pads
			(clearance 0)
		)
		(min_thickness 0.25)
		(keepout
			(tracks not_allowed)
			(vias allowed)
			(pads allowed)
			(copperpour not_allowed)
			(footprints allowed)
		)
		(placement
			(enabled no)
			(sheetname "")
		)
		(fill
			(thermal_gap 0.5)
			(thermal_bridge_width 0.5)
			(island_removal_mode 0)
		)
		(polygon
			(pts
				(xy 193.854578 -211.525104) (xy 195.353178 -211.525104) (xy 195.353178 -212.045042) (xy 193.854578 -212.045042)
			)
		)
	)
	(zone
		(layer "In2.Cu")
		(hatch none 0.5)
		(connect_pads
			(clearance 0)
		)
		(min_thickness 0.25)
		(keepout
			(tracks not_allowed)
			(vias allowed)
			(pads allowed)
			(copperpour not_allowed)
			(footprints allowed)
		)
		(placement
			(enabled no)
			(sheetname "")
		)
		(fill
			(thermal_gap 0.5)
			(thermal_bridge_width 0.5)
			(island_removal_mode 0)
		)
		(polygon
			(pts
				(xy 287.430718 -276.975316) (xy 288.929318 -276.975316) (xy 288.929318 -277.495254) (xy 287.430718 -277.495254)
			)
		)
	)
	(zone
		(layer "In2.Cu")
		(hatch none 0.5)
		(connect_pads
			(clearance 0)
		)
		(min_thickness 0.25)
		(keepout
			(tracks not_allowed)
			(vias allowed)
			(pads allowed)
			(copperpour not_allowed)
			(footprints allowed)
		)
		(placement
			(enabled no)
			(sheetname "")
		)
		(fill
			(thermal_gap 0.5)
			(thermal_bridge_width 0.5)
			(island_removal_mode 0)
		)
		(polygon
			(pts
				(xy 445.894968 -198.77532) (xy 447.393568 -198.77532) (xy 447.393568 -199.295258) (xy 445.894968 -199.295258)
			)
		)
	)
	(zone
		(layer "In2.Cu")
		(hatch none 0.5)
		(connect_pads
			(clearance 0)
		)
		(min_thickness 0.25)
		(keepout
			(tracks not_allowed)
			(vias allowed)
			(pads allowed)
			(copperpour not_allowed)
			(footprints allowed)
		)
		(placement
			(enabled no)
			(sheetname "")
		)
		(fill
			(thermal_gap 0.5)
			(thermal_bridge_width 0.5)
			(island_removal_mode 0)
		)
		(polygon
			(pts
				(xy 272.342864 -216.62517) (xy 273.841464 -216.62517) (xy 273.841464 -217.145108) (xy 272.342864 -217.145108)
			)
		)
	)
	(zone
		(layer "In2.Cu")
		(hatch none 0.5)
		(connect_pads
			(clearance 0)
		)
		(min_thickness 0.25)
		(keepout
			(tracks not_allowed)
			(vias allowed)
			(pads allowed)
			(copperpour not_allowed)
			(footprints allowed)
		)
		(placement
			(enabled no)
			(sheetname "")
		)
		(fill
			(thermal_gap 0.5)
			(thermal_bridge_width 0.5)
			(island_removal_mode 0)
		)
		(polygon
			(pts
				(xy 58.678826 -301.625254) (xy 60.177426 -301.625254) (xy 60.177426 -302.145192) (xy 58.678826 -302.145192)
			)
		)
	)
	(zone
		(layer "In2.Cu")
		(hatch none 0.5)
		(connect_pads
			(clearance 0)
		)
		(min_thickness 0.25)
		(keepout
			(tracks not_allowed)
			(vias allowed)
			(pads allowed)
			(copperpour not_allowed)
			(footprints allowed)
		)
		(placement
			(enabled no)
			(sheetname "")
		)
		(fill
			(thermal_gap 0.5)
			(thermal_bridge_width 0.5)
			(island_removal_mode 0)
		)
		(polygon
			(pts
				(xy 291.530786 -305.875182) (xy 293.029386 -305.875182) (xy 293.029386 -306.39512) (xy 291.530786 -306.39512)
			)
		)
	)
	(zone
		(layer "In2.Cu")
		(hatch none 0.5)
		(connect_pads
			(clearance 0)
		)
		(min_thickness 0.25)
		(keepout
			(tracks not_allowed)
			(vias allowed)
			(pads allowed)
			(copperpour not_allowed)
			(footprints allowed)
		)
		(placement
			(enabled no)
			(sheetname "")
		)
		(fill
			(thermal_gap 0.5)
			(thermal_bridge_width 0.5)
			(island_removal_mode 0)
		)
		(polygon
			(pts
				(xy 16.858742 -238.725202) (xy 18.357342 -238.725202) (xy 18.357342 -239.24514) (xy 16.858742 -239.24514)
			)
		)
	)
	(zone
		(layer "In2.Cu")
		(hatch none 0.5)
		(connect_pads
			(clearance 0)
		)
		(min_thickness 0.25)
		(keepout
			(tracks not_allowed)
			(vias allowed)
			(pads allowed)
			(copperpour not_allowed)
			(footprints allowed)
		)
		(placement
			(enabled no)
			(sheetname "")
		)
		(fill
			(thermal_gap 0.5)
			(thermal_bridge_width 0.5)
			(island_removal_mode 0)
		)
		(polygon
			(pts
				(xy 291.530786 -248.925334) (xy 293.029386 -248.925334) (xy 293.029386 -249.445272) (xy 291.530786 -249.445272)
			)
		)
	)
	(zone
		(layer "In2.Cu")
		(hatch none 0.5)
		(connect_pads
			(clearance 0)
		)
		(min_thickness 0.25)
		(keepout
			(tracks not_allowed)
			(vias allowed)
			(pads allowed)
			(copperpour not_allowed)
			(footprints allowed)
		)
		(placement
			(enabled no)
			(sheetname "")
		)
		(fill
			(thermal_gap 0.5)
			(thermal_bridge_width 0.5)
			(island_removal_mode 0)
		)
		(polygon
			(pts
				(xy 175.322738 -284.625288) (xy 176.821338 -284.625288) (xy 176.821338 -285.145226) (xy 175.322738 -285.145226)
			)
		)
	)
	(zone
		(layer "In2.Cu")
		(hatch none 0.5)
		(connect_pads
			(clearance 0)
		)
		(min_thickness 0.25)
		(keepout
			(tracks not_allowed)
			(vias allowed)
			(pads allowed)
			(copperpour not_allowed)
			(footprints allowed)
		)
		(placement
			(enabled no)
			(sheetname "")
		)
		(fill
			(thermal_gap 0.5)
			(thermal_bridge_width 0.5)
			(island_removal_mode 0)
		)
		(polygon
			(pts
				(xy 272.342864 -265.075162) (xy 273.841464 -265.075162) (xy 273.841464 -265.5951) (xy 272.342864 -265.5951)
			)
		)
	)
	(zone
		(layer "In2.Cu")
		(hatch none 0.5)
		(connect_pads
			(clearance 0)
		)
		(min_thickness 0.25)
		(keepout
			(tracks not_allowed)
			(vias allowed)
			(pads allowed)
			(copperpour not_allowed)
			(footprints allowed)
		)
		(placement
			(enabled no)
			(sheetname "")
		)
		(fill
			(thermal_gap 0.5)
			(thermal_bridge_width 0.5)
			(island_removal_mode 0)
		)
		(polygon
			(pts
				(xy 453.438768 -248.925334) (xy 454.937368 -248.925334) (xy 454.937368 -249.445272) (xy 453.438768 -249.445272)
			)
		)
	)
	(zone
		(layer "In2.Cu")
		(hatch none 0.5)
		(connect_pads
			(clearance 0)
		)
		(min_thickness 0.25)
		(keepout
			(tracks not_allowed)
			(vias allowed)
			(pads allowed)
			(copperpour not_allowed)
			(footprints allowed)
		)
		(placement
			(enabled no)
			(sheetname "")
		)
		(fill
			(thermal_gap 0.5)
			(thermal_bridge_width 0.5)
			(island_removal_mode 0)
		)
		(polygon
			(pts
				(xy 276.442932 -285.475172) (xy 277.941532 -285.475172) (xy 277.941532 -285.99511) (xy 276.442932 -285.99511)
			)
		)
	)
	(zone
		(layer "In2.Cu")
		(hatch none 0.5)
		(connect_pads
			(clearance 0)
		)
		(min_thickness 0.25)
		(keepout
			(tracks not_allowed)
			(vias allowed)
			(pads allowed)
			(copperpour not_allowed)
			(footprints allowed)
		)
		(placement
			(enabled no)
			(sheetname "")
		)
		(fill
			(thermal_gap 0.5)
			(thermal_bridge_width 0.5)
			(island_removal_mode 0)
		)
		(polygon
			(pts
				(xy 36.046664 -197.075298) (xy 37.545264 -197.075298) (xy 37.545264 -197.595236) (xy 36.046664 -197.595236)
			)
		)
	)
	(zone
		(layer "In2.Cu")
		(hatch none 0.5)
		(connect_pads
			(clearance 0)
		)
		(min_thickness 0.25)
		(keepout
			(tracks not_allowed)
			(vias allowed)
			(pads allowed)
			(copperpour not_allowed)
			(footprints allowed)
		)
		(placement
			(enabled no)
			(sheetname "")
		)
		(fill
			(thermal_gap 0.5)
			(thermal_bridge_width 0.5)
			(island_removal_mode 0)
		)
		(polygon
			(pts
				(xy 441.7949 -265.075162) (xy 443.2935 -265.075162) (xy 443.2935 -265.5951) (xy 441.7949 -265.5951)
			)
		)
	)
	(zone
		(layer "In2.Cu")
		(hatch none 0.5)
		(connect_pads
			(clearance 0)
		)
		(min_thickness 0.25)
		(keepout
			(tracks not_allowed)
			(vias allowed)
			(pads allowed)
			(copperpour not_allowed)
			(footprints allowed)
		)
		(placement
			(enabled no)
			(sheetname "")
		)
		(fill
			(thermal_gap 0.5)
			(thermal_bridge_width 0.5)
			(island_removal_mode 0)
		)
		(polygon
			(pts
				(xy 58.678826 -284.625288) (xy 60.177426 -284.625288) (xy 60.177426 -285.145226) (xy 58.678826 -285.145226)
			)
		)
	)
	(zone
		(layer "In2.Cu")
		(hatch none 0.5)
		(connect_pads
			(clearance 0)
		)
		(min_thickness 0.25)
		(keepout
			(tracks not_allowed)
			(vias allowed)
			(pads allowed)
			(copperpour not_allowed)
			(footprints allowed)
		)
		(placement
			(enabled no)
			(sheetname "")
		)
		(fill
			(thermal_gap 0.5)
			(thermal_bridge_width 0.5)
			(island_removal_mode 0)
		)
		(polygon
			(pts
				(xy 302.518826 -286.32531) (xy 304.017426 -286.32531) (xy 304.017426 -286.845248) (xy 302.518826 -286.845248)
			)
		)
	)
	(zone
		(layer "In2.Cu")
		(hatch none 0.5)
		(connect_pads
			(clearance 0)
		)
		(min_thickness 0.25)
		(keepout
			(tracks not_allowed)
			(vias allowed)
			(pads allowed)
			(copperpour not_allowed)
			(footprints allowed)
		)
		(placement
			(enabled no)
			(sheetname "")
		)
		(fill
			(thermal_gap 0.5)
			(thermal_bridge_width 0.5)
			(island_removal_mode 0)
		)
		(polygon
			(pts
				(xy 283.986732 -200.475342) (xy 285.485332 -200.475342) (xy 285.485332 -200.99528) (xy 283.986732 -200.99528)
			)
		)
	)
	(zone
		(layer "In2.Cu")
		(hatch none 0.5)
		(connect_pads
			(clearance 0)
		)
		(min_thickness 0.25)
		(keepout
			(tracks not_allowed)
			(vias allowed)
			(pads allowed)
			(copperpour not_allowed)
			(footprints allowed)
		)
		(placement
			(enabled no)
			(sheetname "")
		)
		(fill
			(thermal_gap 0.5)
			(thermal_bridge_width 0.5)
			(island_removal_mode 0)
		)
		(polygon
			(pts
				(xy 302.518826 -227.675186) (xy 304.017426 -227.675186) (xy 304.017426 -228.195124) (xy 302.518826 -228.195124)
			)
		)
	)
	(zone
		(layer "In2.Cu")
		(hatch none 0.5)
		(connect_pads
			(clearance 0)
		)
		(min_thickness 0.25)
		(keepout
			(tracks not_allowed)
			(vias allowed)
			(pads allowed)
			(copperpour not_allowed)
			(footprints allowed)
		)
		(placement
			(enabled no)
			(sheetname "")
		)
		(fill
			(thermal_gap 0.5)
			(thermal_bridge_width 0.5)
			(island_removal_mode 0)
		)
		(polygon
			(pts
				(xy 441.7949 -297.375326) (xy 443.2935 -297.375326) (xy 443.2935 -297.895264) (xy 441.7949 -297.895264)
			)
		)
	)
	(zone
		(layer "In2.Cu")
		(hatch none 0.5)
		(connect_pads
			(clearance 0)
		)
		(min_thickness 0.25)
		(keepout
			(tracks allowed)
			(vias allowed)
			(pads allowed)
			(copperpour allowed)
			(footprints allowed)
		)
		(placement
			(enabled no)
			(sheetname "")
		)
		(fill
			(thermal_gap 0.5)
			(thermal_bridge_width 0.5)
			(island_removal_mode 0)
		)
		(polygon
			(pts
				(xy 375.1199 -180.14696) (xy 375.1199 -179.600606) (xy 375.67235 -179.600606) (xy 375.67235 -180.14696)
			)
		)
	)
	(zone
		(layer "In2.Cu")
		(hatch none 0.5)
		(connect_pads
			(clearance 0)
		)
		(min_thickness 0.25)
		(keepout
			(tracks not_allowed)
			(vias allowed)
			(pads allowed)
			(copperpour not_allowed)
			(footprints allowed)
		)
		(placement
			(enabled no)
			(sheetname "")
		)
		(fill
			(thermal_gap 0.5)
			(thermal_bridge_width 0.5)
			(island_removal_mode 0)
		)
		(polygon
			(pts
				(xy 449.3387 -317.775336) (xy 450.8373 -317.775336) (xy 450.8373 -318.295274) (xy 449.3387 -318.295274)
			)
		)
	)
	(zone
		(layer "In2.Cu")
		(hatch none 0.5)
		(connect_pads
			(clearance 0)
		)
		(min_thickness 0.25)
		(keepout
			(tracks not_allowed)
			(vias allowed)
			(pads allowed)
			(copperpour not_allowed)
			(footprints allowed)
		)
		(placement
			(enabled no)
			(sheetname "")
		)
		(fill
			(thermal_gap 0.5)
			(thermal_bridge_width 0.5)
			(island_removal_mode 0)
		)
		(polygon
			(pts
				(xy 197.954646 -312.67527) (xy 199.453246 -312.67527) (xy 199.453246 -313.195208) (xy 197.954646 -313.195208)
			)
		)
	)
	(zone
		(layer "In2.Cu")
		(hatch none 0.5)
		(connect_pads
			(clearance 0)
		)
		(min_thickness 0.25)
		(keepout
			(tracks not_allowed)
			(vias allowed)
			(pads allowed)
			(copperpour not_allowed)
			(footprints allowed)
		)
		(placement
			(enabled no)
			(sheetname "")
		)
		(fill
			(thermal_gap 0.5)
			(thermal_bridge_width 0.5)
			(island_removal_mode 0)
		)
		(polygon
			(pts
				(xy 175.322738 -245.52529) (xy 176.821338 -245.52529) (xy 176.821338 -246.045228) (xy 175.322738 -246.045228)
			)
		)
	)
	(zone
		(layer "In2.Cu")
		(hatch none 0.5)
		(connect_pads
			(clearance 0)
		)
		(min_thickness 0.25)
		(keepout
			(tracks not_allowed)
			(vias allowed)
			(pads allowed)
			(copperpour not_allowed)
			(footprints allowed)
		)
		(placement
			(enabled no)
			(sheetname "")
		)
		(fill
			(thermal_gap 0.5)
			(thermal_bridge_width 0.5)
			(island_removal_mode 0)
		)
		(polygon
			(pts
				(xy 283.986732 -204.72527) (xy 285.485332 -204.72527) (xy 285.485332 -205.245208) (xy 283.986732 -205.245208)
			)
		)
	)
	(zone
		(layer "In2.Cu")
		(hatch none 0.5)
		(connect_pads
			(clearance 0)
		)
		(min_thickness 0.25)
		(keepout
			(tracks not_allowed)
			(vias allowed)
			(pads allowed)
			(copperpour not_allowed)
			(footprints allowed)
		)
		(placement
			(enabled no)
			(sheetname "")
		)
		(fill
			(thermal_gap 0.5)
			(thermal_bridge_width 0.5)
			(island_removal_mode 0)
		)
		(polygon
			(pts
				(xy 419.162738 -253.175262) (xy 420.661338 -253.175262) (xy 420.661338 -253.6952) (xy 419.162738 -253.6952)
			)
		)
	)
	(zone
		(layer "In2.Cu")
		(hatch none 0.5)
		(connect_pads
			(clearance 0)
		)
		(min_thickness 0.25)
		(keepout
			(tracks not_allowed)
			(vias allowed)
			(pads allowed)
			(copperpour not_allowed)
			(footprints allowed)
		)
		(placement
			(enabled no)
			(sheetname "")
		)
		(fill
			(thermal_gap 0.5)
			(thermal_bridge_width 0.5)
			(island_removal_mode 0)
		)
		(polygon
			(pts
				(xy 291.530786 -210.67522) (xy 293.029386 -210.67522) (xy 293.029386 -211.195158) (xy 291.530786 -211.195158)
			)
		)
	)
	(zone
		(layer "In2.Cu")
		(hatch none 0.5)
		(connect_pads
			(clearance 0)
		)
		(min_thickness 0.25)
		(keepout
			(tracks not_allowed)
			(vias allowed)
			(pads allowed)
			(copperpour not_allowed)
			(footprints allowed)
		)
		(placement
			(enabled no)
			(sheetname "")
		)
		(fill
			(thermal_gap 0.5)
			(thermal_bridge_width 0.5)
			(island_removal_mode 0)
		)
		(polygon
			(pts
				(xy 163.678616 -235.325158) (xy 165.177216 -235.325158) (xy 165.177216 -235.845096) (xy 163.678616 -235.845096)
			)
		)
	)
	(zone
		(layer "In2.Cu")
		(hatch none 0.5)
		(connect_pads
			(clearance 0)
		)
		(min_thickness 0.25)
		(keepout
			(tracks not_allowed)
			(vias allowed)
			(pads allowed)
			(copperpour not_allowed)
			(footprints allowed)
		)
		(placement
			(enabled no)
			(sheetname "")
		)
		(fill
			(thermal_gap 0.5)
			(thermal_bridge_width 0.5)
			(island_removal_mode 0)
		)
		(polygon
			(pts
				(xy 445.894968 -234.475274) (xy 447.393568 -234.475274) (xy 447.393568 -234.995212) (xy 445.894968 -234.995212)
			)
		)
	)
	(zone
		(layer "In2.Cu")
		(hatch none 0.5)
		(connect_pads
			(clearance 0)
		)
		(min_thickness 0.25)
		(keepout
			(tracks not_allowed)
			(vias allowed)
			(pads allowed)
			(copperpour not_allowed)
			(footprints allowed)
		)
		(placement
			(enabled no)
			(sheetname "")
		)
		(fill
			(thermal_gap 0.5)
			(thermal_bridge_width 0.5)
			(island_removal_mode 0)
		)
		(polygon
			(pts
				(xy 16.858742 -283.77515) (xy 18.357342 -283.77515) (xy 18.357342 -284.295088) (xy 16.858742 -284.295088)
			)
		)
	)
	(zone
		(layer "In2.Cu")
		(hatch none 0.5)
		(connect_pads
			(clearance 0)
		)
		(min_thickness 0.25)
		(keepout
			(tracks not_allowed)
			(vias allowed)
			(pads allowed)
			(copperpour not_allowed)
			(footprints allowed)
		)
		(placement
			(enabled no)
			(sheetname "")
		)
		(fill
			(thermal_gap 0.5)
			(thermal_bridge_width 0.5)
			(island_removal_mode 0)
		)
		(polygon
			(pts
				(xy 449.3387 -266.775184) (xy 450.8373 -266.775184) (xy 450.8373 -267.295122) (xy 449.3387 -267.295122)
			)
		)
	)
	(zone
		(layer "In2.Cu")
		(hatch none 0.5)
		(connect_pads
			(clearance 0)
		)
		(min_thickness 0.25)
		(keepout
			(tracks not_allowed)
			(vias allowed)
			(pads allowed)
			(copperpour not_allowed)
			(footprints allowed)
		)
		(placement
			(enabled no)
			(sheetname "")
		)
		(fill
			(thermal_gap 0.5)
			(thermal_bridge_width 0.5)
			(island_removal_mode 0)
		)
		(polygon
			(pts
				(xy 20.95881 -277.8252) (xy 22.45741 -277.8252) (xy 22.45741 -278.345138) (xy 20.95881 -278.345138)
			)
		)
	)
	(zone
		(layer "In2.Cu")
		(hatch none 0.5)
		(connect_pads
			(clearance 0)
		)
		(min_thickness 0.25)
		(keepout
			(tracks not_allowed)
			(vias allowed)
			(pads allowed)
			(copperpour not_allowed)
			(footprints allowed)
		)
		(placement
			(enabled no)
			(sheetname "")
		)
		(fill
			(thermal_gap 0.5)
			(thermal_bridge_width 0.5)
			(island_removal_mode 0)
		)
		(polygon
			(pts
				(xy 419.162738 -288.025332) (xy 420.661338 -288.025332) (xy 420.661338 -288.54527) (xy 419.162738 -288.54527)
			)
		)
	)
	(zone
		(layer "In2.Cu")
		(hatch none 0.5)
		(connect_pads
			(clearance 0)
		)
		(min_thickness 0.25)
		(keepout
			(tracks not_allowed)
			(vias allowed)
			(pads allowed)
			(copperpour not_allowed)
			(footprints allowed)
		)
		(placement
			(enabled no)
			(sheetname "")
		)
		(fill
			(thermal_gap 0.5)
			(thermal_bridge_width 0.5)
			(island_removal_mode 0)
		)
		(polygon
			(pts
				(xy 175.322738 -276.125178) (xy 176.821338 -276.125178) (xy 176.821338 -276.645116) (xy 175.322738 -276.645116)
			)
		)
	)
	(zone
		(layer "In2.Cu")
		(hatch none 0.5)
		(connect_pads
			(clearance 0)
		)
		(min_thickness 0.25)
		(keepout
			(tracks not_allowed)
			(vias allowed)
			(pads allowed)
			(copperpour not_allowed)
			(footprints allowed)
		)
		(placement
			(enabled no)
			(sheetname "")
		)
		(fill
			(thermal_gap 0.5)
			(thermal_bridge_width 0.5)
			(island_removal_mode 0)
		)
		(polygon
			(pts
				(xy 24.402542 -314.375292) (xy 25.901142 -314.375292) (xy 25.901142 -314.89523) (xy 24.402542 -314.89523)
			)
		)
	)
	(zone
		(layer "In2.Cu")
		(hatch none 0.5)
		(connect_pads
			(clearance 0)
		)
		(min_thickness 0.25)
		(keepout
			(tracks not_allowed)
			(vias allowed)
			(pads allowed)
			(copperpour not_allowed)
			(footprints allowed)
		)
		(placement
			(enabled no)
			(sheetname "")
		)
		(fill
			(thermal_gap 0.5)
			(thermal_bridge_width 0.5)
			(island_removal_mode 0)
		)
		(polygon
			(pts
				(xy 175.322738 -288.875216) (xy 176.821338 -288.875216) (xy 176.821338 -289.395154) (xy 175.322738 -289.395154)
			)
		)
	)
	(zone
		(layer "In2.Cu")
		(hatch none 0.5)
		(connect_pads
			(clearance 0)
		)
		(min_thickness 0.25)
		(keepout
			(tracks not_allowed)
			(vias allowed)
			(pads allowed)
			(copperpour not_allowed)
			(footprints allowed)
		)
		(placement
			(enabled no)
			(sheetname "")
		)
		(fill
			(thermal_gap 0.5)
			(thermal_bridge_width 0.5)
			(island_removal_mode 0)
		)
		(polygon
			(pts
				(xy 16.858742 -233.625136) (xy 18.357342 -233.625136) (xy 18.357342 -234.145074) (xy 16.858742 -234.145074)
			)
		)
	)
	(zone
		(layer "In2.Cu")
		(hatch none 0.5)
		(connect_pads
			(clearance 0)
		)
		(min_thickness 0.25)
		(keepout
			(tracks not_allowed)
			(vias allowed)
			(pads allowed)
			(copperpour not_allowed)
			(footprints allowed)
		)
		(placement
			(enabled no)
			(sheetname "")
		)
		(fill
			(thermal_gap 0.5)
			(thermal_bridge_width 0.5)
			(island_removal_mode 0)
		)
		(polygon
			(pts
				(xy 441.7949 -207.275176) (xy 443.2935 -207.275176) (xy 443.2935 -207.795114) (xy 441.7949 -207.795114)
			)
		)
	)
	(zone
		(layer "In2.Cu")
		(hatch none 0.5)
		(connect_pads
			(clearance 0)
		)
		(min_thickness 0.25)
		(keepout
			(tracks not_allowed)
			(vias allowed)
			(pads allowed)
			(copperpour not_allowed)
			(footprints allowed)
		)
		(placement
			(enabled no)
			(sheetname "")
		)
		(fill
			(thermal_gap 0.5)
			(thermal_bridge_width 0.5)
			(island_removal_mode 0)
		)
		(polygon
			(pts
				(xy 423.262806 -292.27526) (xy 424.761406 -292.27526) (xy 424.761406 -292.795198) (xy 423.262806 -292.795198)
			)
		)
	)
	(zone
		(layer "In2.Cu")
		(hatch none 0.5)
		(connect_pads
			(clearance 0)
		)
		(min_thickness 0.25)
		(keepout
			(tracks not_allowed)
			(vias allowed)
			(pads allowed)
			(copperpour not_allowed)
			(footprints allowed)
		)
		(placement
			(enabled no)
			(sheetname "")
		)
		(fill
			(thermal_gap 0.5)
			(thermal_bridge_width 0.5)
			(island_removal_mode 0)
		)
		(polygon
			(pts
				(xy 31.946596 -317.775336) (xy 33.445196 -317.775336) (xy 33.445196 -318.295274) (xy 31.946596 -318.295274)
			)
		)
	)
	(zone
		(layer "In2.Cu")
		(hatch none 0.5)
		(connect_pads
			(clearance 0)
		)
		(min_thickness 0.25)
		(keepout
			(tracks not_allowed)
			(vias allowed)
			(pads allowed)
			(copperpour not_allowed)
			(footprints allowed)
		)
		(placement
			(enabled no)
			(sheetname "")
		)
		(fill
			(thermal_gap 0.5)
			(thermal_bridge_width 0.5)
			(island_removal_mode 0)
		)
		(polygon
			(pts
				(xy 58.678826 -290.575238) (xy 60.177426 -290.575238) (xy 60.177426 -291.095176) (xy 58.678826 -291.095176)
			)
		)
	)
	(zone
		(layer "In2.Cu")
		(hatch none 0.5)
		(connect_pads
			(clearance 0)
		)
		(min_thickness 0.25)
		(keepout
			(tracks allowed)
			(vias allowed)
			(pads allowed)
			(copperpour allowed)
			(footprints allowed)
		)
		(placement
			(enabled no)
			(sheetname "")
		)
		(fill
			(thermal_gap 0.5)
			(thermal_bridge_width 0.5)
			(island_removal_mode 0)
		)
		(polygon
			(pts
				(xy 330.052172 -338.195666) (xy 330.052172 -337.573366) (xy 330.603352 -337.573366) (xy 330.603352 -338.195666)
			)
		)
	)
	(zone
		(layer "In2.Cu")
		(hatch none 0.5)
		(connect_pads
			(clearance 0)
		)
		(min_thickness 0.25)
		(keepout
			(tracks not_allowed)
			(vias allowed)
			(pads allowed)
			(copperpour not_allowed)
			(footprints allowed)
		)
		(placement
			(enabled no)
			(sheetname "")
		)
		(fill
			(thermal_gap 0.5)
			(thermal_bridge_width 0.5)
			(island_removal_mode 0)
		)
		(polygon
			(pts
				(xy 453.438768 -288.875216) (xy 454.937368 -288.875216) (xy 454.937368 -289.395154) (xy 453.438768 -289.395154)
			)
		)
	)
	(zone
		(layer "In2.Cu")
		(hatch none 0.5)
		(connect_pads
			(clearance 0)
		)
		(min_thickness 0.25)
		(keepout
			(tracks not_allowed)
			(vias allowed)
			(pads allowed)
			(copperpour not_allowed)
			(footprints allowed)
		)
		(placement
			(enabled no)
			(sheetname "")
		)
		(fill
			(thermal_gap 0.5)
			(thermal_bridge_width 0.5)
			(island_removal_mode 0)
		)
		(polygon
			(pts
				(xy 279.886664 -311.825132) (xy 281.385264 -311.825132) (xy 281.385264 -312.34507) (xy 279.886664 -312.34507)
			)
		)
	)
	(zone
		(layer "In2.Cu")
		(hatch none 0.5)
		(connect_pads
			(clearance 0)
		)
		(min_thickness 0.25)
		(keepout
			(tracks not_allowed)
			(vias allowed)
			(pads allowed)
			(copperpour not_allowed)
			(footprints allowed)
		)
		(placement
			(enabled no)
			(sheetname "")
		)
		(fill
			(thermal_gap 0.5)
			(thermal_bridge_width 0.5)
			(island_removal_mode 0)
		)
		(polygon
			(pts
				(xy 426.706792 -203.875132) (xy 428.205392 -203.875132) (xy 428.205392 -204.39507) (xy 426.706792 -204.39507)
			)
		)
	)
	(zone
		(layer "In2.Cu")
		(hatch none 0.5)
		(connect_pads
			(clearance 0)
		)
		(min_thickness 0.25)
		(keepout
			(tracks not_allowed)
			(vias allowed)
			(pads allowed)
			(copperpour not_allowed)
			(footprints allowed)
		)
		(placement
			(enabled no)
			(sheetname "")
		)
		(fill
			(thermal_gap 0.5)
			(thermal_bridge_width 0.5)
			(island_removal_mode 0)
		)
		(polygon
			(pts
				(xy 201.398632 -218.325192) (xy 202.897232 -218.325192) (xy 202.897232 -218.84513) (xy 201.398632 -218.84513)
			)
		)
	)
	(zone
		(layer "In2.Cu")
		(hatch none 0.5)
		(connect_pads
			(clearance 0)
		)
		(min_thickness 0.25)
		(keepout
			(tracks not_allowed)
			(vias allowed)
			(pads allowed)
			(copperpour not_allowed)
			(footprints allowed)
		)
		(placement
			(enabled no)
			(sheetname "")
		)
		(fill
			(thermal_gap 0.5)
			(thermal_bridge_width 0.5)
			(island_removal_mode 0)
		)
		(polygon
			(pts
				(xy 430.80686 -267.625322) (xy 432.30546 -267.625322) (xy 432.30546 -268.14526) (xy 430.80686 -268.14526)
			)
		)
	)
	(zone
		(layer "In2.Cu")
		(hatch none 0.5)
		(connect_pads
			(clearance 0)
		)
		(min_thickness 0.25)
		(keepout
			(tracks not_allowed)
			(vias allowed)
			(pads allowed)
			(copperpour not_allowed)
			(footprints allowed)
		)
		(placement
			(enabled no)
			(sheetname "")
		)
		(fill
			(thermal_gap 0.5)
			(thermal_bridge_width 0.5)
			(island_removal_mode 0)
		)
		(polygon
			(pts
				(xy 163.678616 -199.625204) (xy 165.177216 -199.625204) (xy 165.177216 -200.145142) (xy 163.678616 -200.145142)
			)
		)
	)
	(zone
		(layer "In2.Cu")
		(hatch none 0.5)
		(connect_pads
			(clearance 0)
		)
		(min_thickness 0.25)
		(keepout
			(tracks not_allowed)
			(vias allowed)
			(pads allowed)
			(copperpour not_allowed)
			(footprints allowed)
		)
		(placement
			(enabled no)
			(sheetname "")
		)
		(fill
			(thermal_gap 0.5)
			(thermal_bridge_width 0.5)
			(island_removal_mode 0)
		)
		(polygon
			(pts
				(xy 276.442932 -219.17533) (xy 277.941532 -219.17533) (xy 277.941532 -219.695268) (xy 276.442932 -219.695268)
			)
		)
	)
	(zone
		(layer "In2.Cu")
		(hatch none 0.5)
		(connect_pads
			(clearance 0)
		)
		(min_thickness 0.25)
		(keepout
			(tracks not_allowed)
			(vias allowed)
			(pads allowed)
			(copperpour not_allowed)
			(footprints allowed)
		)
		(placement
			(enabled no)
			(sheetname "")
		)
		(fill
			(thermal_gap 0.5)
			(thermal_bridge_width 0.5)
			(island_removal_mode 0)
		)
		(polygon
			(pts
				(xy 272.342864 -241.275108) (xy 273.841464 -241.275108) (xy 273.841464 -241.795046) (xy 272.342864 -241.795046)
			)
		)
	)
	(zone
		(layer "In2.Cu")
		(hatch none 0.5)
		(connect_pads
			(clearance 0)
		)
		(min_thickness 0.25)
		(keepout
			(tracks not_allowed)
			(vias allowed)
			(pads allowed)
			(copperpour not_allowed)
			(footprints allowed)
		)
		(placement
			(enabled no)
			(sheetname "")
		)
		(fill
			(thermal_gap 0.5)
			(thermal_bridge_width 0.5)
			(island_removal_mode 0)
		)
		(polygon
			(pts
				(xy 430.80686 -271.87525) (xy 432.30546 -271.87525) (xy 432.30546 -272.395188) (xy 430.80686 -272.395188)
			)
		)
	)
	(zone
		(layer "In2.Cu")
		(hatch none 0.5)
		(connect_pads
			(clearance 0)
		)
		(min_thickness 0.25)
		(keepout
			(tracks not_allowed)
			(vias allowed)
			(pads allowed)
			(copperpour not_allowed)
			(footprints allowed)
		)
		(placement
			(enabled no)
			(sheetname "")
		)
		(fill
			(thermal_gap 0.5)
			(thermal_bridge_width 0.5)
			(island_removal_mode 0)
		)
		(polygon
			(pts
				(xy 175.322738 -294.825166) (xy 176.821338 -294.825166) (xy 176.821338 -295.345104) (xy 175.322738 -295.345104)
			)
		)
	)
	(zone
		(layer "In2.Cu")
		(hatch none 0.5)
		(connect_pads
			(clearance 0)
		)
		(min_thickness 0.25)
		(keepout
			(tracks not_allowed)
			(vias allowed)
			(pads allowed)
			(copperpour not_allowed)
			(footprints allowed)
		)
		(placement
			(enabled no)
			(sheetname "")
		)
		(fill
			(thermal_gap 0.5)
			(thermal_bridge_width 0.5)
			(island_removal_mode 0)
		)
		(polygon
			(pts
				(xy 197.954646 -264.225278) (xy 199.453246 -264.225278) (xy 199.453246 -264.745216) (xy 197.954646 -264.745216)
			)
		)
	)
	(zone
		(layer "In2.Cu")
		(hatch none 0.5)
		(connect_pads
			(clearance 0)
		)
		(min_thickness 0.25)
		(keepout
			(tracks not_allowed)
			(vias allowed)
			(pads allowed)
			(copperpour not_allowed)
			(footprints allowed)
		)
		(placement
			(enabled no)
			(sheetname "")
		)
		(fill
			(thermal_gap 0.5)
			(thermal_bridge_width 0.5)
			(island_removal_mode 0)
		)
		(polygon
			(pts
				(xy 426.706792 -238.725202) (xy 428.205392 -238.725202) (xy 428.205392 -239.24514) (xy 426.706792 -239.24514)
			)
		)
	)
	(zone
		(layer "In2.Cu")
		(hatch none 0.5)
		(connect_pads
			(clearance 0)
		)
		(min_thickness 0.25)
		(keepout
			(tracks not_allowed)
			(vias allowed)
			(pads allowed)
			(copperpour not_allowed)
			(footprints allowed)
		)
		(placement
			(enabled no)
			(sheetname "")
		)
		(fill
			(thermal_gap 0.5)
			(thermal_bridge_width 0.5)
			(island_removal_mode 0)
		)
		(polygon
			(pts
				(xy 276.442932 -217.475308) (xy 277.941532 -217.475308) (xy 277.941532 -217.995246) (xy 276.442932 -217.995246)
			)
		)
	)
	(zone
		(layer "In2.Cu")
		(hatch none 0.5)
		(connect_pads
			(clearance 0)
		)
		(min_thickness 0.25)
		(keepout
			(tracks not_allowed)
			(vias allowed)
			(pads allowed)
			(copperpour not_allowed)
			(footprints allowed)
		)
		(placement
			(enabled no)
			(sheetname "")
		)
		(fill
			(thermal_gap 0.5)
			(thermal_bridge_width 0.5)
			(island_removal_mode 0)
		)
		(polygon
			(pts
				(xy 415.718752 -214.075264) (xy 417.217352 -214.075264) (xy 417.217352 -214.595202) (xy 415.718752 -214.595202)
			)
		)
	)
	(zone
		(layer "In2.Cu")
		(hatch none 0.5)
		(connect_pads
			(clearance 0)
		)
		(min_thickness 0.25)
		(keepout
			(tracks not_allowed)
			(vias allowed)
			(pads allowed)
			(copperpour not_allowed)
			(footprints allowed)
		)
		(placement
			(enabled no)
			(sheetname "")
		)
		(fill
			(thermal_gap 0.5)
			(thermal_bridge_width 0.5)
			(island_removal_mode 0)
		)
		(polygon
			(pts
				(xy 287.430718 -211.525104) (xy 288.929318 -211.525104) (xy 288.929318 -212.045042) (xy 287.430718 -212.045042)
			)
		)
	)
	(zone
		(layer "In2.Cu")
		(hatch none 0.5)
		(connect_pads
			(clearance 0)
		)
		(min_thickness 0.25)
		(keepout
			(tracks not_allowed)
			(vias allowed)
			(pads allowed)
			(copperpour not_allowed)
			(footprints allowed)
		)
		(placement
			(enabled no)
			(sheetname "")
		)
		(fill
			(thermal_gap 0.5)
			(thermal_bridge_width 0.5)
			(island_removal_mode 0)
		)
		(polygon
			(pts
				(xy 197.954646 -236.175296) (xy 199.453246 -236.175296) (xy 199.453246 -236.695234) (xy 197.954646 -236.695234)
			)
		)
	)
	(zone
		(layer "In2.Cu")
		(hatch none 0.5)
		(connect_pads
			(clearance 0)
		)
		(min_thickness 0.25)
		(keepout
			(tracks not_allowed)
			(vias allowed)
			(pads allowed)
			(copperpour not_allowed)
			(footprints allowed)
		)
		(placement
			(enabled no)
			(sheetname "")
		)
		(fill
			(thermal_gap 0.5)
			(thermal_bridge_width 0.5)
			(island_removal_mode 0)
		)
		(polygon
			(pts
				(xy 291.530786 -226.825302) (xy 293.029386 -226.825302) (xy 293.029386 -227.34524) (xy 291.530786 -227.34524)
			)
		)
	)
	(zone
		(layer "In2.Cu")
		(hatch none 0.5)
		(connect_pads
			(clearance 0)
		)
		(min_thickness 0.25)
		(keepout
			(tracks not_allowed)
			(vias allowed)
			(pads allowed)
			(copperpour not_allowed)
			(footprints allowed)
		)
		(placement
			(enabled no)
			(sheetname "")
		)
		(fill
			(thermal_gap 0.5)
			(thermal_bridge_width 0.5)
			(island_removal_mode 0)
		)
		(polygon
			(pts
				(xy 28.50261 -310.975248) (xy 30.00121 -310.975248) (xy 30.00121 -311.495186) (xy 28.50261 -311.495186)
			)
		)
	)
	(zone
		(layer "In2.Cu")
		(hatch none 0.5)
		(connect_pads
			(clearance 0)
		)
		(min_thickness 0.25)
		(keepout
			(tracks not_allowed)
			(vias allowed)
			(pads allowed)
			(copperpour not_allowed)
			(footprints allowed)
		)
		(placement
			(enabled no)
			(sheetname "")
		)
		(fill
			(thermal_gap 0.5)
			(thermal_bridge_width 0.5)
			(island_removal_mode 0)
		)
		(polygon
			(pts
				(xy 276.442932 -271.87525) (xy 277.941532 -271.87525) (xy 277.941532 -272.395188) (xy 276.442932 -272.395188)
			)
		)
	)
	(zone
		(layer "In2.Cu")
		(hatch none 0.5)
		(connect_pads
			(clearance 0)
		)
		(min_thickness 0.25)
		(keepout
			(tracks not_allowed)
			(vias allowed)
			(pads allowed)
			(copperpour not_allowed)
			(footprints allowed)
		)
		(placement
			(enabled no)
			(sheetname "")
		)
		(fill
			(thermal_gap 0.5)
			(thermal_bridge_width 0.5)
			(island_removal_mode 0)
		)
		(polygon
			(pts
				(xy 171.22267 -314.375292) (xy 172.72127 -314.375292) (xy 172.72127 -314.89523) (xy 171.22267 -314.89523)
			)
		)
	)
	(zone
		(layer "In2.Cu")
		(hatch none 0.5)
		(connect_pads
			(clearance 0)
		)
		(min_thickness 0.25)
		(keepout
			(tracks not_allowed)
			(vias allowed)
			(pads allowed)
			(copperpour not_allowed)
			(footprints allowed)
		)
		(placement
			(enabled no)
			(sheetname "")
		)
		(fill
			(thermal_gap 0.5)
			(thermal_bridge_width 0.5)
			(island_removal_mode 0)
		)
		(polygon
			(pts
				(xy 445.894968 -309.275226) (xy 447.393568 -309.275226) (xy 447.393568 -309.795164) (xy 445.894968 -309.795164)
			)
		)
	)
	(zone
		(layer "In2.Cu")
		(hatch none 0.5)
		(connect_pads
			(clearance 0)
		)
		(min_thickness 0.25)
		(keepout
			(tracks not_allowed)
			(vias allowed)
			(pads allowed)
			(copperpour not_allowed)
			(footprints allowed)
		)
		(placement
			(enabled no)
			(sheetname "")
		)
		(fill
			(thermal_gap 0.5)
			(thermal_bridge_width 0.5)
			(island_removal_mode 0)
		)
		(polygon
			(pts
				(xy 20.95881 -206.425292) (xy 22.45741 -206.425292) (xy 22.45741 -206.94523) (xy 20.95881 -206.94523)
			)
		)
	)
	(zone
		(layer "In2.Cu")
		(hatch none 0.5)
		(connect_pads
			(clearance 0)
		)
		(min_thickness 0.25)
		(keepout
			(tracks not_allowed)
			(vias allowed)
			(pads allowed)
			(copperpour not_allowed)
			(footprints allowed)
		)
		(placement
			(enabled no)
			(sheetname "")
		)
		(fill
			(thermal_gap 0.5)
			(thermal_bridge_width 0.5)
			(island_removal_mode 0)
		)
		(polygon
			(pts
				(xy 445.894968 -231.07523) (xy 447.393568 -231.07523) (xy 447.393568 -231.595168) (xy 445.894968 -231.595168)
			)
		)
	)
	(zone
		(layer "In2.Cu")
		(hatch none 0.5)
		(connect_pads
			(clearance 0)
		)
		(min_thickness 0.25)
		(keepout
			(tracks not_allowed)
			(vias allowed)
			(pads allowed)
			(copperpour not_allowed)
			(footprints allowed)
		)
		(placement
			(enabled no)
			(sheetname "")
		)
		(fill
			(thermal_gap 0.5)
			(thermal_bridge_width 0.5)
			(island_removal_mode 0)
		)
		(polygon
			(pts
				(xy 419.162738 -216.62517) (xy 420.661338 -216.62517) (xy 420.661338 -217.145108) (xy 419.162738 -217.145108)
			)
		)
	)
	(zone
		(layer "In2.Cu")
		(hatch none 0.5)
		(connect_pads
			(clearance 0)
		)
		(min_thickness 0.25)
		(keepout
			(tracks not_allowed)
			(vias allowed)
			(pads allowed)
			(copperpour not_allowed)
			(footprints allowed)
		)
		(placement
			(enabled no)
			(sheetname "")
		)
		(fill
			(thermal_gap 0.5)
			(thermal_bridge_width 0.5)
			(island_removal_mode 0)
		)
		(polygon
			(pts
				(xy 434.250846 -313.525154) (xy 435.749446 -313.525154) (xy 435.749446 -314.045092) (xy 434.250846 -314.045092)
			)
		)
	)
	(zone
		(layer "In2.Cu")
		(hatch none 0.5)
		(connect_pads
			(clearance 0)
		)
		(min_thickness 0.25)
		(keepout
			(tracks not_allowed)
			(vias allowed)
			(pads allowed)
			(copperpour not_allowed)
			(footprints allowed)
		)
		(placement
			(enabled no)
			(sheetname "")
		)
		(fill
			(thermal_gap 0.5)
			(thermal_bridge_width 0.5)
			(island_removal_mode 0)
		)
		(polygon
			(pts
				(xy 430.80686 -294.825166) (xy 432.30546 -294.825166) (xy 432.30546 -295.345104) (xy 430.80686 -295.345104)
			)
		)
	)
	(zone
		(layer "In2.Cu")
		(hatch none 0.5)
		(connect_pads
			(clearance 0)
		)
		(min_thickness 0.25)
		(keepout
			(tracks not_allowed)
			(vias allowed)
			(pads allowed)
			(copperpour not_allowed)
			(footprints allowed)
		)
		(placement
			(enabled no)
			(sheetname "")
		)
		(fill
			(thermal_gap 0.5)
			(thermal_bridge_width 0.5)
			(island_removal_mode 0)
		)
		(polygon
			(pts
				(xy 287.430718 -244.675152) (xy 288.929318 -244.675152) (xy 288.929318 -245.19509) (xy 287.430718 -245.19509)
			)
		)
	)
	(zone
		(layer "In2.Cu")
		(hatch none 0.5)
		(connect_pads
			(clearance 0)
		)
		(min_thickness 0.25)
		(keepout
			(tracks not_allowed)
			(vias allowed)
			(pads allowed)
			(copperpour not_allowed)
			(footprints allowed)
		)
		(placement
			(enabled no)
			(sheetname "")
		)
		(fill
			(thermal_gap 0.5)
			(thermal_bridge_width 0.5)
			(island_removal_mode 0)
		)
		(polygon
			(pts
				(xy 268.898878 -275.275294) (xy 270.397478 -275.275294) (xy 270.397478 -275.795232) (xy 268.898878 -275.795232)
			)
		)
	)
	(zone
		(layer "In2.Cu")
		(hatch none 0.5)
		(connect_pads
			(clearance 0)
		)
		(min_thickness 0.25)
		(keepout
			(tracks not_allowed)
			(vias allowed)
			(pads allowed)
			(copperpour not_allowed)
			(footprints allowed)
		)
		(placement
			(enabled no)
			(sheetname "")
		)
		(fill
			(thermal_gap 0.5)
			(thermal_bridge_width 0.5)
			(island_removal_mode 0)
		)
		(polygon
			(pts
				(xy 426.706792 -249.775218) (xy 428.205392 -249.775218) (xy 428.205392 -250.295156) (xy 426.706792 -250.295156)
			)
		)
	)
	(zone
		(layer "In2.Cu")
		(hatch none 0.5)
		(connect_pads
			(clearance 0)
		)
		(min_thickness 0.25)
		(keepout
			(tracks not_allowed)
			(vias allowed)
			(pads allowed)
			(copperpour not_allowed)
			(footprints allowed)
		)
		(placement
			(enabled no)
			(sheetname "")
		)
		(fill
			(thermal_gap 0.5)
			(thermal_bridge_width 0.5)
			(island_removal_mode 0)
		)
		(polygon
			(pts
				(xy 279.886664 -317.775336) (xy 281.385264 -317.775336) (xy 281.385264 -318.295274) (xy 279.886664 -318.295274)
			)
		)
	)
	(zone
		(layer "In2.Cu")
		(hatch none 0.5)
		(connect_pads
			(clearance 0)
		)
		(min_thickness 0.25)
		(keepout
			(tracks not_allowed)
			(vias allowed)
			(pads allowed)
			(copperpour not_allowed)
			(footprints allowed)
		)
		(placement
			(enabled no)
			(sheetname "")
		)
		(fill
			(thermal_gap 0.5)
			(thermal_bridge_width 0.5)
			(island_removal_mode 0)
		)
		(polygon
			(pts
				(xy 419.162738 -280.375106) (xy 420.661338 -280.375106) (xy 420.661338 -280.895044) (xy 419.162738 -280.895044)
			)
		)
	)
	(zone
		(layer "In2.Cu")
		(hatch none 0.5)
		(connect_pads
			(clearance 0)
		)
		(min_thickness 0.25)
		(keepout
			(tracks not_allowed)
			(vias allowed)
			(pads allowed)
			(copperpour not_allowed)
			(footprints allowed)
		)
		(placement
			(enabled no)
			(sheetname "")
		)
		(fill
			(thermal_gap 0.5)
			(thermal_bridge_width 0.5)
			(island_removal_mode 0)
		)
		(polygon
			(pts
				(xy 299.07484 -304.17516) (xy 300.57344 -304.17516) (xy 300.57344 -304.695098) (xy 299.07484 -304.695098)
			)
		)
	)
	(zone
		(layer "In2.Cu")
		(hatch none 0.5)
		(connect_pads
			(clearance 0)
		)
		(min_thickness 0.25)
		(keepout
			(tracks not_allowed)
			(vias allowed)
			(pads allowed)
			(copperpour not_allowed)
			(footprints allowed)
		)
		(placement
			(enabled no)
			(sheetname "")
		)
		(fill
			(thermal_gap 0.5)
			(thermal_bridge_width 0.5)
			(island_removal_mode 0)
		)
		(polygon
			(pts
				(xy 193.854578 -302.475138) (xy 195.353178 -302.475138) (xy 195.353178 -302.995076) (xy 193.854578 -302.995076)
			)
		)
	)
	(zone
		(layer "In2.Cu")
		(hatch none 0.5)
		(connect_pads
			(clearance 0)
		)
		(min_thickness 0.25)
		(keepout
			(tracks not_allowed)
			(vias allowed)
			(pads allowed)
			(copperpour not_allowed)
			(footprints allowed)
		)
		(placement
			(enabled no)
			(sheetname "")
		)
		(fill
			(thermal_gap 0.5)
			(thermal_bridge_width 0.5)
			(island_removal_mode 0)
		)
		(polygon
			(pts
				(xy 47.034704 -249.775218) (xy 48.533304 -249.775218) (xy 48.533304 -250.295156) (xy 47.034704 -250.295156)
			)
		)
	)
	(zone
		(layer "In2.Cu")
		(hatch none 0.5)
		(connect_pads
			(clearance 0)
		)
		(min_thickness 0.25)
		(keepout
			(tracks not_allowed)
			(vias allowed)
			(pads allowed)
			(copperpour not_allowed)
			(footprints allowed)
		)
		(placement
			(enabled no)
			(sheetname "")
		)
		(fill
			(thermal_gap 0.5)
			(thermal_bridge_width 0.5)
			(island_removal_mode 0)
		)
		(polygon
			(pts
				(xy 438.350914 -204.72527) (xy 439.849514 -204.72527) (xy 439.849514 -205.245208) (xy 438.350914 -205.245208)
			)
		)
	)
	(zone
		(layer "In2.Cu")
		(hatch none 0.5)
		(connect_pads
			(clearance 0)
		)
		(min_thickness 0.25)
		(keepout
			(tracks not_allowed)
			(vias allowed)
			(pads allowed)
			(copperpour not_allowed)
			(footprints allowed)
		)
		(placement
			(enabled no)
			(sheetname "")
		)
		(fill
			(thermal_gap 0.5)
			(thermal_bridge_width 0.5)
			(island_removal_mode 0)
		)
		(polygon
			(pts
				(xy 415.718752 -313.525154) (xy 417.217352 -313.525154) (xy 417.217352 -314.045092) (xy 415.718752 -314.045092)
			)
		)
	)
	(zone
		(layer "In2.Cu")
		(hatch none 0.5)
		(connect_pads
			(clearance 0)
		)
		(min_thickness 0.25)
		(keepout
			(tracks not_allowed)
			(vias allowed)
			(pads allowed)
			(copperpour not_allowed)
			(footprints allowed)
		)
		(placement
			(enabled no)
			(sheetname "")
		)
		(fill
			(thermal_gap 0.5)
			(thermal_bridge_width 0.5)
			(island_removal_mode 0)
		)
		(polygon
			(pts
				(xy 438.350914 -304.17516) (xy 439.849514 -304.17516) (xy 439.849514 -304.695098) (xy 438.350914 -304.695098)
			)
		)
	)
	(zone
		(layer "In2.Cu")
		(hatch none 0.5)
		(connect_pads
			(clearance 0)
		)
		(min_thickness 0.25)
		(keepout
			(tracks not_allowed)
			(vias allowed)
			(pads allowed)
			(copperpour not_allowed)
			(footprints allowed)
		)
		(placement
			(enabled no)
			(sheetname "")
		)
		(fill
			(thermal_gap 0.5)
			(thermal_bridge_width 0.5)
			(island_removal_mode 0)
		)
		(polygon
			(pts
				(xy 419.162738 -197.925182) (xy 420.661338 -197.925182) (xy 420.661338 -198.44512) (xy 419.162738 -198.44512)
			)
		)
	)
	(zone
		(layer "In2.Cu")
		(hatch none 0.5)
		(connect_pads
			(clearance 0)
		)
		(min_thickness 0.25)
		(keepout
			(tracks not_allowed)
			(vias allowed)
			(pads allowed)
			(copperpour not_allowed)
			(footprints allowed)
		)
		(placement
			(enabled no)
			(sheetname "")
		)
		(fill
			(thermal_gap 0.5)
			(thermal_bridge_width 0.5)
			(island_removal_mode 0)
		)
		(polygon
			(pts
				(xy 167.778684 -301.625254) (xy 169.277284 -301.625254) (xy 169.277284 -302.145192) (xy 167.778684 -302.145192)
			)
		)
	)
	(zone
		(layer "In2.Cu")
		(hatch none 0.5)
		(connect_pads
			(clearance 0)
		)
		(min_thickness 0.25)
		(keepout
			(tracks not_allowed)
			(vias allowed)
			(pads allowed)
			(copperpour not_allowed)
			(footprints allowed)
		)
		(placement
			(enabled no)
			(sheetname "")
		)
		(fill
			(thermal_gap 0.5)
			(thermal_bridge_width 0.5)
			(island_removal_mode 0)
		)
		(polygon
			(pts
				(xy 20.95881 -309.275226) (xy 22.45741 -309.275226) (xy 22.45741 -309.795164) (xy 20.95881 -309.795164)
			)
		)
	)
	(zone
		(layer "In2.Cu")
		(hatch none 0.5)
		(connect_pads
			(clearance 0)
		)
		(min_thickness 0.25)
		(keepout
			(tracks not_allowed)
			(vias allowed)
			(pads allowed)
			(copperpour not_allowed)
			(footprints allowed)
		)
		(placement
			(enabled no)
			(sheetname "")
		)
		(fill
			(thermal_gap 0.5)
			(thermal_bridge_width 0.5)
			(island_removal_mode 0)
		)
		(polygon
			(pts
				(xy 58.678826 -217.475308) (xy 60.177426 -217.475308) (xy 60.177426 -217.995246) (xy 58.678826 -217.995246)
			)
		)
	)
	(zone
		(layer "In2.Cu")
		(hatch none 0.5)
		(connect_pads
			(clearance 0)
		)
		(min_thickness 0.25)
		(keepout
			(tracks not_allowed)
			(vias allowed)
			(pads allowed)
			(copperpour not_allowed)
			(footprints allowed)
		)
		(placement
			(enabled no)
			(sheetname "")
		)
		(fill
			(thermal_gap 0.5)
			(thermal_bridge_width 0.5)
			(island_removal_mode 0)
		)
		(polygon
			(pts
				(xy 419.162738 -208.975198) (xy 420.661338 -208.975198) (xy 420.661338 -209.495136) (xy 419.162738 -209.495136)
			)
		)
	)
	(zone
		(layer "In2.Cu")
		(hatch none 0.5)
		(connect_pads
			(clearance 0)
		)
		(min_thickness 0.25)
		(keepout
			(tracks not_allowed)
			(vias allowed)
			(pads allowed)
			(copperpour not_allowed)
			(footprints allowed)
		)
		(placement
			(enabled no)
			(sheetname "")
		)
		(fill
			(thermal_gap 0.5)
			(thermal_bridge_width 0.5)
			(island_removal_mode 0)
		)
		(polygon
			(pts
				(xy 186.310778 -299.075348) (xy 187.809378 -299.075348) (xy 187.809378 -299.595286) (xy 186.310778 -299.595286)
			)
		)
	)
	(zone
		(layer "In2.Cu")
		(hatch none 0.5)
		(connect_pads
			(clearance 0)
		)
		(min_thickness 0.25)
		(keepout
			(tracks not_allowed)
			(vias allowed)
			(pads allowed)
			(copperpour not_allowed)
			(footprints allowed)
		)
		(placement
			(enabled no)
			(sheetname "")
		)
		(fill
			(thermal_gap 0.5)
			(thermal_bridge_width 0.5)
			(island_removal_mode 0)
		)
		(polygon
			(pts
				(xy 294.974772 -216.62517) (xy 296.473372 -216.62517) (xy 296.473372 -217.145108) (xy 294.974772 -217.145108)
			)
		)
	)
	(zone
		(layer "In2.Cu")
		(hatch none 0.5)
		(connect_pads
			(clearance 0)
		)
		(min_thickness 0.25)
		(keepout
			(tracks not_allowed)
			(vias allowed)
			(pads allowed)
			(copperpour not_allowed)
			(footprints allowed)
		)
		(placement
			(enabled no)
			(sheetname "")
		)
		(fill
			(thermal_gap 0.5)
			(thermal_bridge_width 0.5)
			(island_removal_mode 0)
		)
		(polygon
			(pts
				(xy 415.718752 -245.52529) (xy 417.217352 -245.52529) (xy 417.217352 -246.045228) (xy 415.718752 -246.045228)
			)
		)
	)
	(zone
		(layer "In2.Cu")
		(hatch none 0.5)
		(connect_pads
			(clearance 0)
		)
		(min_thickness 0.25)
		(keepout
			(tracks allowed)
			(vias allowed)
			(pads allowed)
			(copperpour allowed)
			(footprints allowed)
		)
		(placement
			(enabled no)
			(sheetname "")
		)
		(fill
			(thermal_gap 0.5)
			(thermal_bridge_width 0.5)
			(island_removal_mode 0)
		)
		(polygon
			(pts
				(xy 328.130154 -338.12607) (xy 328.130154 -337.50377) (xy 328.681334 -337.50377) (xy 328.681334 -338.12607)
			)
		)
	)
	(zone
		(layer "In2.Cu")
		(hatch none 0.5)
		(connect_pads
			(clearance 0)
		)
		(min_thickness 0.25)
		(keepout
			(tracks not_allowed)
			(vias allowed)
			(pads allowed)
			(copperpour not_allowed)
			(footprints allowed)
		)
		(placement
			(enabled no)
			(sheetname "")
		)
		(fill
			(thermal_gap 0.5)
			(thermal_bridge_width 0.5)
			(island_removal_mode 0)
		)
		(polygon
			(pts
				(xy 419.162738 -218.325192) (xy 420.661338 -218.325192) (xy 420.661338 -218.84513) (xy 419.162738 -218.84513)
			)
		)
	)
	(zone
		(layer "In2.Cu")
		(hatch none 0.5)
		(connect_pads
			(clearance 0)
		)
		(min_thickness 0.25)
		(keepout
			(tracks not_allowed)
			(vias allowed)
			(pads allowed)
			(copperpour not_allowed)
			(footprints allowed)
		)
		(placement
			(enabled no)
			(sheetname "")
		)
		(fill
			(thermal_gap 0.5)
			(thermal_bridge_width 0.5)
			(island_removal_mode 0)
		)
		(polygon
			(pts
				(xy 20.95881 -234.475274) (xy 22.45741 -234.475274) (xy 22.45741 -234.995212) (xy 20.95881 -234.995212)
			)
		)
	)
	(zone
		(layer "In2.Cu")
		(hatch none 0.5)
		(connect_pads
			(clearance 0)
		)
		(min_thickness 0.25)
		(keepout
			(tracks not_allowed)
			(vias allowed)
			(pads allowed)
			(copperpour not_allowed)
			(footprints allowed)
		)
		(placement
			(enabled no)
			(sheetname "")
		)
		(fill
			(thermal_gap 0.5)
			(thermal_bridge_width 0.5)
			(island_removal_mode 0)
		)
		(polygon
			(pts
				(xy 201.398632 -239.57534) (xy 202.897232 -239.57534) (xy 202.897232 -240.095278) (xy 201.398632 -240.095278)
			)
		)
	)
	(zone
		(layer "In2.Cu")
		(hatch none 0.5)
		(connect_pads
			(clearance 0)
		)
		(min_thickness 0.25)
		(keepout
			(tracks not_allowed)
			(vias allowed)
			(pads allowed)
			(copperpour not_allowed)
			(footprints allowed)
		)
		(placement
			(enabled no)
			(sheetname "")
		)
		(fill
			(thermal_gap 0.5)
			(thermal_bridge_width 0.5)
			(island_removal_mode 0)
		)
		(polygon
			(pts
				(xy 287.430718 -283.77515) (xy 288.929318 -283.77515) (xy 288.929318 -284.295088) (xy 287.430718 -284.295088)
			)
		)
	)
	(zone
		(layer "In2.Cu")
		(hatch none 0.5)
		(connect_pads
			(clearance 0)
		)
		(min_thickness 0.25)
		(keepout
			(tracks not_allowed)
			(vias allowed)
			(pads allowed)
			(copperpour not_allowed)
			(footprints allowed)
		)
		(placement
			(enabled no)
			(sheetname "")
		)
		(fill
			(thermal_gap 0.5)
			(thermal_bridge_width 0.5)
			(island_removal_mode 0)
		)
		(polygon
			(pts
				(xy 306.618894 -293.975282) (xy 308.117494 -293.975282) (xy 308.117494 -294.49522) (xy 306.618894 -294.49522)
			)
		)
	)
	(zone
		(layer "In2.Cu")
		(hatch none 0.5)
		(connect_pads
			(clearance 0)
		)
		(min_thickness 0.25)
		(keepout
			(tracks not_allowed)
			(vias allowed)
			(pads allowed)
			(copperpour not_allowed)
			(footprints allowed)
		)
		(placement
			(enabled no)
			(sheetname "")
		)
		(fill
			(thermal_gap 0.5)
			(thermal_bridge_width 0.5)
			(island_removal_mode 0)
		)
		(polygon
			(pts
				(xy 58.678826 -269.325344) (xy 60.177426 -269.325344) (xy 60.177426 -269.845282) (xy 58.678826 -269.845282)
			)
		)
	)
	(zone
		(layer "In2.Cu")
		(hatch none 0.5)
		(connect_pads
			(clearance 0)
		)
		(min_thickness 0.25)
		(keepout
			(tracks not_allowed)
			(vias allowed)
			(pads allowed)
			(copperpour not_allowed)
			(footprints allowed)
		)
		(placement
			(enabled no)
			(sheetname "")
		)
		(fill
			(thermal_gap 0.5)
			(thermal_bridge_width 0.5)
			(island_removal_mode 0)
		)
		(polygon
			(pts
				(xy 175.322738 -296.525188) (xy 176.821338 -296.525188) (xy 176.821338 -297.045126) (xy 175.322738 -297.045126)
			)
		)
	)
	(zone
		(layer "In2.Cu")
		(hatch none 0.5)
		(connect_pads
			(clearance 0)
		)
		(min_thickness 0.25)
		(keepout
			(tracks allowed)
			(vias allowed)
			(pads allowed)
			(copperpour allowed)
			(footprints allowed)
		)
		(placement
			(enabled no)
			(sheetname "")
		)
		(fill
			(thermal_gap 0.5)
			(thermal_bridge_width 0.5)
			(island_removal_mode 0)
		)
		(polygon
			(pts
				(xy 188.243464 -354.542852) (xy 188.243464 -353.920552) (xy 188.794644 -353.920552) (xy 188.794644 -354.542852)
			)
		)
	)
	(zone
		(layer "In2.Cu")
		(hatch none 0.5)
		(connect_pads
			(clearance 0)
		)
		(min_thickness 0.25)
		(keepout
			(tracks not_allowed)
			(vias allowed)
			(pads allowed)
			(copperpour not_allowed)
			(footprints allowed)
		)
		(placement
			(enabled no)
			(sheetname "")
		)
		(fill
			(thermal_gap 0.5)
			(thermal_bridge_width 0.5)
			(island_removal_mode 0)
		)
		(polygon
			(pts
				(xy 419.162738 -306.72532) (xy 420.661338 -306.72532) (xy 420.661338 -307.245258) (xy 419.162738 -307.245258)
			)
		)
	)
	(zone
		(layer "In2.Cu")
		(hatch none 0.5)
		(connect_pads
			(clearance 0)
		)
		(min_thickness 0.25)
		(keepout
			(tracks not_allowed)
			(vias allowed)
			(pads allowed)
			(copperpour not_allowed)
			(footprints allowed)
		)
		(placement
			(enabled no)
			(sheetname "")
		)
		(fill
			(thermal_gap 0.5)
			(thermal_bridge_width 0.5)
			(island_removal_mode 0)
		)
		(polygon
			(pts
				(xy 299.07484 -305.875182) (xy 300.57344 -305.875182) (xy 300.57344 -306.39512) (xy 299.07484 -306.39512)
			)
		)
	)
	(zone
		(layer "In2.Cu")
		(hatch none 0.5)
		(connect_pads
			(clearance 0)
		)
		(min_thickness 0.25)
		(keepout
			(tracks not_allowed)
			(vias allowed)
			(pads allowed)
			(copperpour not_allowed)
			(footprints allowed)
		)
		(placement
			(enabled no)
			(sheetname "")
		)
		(fill
			(thermal_gap 0.5)
			(thermal_bridge_width 0.5)
			(island_removal_mode 0)
		)
		(polygon
			(pts
				(xy 453.438768 -273.575272) (xy 454.937368 -273.575272) (xy 454.937368 -274.09521) (xy 453.438768 -274.09521)
			)
		)
	)
	(zone
		(layer "In2.Cu")
		(hatch none 0.5)
		(connect_pads
			(clearance 0)
		)
		(min_thickness 0.25)
		(keepout
			(tracks not_allowed)
			(vias allowed)
			(pads allowed)
			(copperpour not_allowed)
			(footprints allowed)
		)
		(placement
			(enabled no)
			(sheetname "")
		)
		(fill
			(thermal_gap 0.5)
			(thermal_bridge_width 0.5)
			(island_removal_mode 0)
		)
		(polygon
			(pts
				(xy 54.578758 -220.025214) (xy 56.077358 -220.025214) (xy 56.077358 -220.545152) (xy 54.578758 -220.545152)
			)
		)
	)
	(zone
		(layer "In2.Cu")
		(hatch none 0.5)
		(connect_pads
			(clearance 0)
		)
		(min_thickness 0.25)
		(keepout
			(tracks allowed)
			(vias allowed)
			(pads allowed)
			(copperpour allowed)
			(footprints allowed)
		)
		(placement
			(enabled no)
			(sheetname "")
		)
		(fill
			(thermal_gap 0.5)
			(thermal_bridge_width 0.5)
			(island_removal_mode 0)
		)
		(polygon
			(pts
				(xy 358.478328 -166.899082) (xy 358.478328 -166.352728) (xy 359.030778 -166.352728) (xy 359.030778 -166.899082)
			)
		)
	)
	(zone
		(layer "In2.Cu")
		(hatch none 0.5)
		(connect_pads
			(clearance 0)
		)
		(min_thickness 0.25)
		(keepout
			(tracks not_allowed)
			(vias allowed)
			(pads allowed)
			(copperpour not_allowed)
			(footprints allowed)
		)
		(placement
			(enabled no)
			(sheetname "")
		)
		(fill
			(thermal_gap 0.5)
			(thermal_bridge_width 0.5)
			(island_removal_mode 0)
		)
		(polygon
			(pts
				(xy 51.134772 -229.375208) (xy 52.633372 -229.375208) (xy 52.633372 -229.895146) (xy 51.134772 -229.895146)
			)
		)
	)
	(zone
		(layer "In2.Cu")
		(hatch none 0.5)
		(connect_pads
			(clearance 0)
		)
		(min_thickness 0.25)
		(keepout
			(tracks not_allowed)
			(vias allowed)
			(pads allowed)
			(copperpour not_allowed)
			(footprints allowed)
		)
		(placement
			(enabled no)
			(sheetname "")
		)
		(fill
			(thermal_gap 0.5)
			(thermal_bridge_width 0.5)
			(island_removal_mode 0)
		)
		(polygon
			(pts
				(xy 20.95881 -245.52529) (xy 22.45741 -245.52529) (xy 22.45741 -246.045228) (xy 20.95881 -246.045228)
			)
		)
	)
	(zone
		(layer "In2.Cu")
		(hatch none 0.5)
		(connect_pads
			(clearance 0)
		)
		(min_thickness 0.25)
		(keepout
			(tracks not_allowed)
			(vias allowed)
			(pads allowed)
			(copperpour not_allowed)
			(footprints allowed)
		)
		(placement
			(enabled no)
			(sheetname "")
		)
		(fill
			(thermal_gap 0.5)
			(thermal_bridge_width 0.5)
			(island_removal_mode 0)
		)
		(polygon
			(pts
				(xy 31.946596 -242.97513) (xy 33.445196 -242.97513) (xy 33.445196 -243.495068) (xy 31.946596 -243.495068)
			)
		)
	)
	(zone
		(layer "In2.Cu")
		(hatch none 0.5)
		(connect_pads
			(clearance 0)
		)
		(min_thickness 0.25)
		(keepout
			(tracks not_allowed)
			(vias allowed)
			(pads allowed)
			(copperpour not_allowed)
			(footprints allowed)
		)
		(placement
			(enabled no)
			(sheetname "")
		)
		(fill
			(thermal_gap 0.5)
			(thermal_bridge_width 0.5)
			(island_removal_mode 0)
		)
		(polygon
			(pts
				(xy 445.894968 -245.52529) (xy 447.393568 -245.52529) (xy 447.393568 -246.045228) (xy 445.894968 -246.045228)
			)
		)
	)
	(zone
		(layer "In2.Cu")
		(hatch none 0.5)
		(connect_pads
			(clearance 0)
		)
		(min_thickness 0.25)
		(keepout
			(tracks not_allowed)
			(vias allowed)
			(pads allowed)
			(copperpour not_allowed)
			(footprints allowed)
		)
		(placement
			(enabled no)
			(sheetname "")
		)
		(fill
			(thermal_gap 0.5)
			(thermal_bridge_width 0.5)
			(island_removal_mode 0)
		)
		(polygon
			(pts
				(xy 58.678826 -298.22521) (xy 60.177426 -298.22521) (xy 60.177426 -298.745148) (xy 58.678826 -298.745148)
			)
		)
	)
	(zone
		(layer "In2.Cu")
		(hatch none 0.5)
		(connect_pads
			(clearance 0)
		)
		(min_thickness 0.25)
		(keepout
			(tracks not_allowed)
			(vias allowed)
			(pads allowed)
			(copperpour not_allowed)
			(footprints allowed)
		)
		(placement
			(enabled no)
			(sheetname "")
		)
		(fill
			(thermal_gap 0.5)
			(thermal_bridge_width 0.5)
			(island_removal_mode 0)
		)
		(polygon
			(pts
				(xy 20.95881 -217.475308) (xy 22.45741 -217.475308) (xy 22.45741 -217.995246) (xy 20.95881 -217.995246)
			)
		)
	)
	(zone
		(layer "In2.Cu")
		(hatch none 0.5)
		(connect_pads
			(clearance 0)
		)
		(min_thickness 0.25)
		(keepout
			(tracks not_allowed)
			(vias allowed)
			(pads allowed)
			(copperpour not_allowed)
			(footprints allowed)
		)
		(placement
			(enabled no)
			(sheetname "")
		)
		(fill
			(thermal_gap 0.5)
			(thermal_bridge_width 0.5)
			(island_removal_mode 0)
		)
		(polygon
			(pts
				(xy 434.250846 -316.075314) (xy 435.749446 -316.075314) (xy 435.749446 -316.595252) (xy 434.250846 -316.595252)
			)
		)
	)
	(zone
		(layer "In2.Cu")
		(hatch none 0.5)
		(connect_pads
			(clearance 0)
		)
		(min_thickness 0.25)
		(keepout
			(tracks allowed)
			(vias allowed)
			(pads allowed)
			(copperpour allowed)
			(footprints allowed)
		)
		(placement
			(enabled no)
			(sheetname "")
		)
		(fill
			(thermal_gap 0.5)
			(thermal_bridge_width 0.5)
			(island_removal_mode 0)
		)
		(polygon
			(pts
				(xy 349.858838 -156.425392) (xy 349.548958 -156.425392) (xy 349.477838 -156.496512) (xy 349.477838 -157.466792)
				(xy 349.592138 -157.581092) (xy 349.851218 -157.581092) (xy 349.922338 -157.509972) (xy 349.922338 -156.488892)
			)
		)
	)
	(zone
		(layer "In2.Cu")
		(hatch none 0.5)
		(connect_pads
			(clearance 0)
		)
		(min_thickness 0.25)
		(keepout
			(tracks not_allowed)
			(vias allowed)
			(pads allowed)
			(copperpour not_allowed)
			(footprints allowed)
		)
		(placement
			(enabled no)
			(sheetname "")
		)
		(fill
			(thermal_gap 0.5)
			(thermal_bridge_width 0.5)
			(island_removal_mode 0)
		)
		(polygon
			(pts
				(xy 441.7949 -246.375174) (xy 443.2935 -246.375174) (xy 443.2935 -246.895112) (xy 441.7949 -246.895112)
			)
		)
	)
	(zone
		(layer "In2.Cu")
		(hatch none 0.5)
		(connect_pads
			(clearance 0)
		)
		(min_thickness 0.25)
		(keepout
			(tracks not_allowed)
			(vias allowed)
			(pads allowed)
			(copperpour not_allowed)
			(footprints allowed)
		)
		(placement
			(enabled no)
			(sheetname "")
		)
		(fill
			(thermal_gap 0.5)
			(thermal_bridge_width 0.5)
			(island_removal_mode 0)
		)
		(polygon
			(pts
				(xy 419.162738 -224.275142) (xy 420.661338 -224.275142) (xy 420.661338 -224.79508) (xy 419.162738 -224.79508)
			)
		)
	)
	(zone
		(layer "In2.Cu")
		(hatch none 0.5)
		(connect_pads
			(clearance 0)
		)
		(min_thickness 0.25)
		(keepout
			(tracks not_allowed)
			(vias allowed)
			(pads allowed)
			(copperpour not_allowed)
			(footprints allowed)
		)
		(placement
			(enabled no)
			(sheetname "")
		)
		(fill
			(thermal_gap 0.5)
			(thermal_bridge_width 0.5)
			(island_removal_mode 0)
		)
		(polygon
			(pts
				(xy 419.162738 -311.825132) (xy 420.661338 -311.825132) (xy 420.661338 -312.34507) (xy 419.162738 -312.34507)
			)
		)
	)
	(zone
		(layer "In2.Cu")
		(hatch none 0.5)
		(connect_pads
			(clearance 0)
		)
		(min_thickness 0.25)
		(keepout
			(tracks not_allowed)
			(vias allowed)
			(pads allowed)
			(copperpour not_allowed)
			(footprints allowed)
		)
		(placement
			(enabled no)
			(sheetname "")
		)
		(fill
			(thermal_gap 0.5)
			(thermal_bridge_width 0.5)
			(island_removal_mode 0)
		)
		(polygon
			(pts
				(xy 16.858742 -225.975164) (xy 18.357342 -225.975164) (xy 18.357342 -226.495102) (xy 16.858742 -226.495102)
			)
		)
	)
	(zone
		(layer "In2.Cu")
		(hatch none 0.5)
		(connect_pads
			(clearance 0)
		)
		(min_thickness 0.25)
		(keepout
			(tracks not_allowed)
			(vias allowed)
			(pads allowed)
			(copperpour not_allowed)
			(footprints allowed)
		)
		(placement
			(enabled no)
			(sheetname "")
		)
		(fill
			(thermal_gap 0.5)
			(thermal_bridge_width 0.5)
			(island_removal_mode 0)
		)
		(polygon
			(pts
				(arc
					(start 351.030794 -384.288284)
					(mid 351.050718 -384.29752)
					(end 351.07245 -384.30073)
				)
				(arc
					(start 351.267014 -384.30073)
					(mid 351.320896 -384.278412)
					(end 351.343214 -384.22453)
				)
				(arc
					(start 351.343214 -383.53873)
					(mid 351.320896 -383.484848)
					(end 351.267014 -383.46253)
				)
				(arc
					(start 351.07245 -383.46253)
					(mid 351.050706 -383.465698)
					(end 351.030794 -383.474976)
				)
				(arc
					(start 350.73463 -383.667762)
					(mid 350.692946 -383.679984)
					(end 350.651318 -383.667508)
				)
				(arc
					(start 350.357694 -383.474976)
					(mid 350.33777 -383.46574)
					(end 350.316038 -383.46253)
				)
				(arc
					(start 350.121474 -383.46253)
					(mid 350.067592 -383.484848)
					(end 350.045274 -383.53873)
				)
				(arc
					(start 350.045274 -384.22453)
					(mid 350.067592 -384.278412)
					(end 350.121474 -384.30073)
				)
				(arc
					(start 350.317308 -384.30073)
					(mid 350.339052 -384.297562)
					(end 350.358964 -384.288284)
				)
				(arc
					(start 350.652588 -384.095752)
					(mid 350.694244 -384.08335)
					(end 350.7359 -384.095752)
				)
			)
		)
	)
	(zone
		(layer "In2.Cu")
		(hatch none 0.5)
		(connect_pads
			(clearance 0)
		)
		(min_thickness 0.25)
		(keepout
			(tracks allowed)
			(vias allowed)
			(pads allowed)
			(copperpour allowed)
			(footprints allowed)
		)
		(placement
			(enabled no)
			(sheetname "")
		)
		(fill
			(thermal_gap 0.5)
			(thermal_bridge_width 0.5)
			(island_removal_mode 0)
		)
		(polygon
			(pts
				(xy 377.08713 -180.967634) (xy 377.08713 -180.42128) (xy 377.63958 -180.42128) (xy 377.63958 -180.967634)
			)
		)
	)
	(zone
		(layer "In2.Cu")
		(hatch none 0.5)
		(connect_pads
			(clearance 0)
		)
		(min_thickness 0.25)
		(keepout
			(tracks not_allowed)
			(vias allowed)
			(pads allowed)
			(copperpour not_allowed)
			(footprints allowed)
		)
		(placement
			(enabled no)
			(sheetname "")
		)
		(fill
			(thermal_gap 0.5)
			(thermal_bridge_width 0.5)
			(island_removal_mode 0)
		)
		(polygon
			(pts
				(xy 47.034704 -220.875098) (xy 48.533304 -220.875098) (xy 48.533304 -221.395036) (xy 47.034704 -221.395036)
			)
		)
	)
	(zone
		(layer "In2.Cu")
		(hatch none 0.5)
		(connect_pads
			(clearance 0)
		)
		(min_thickness 0.25)
		(keepout
			(tracks not_allowed)
			(vias allowed)
			(pads allowed)
			(copperpour not_allowed)
			(footprints allowed)
		)
		(placement
			(enabled no)
			(sheetname "")
		)
		(fill
			(thermal_gap 0.5)
			(thermal_bridge_width 0.5)
			(island_removal_mode 0)
		)
		(polygon
			(pts
				(xy 54.578758 -241.275108) (xy 56.077358 -241.275108) (xy 56.077358 -241.795046) (xy 54.578758 -241.795046)
			)
		)
	)
	(zone
		(layer "In2.Cu")
		(hatch none 0.5)
		(connect_pads
			(clearance 0)
		)
		(min_thickness 0.25)
		(keepout
			(tracks not_allowed)
			(vias allowed)
			(pads allowed)
			(copperpour not_allowed)
			(footprints allowed)
		)
		(placement
			(enabled no)
			(sheetname "")
		)
		(fill
			(thermal_gap 0.5)
			(thermal_bridge_width 0.5)
			(island_removal_mode 0)
		)
		(polygon
			(pts
				(xy 186.310778 -286.32531) (xy 187.809378 -286.32531) (xy 187.809378 -286.845248) (xy 186.310778 -286.845248)
			)
		)
	)
	(zone
		(layer "In2.Cu")
		(hatch none 0.5)
		(connect_pads
			(clearance 0)
		)
		(min_thickness 0.25)
		(keepout
			(tracks not_allowed)
			(vias allowed)
			(pads allowed)
			(copperpour not_allowed)
			(footprints allowed)
		)
		(placement
			(enabled no)
			(sheetname "")
		)
		(fill
			(thermal_gap 0.5)
			(thermal_bridge_width 0.5)
			(island_removal_mode 0)
		)
		(polygon
			(pts
				(xy 58.678826 -247.225312) (xy 60.177426 -247.225312) (xy 60.177426 -247.74525) (xy 58.678826 -247.74525)
			)
		)
	)
	(zone
		(layer "In2.Cu")
		(hatch none 0.5)
		(connect_pads
			(clearance 0)
		)
		(min_thickness 0.25)
		(keepout
			(tracks not_allowed)
			(vias allowed)
			(pads allowed)
			(copperpour not_allowed)
			(footprints allowed)
		)
		(placement
			(enabled no)
			(sheetname "")
		)
		(fill
			(thermal_gap 0.5)
			(thermal_bridge_width 0.5)
			(island_removal_mode 0)
		)
		(polygon
			(pts
				(xy 28.50261 -309.275226) (xy 30.00121 -309.275226) (xy 30.00121 -309.795164) (xy 28.50261 -309.795164)
			)
		)
	)
	(zone
		(layer "In2.Cu")
		(hatch none 0.5)
		(connect_pads
			(clearance 0)
		)
		(min_thickness 0.25)
		(keepout
			(tracks not_allowed)
			(vias allowed)
			(pads allowed)
			(copperpour not_allowed)
			(footprints allowed)
		)
		(placement
			(enabled no)
			(sheetname "")
		)
		(fill
			(thermal_gap 0.5)
			(thermal_bridge_width 0.5)
			(island_removal_mode 0)
		)
		(polygon
			(pts
				(xy 190.410846 -301.625254) (xy 191.909446 -301.625254) (xy 191.909446 -302.145192) (xy 190.410846 -302.145192)
			)
		)
	)
	(zone
		(layer "In2.Cu")
		(hatch none 0.5)
		(connect_pads
			(clearance 0)
		)
		(min_thickness 0.25)
		(keepout
			(tracks not_allowed)
			(vias allowed)
			(pads allowed)
			(copperpour not_allowed)
			(footprints allowed)
		)
		(placement
			(enabled no)
			(sheetname "")
		)
		(fill
			(thermal_gap 0.5)
			(thermal_bridge_width 0.5)
			(island_removal_mode 0)
		)
		(polygon
			(pts
				(xy 16.858742 -295.675304) (xy 18.357342 -295.675304) (xy 18.357342 -296.195242) (xy 16.858742 -296.195242)
			)
		)
	)
	(zone
		(layer "In2.Cu")
		(hatch none 0.5)
		(connect_pads
			(clearance 0)
		)
		(min_thickness 0.25)
		(keepout
			(tracks not_allowed)
			(vias allowed)
			(pads allowed)
			(copperpour not_allowed)
			(footprints allowed)
		)
		(placement
			(enabled no)
			(sheetname "")
		)
		(fill
			(thermal_gap 0.5)
			(thermal_bridge_width 0.5)
			(island_removal_mode 0)
		)
		(polygon
			(pts
				(xy 167.778684 -281.225244) (xy 169.277284 -281.225244) (xy 169.277284 -281.745182) (xy 167.778684 -281.745182)
			)
		)
	)
	(zone
		(layer "In2.Cu")
		(hatch none 0.5)
		(connect_pads
			(clearance 0)
		)
		(min_thickness 0.25)
		(keepout
			(tracks not_allowed)
			(vias allowed)
			(pads allowed)
			(copperpour not_allowed)
			(footprints allowed)
		)
		(placement
			(enabled no)
			(sheetname "")
		)
		(fill
			(thermal_gap 0.5)
			(thermal_bridge_width 0.5)
			(island_removal_mode 0)
		)
		(polygon
			(pts
				(xy 51.134772 -217.475308) (xy 52.633372 -217.475308) (xy 52.633372 -217.995246) (xy 51.134772 -217.995246)
			)
		)
	)
	(zone
		(layer "In2.Cu")
		(hatch none 0.5)
		(connect_pads
			(clearance 0)
		)
		(min_thickness 0.25)
		(keepout
			(tracks not_allowed)
			(vias allowed)
			(pads allowed)
			(copperpour not_allowed)
			(footprints allowed)
		)
		(placement
			(enabled no)
			(sheetname "")
		)
		(fill
			(thermal_gap 0.5)
			(thermal_bridge_width 0.5)
			(island_removal_mode 0)
		)
		(polygon
			(pts
				(xy 287.430718 -251.47524) (xy 288.929318 -251.47524) (xy 288.929318 -251.995178) (xy 287.430718 -251.995178)
			)
		)
	)
	(zone
		(layer "In2.Cu")
		(hatch none 0.5)
		(connect_pads
			(clearance 0)
		)
		(min_thickness 0.25)
		(keepout
			(tracks not_allowed)
			(vias allowed)
			(pads allowed)
			(copperpour not_allowed)
			(footprints allowed)
		)
		(placement
			(enabled no)
			(sheetname "")
		)
		(fill
			(thermal_gap 0.5)
			(thermal_bridge_width 0.5)
			(island_removal_mode 0)
		)
		(polygon
			(pts
				(xy 175.322738 -242.125246) (xy 176.821338 -242.125246) (xy 176.821338 -242.645184) (xy 175.322738 -242.645184)
			)
		)
	)
	(zone
		(layer "In2.Cu")
		(hatch none 0.5)
		(connect_pads
			(clearance 0)
		)
		(min_thickness 0.25)
		(keepout
			(tracks not_allowed)
			(vias allowed)
			(pads allowed)
			(copperpour not_allowed)
			(footprints allowed)
		)
		(placement
			(enabled no)
			(sheetname "")
		)
		(fill
			(thermal_gap 0.5)
			(thermal_bridge_width 0.5)
			(island_removal_mode 0)
		)
		(polygon
			(pts
				(xy 28.50261 -293.975282) (xy 30.00121 -293.975282) (xy 30.00121 -294.49522) (xy 28.50261 -294.49522)
			)
		)
	)
	(zone
		(layer "In2.Cu")
		(hatch none 0.5)
		(connect_pads
			(clearance 0)
		)
		(min_thickness 0.25)
		(keepout
			(tracks not_allowed)
			(vias allowed)
			(pads allowed)
			(copperpour not_allowed)
			(footprints allowed)
		)
		(placement
			(enabled no)
			(sheetname "")
		)
		(fill
			(thermal_gap 0.5)
			(thermal_bridge_width 0.5)
			(island_removal_mode 0)
		)
		(polygon
			(pts
				(xy 294.974772 -225.975164) (xy 296.473372 -225.975164) (xy 296.473372 -226.495102) (xy 294.974772 -226.495102)
			)
		)
	)
	(zone
		(layer "In2.Cu")
		(hatch none 0.5)
		(connect_pads
			(clearance 0)
		)
		(min_thickness 0.25)
		(keepout
			(tracks not_allowed)
			(vias allowed)
			(pads allowed)
			(copperpour not_allowed)
			(footprints allowed)
		)
		(placement
			(enabled no)
			(sheetname "")
		)
		(fill
			(thermal_gap 0.5)
			(thermal_bridge_width 0.5)
			(island_removal_mode 0)
		)
		(polygon
			(pts
				(xy 441.7949 -313.525154) (xy 443.2935 -313.525154) (xy 443.2935 -314.045092) (xy 441.7949 -314.045092)
			)
		)
	)
	(zone
		(layer "In2.Cu")
		(hatch none 0.5)
		(connect_pads
			(clearance 0)
		)
		(min_thickness 0.25)
		(keepout
			(tracks not_allowed)
			(vias allowed)
			(pads allowed)
			(copperpour not_allowed)
			(footprints allowed)
		)
		(placement
			(enabled no)
			(sheetname "")
		)
		(fill
			(thermal_gap 0.5)
			(thermal_bridge_width 0.5)
			(island_removal_mode 0)
		)
		(polygon
			(pts
				(xy 434.250846 -220.875098) (xy 435.749446 -220.875098) (xy 435.749446 -221.395036) (xy 434.250846 -221.395036)
			)
		)
	)
	(zone
		(layer "In2.Cu")
		(hatch none 0.5)
		(connect_pads
			(clearance 0)
		)
		(min_thickness 0.25)
		(keepout
			(tracks not_allowed)
			(vias allowed)
			(pads allowed)
			(copperpour not_allowed)
			(footprints allowed)
		)
		(placement
			(enabled no)
			(sheetname "")
		)
		(fill
			(thermal_gap 0.5)
			(thermal_bridge_width 0.5)
			(island_removal_mode 0)
		)
		(polygon
			(pts
				(xy 423.262806 -208.125314) (xy 424.761406 -208.125314) (xy 424.761406 -208.645252) (xy 423.262806 -208.645252)
			)
		)
	)
	(zone
		(layer "In2.Cu")
		(hatch none 0.5)
		(connect_pads
			(clearance 0)
		)
		(min_thickness 0.25)
		(keepout
			(tracks not_allowed)
			(vias allowed)
			(pads allowed)
			(copperpour not_allowed)
			(footprints allowed)
		)
		(placement
			(enabled no)
			(sheetname "")
		)
		(fill
			(thermal_gap 0.5)
			(thermal_bridge_width 0.5)
			(island_removal_mode 0)
		)
		(polygon
			(pts
				(xy 54.578758 -205.575154) (xy 56.077358 -205.575154) (xy 56.077358 -206.095092) (xy 54.578758 -206.095092)
			)
		)
	)
	(zone
		(layer "In2.Cu")
		(hatch none 0.5)
		(connect_pads
			(clearance 0)
		)
		(min_thickness 0.25)
		(keepout
			(tracks not_allowed)
			(vias allowed)
			(pads allowed)
			(copperpour not_allowed)
			(footprints allowed)
		)
		(placement
			(enabled no)
			(sheetname "")
		)
		(fill
			(thermal_gap 0.5)
			(thermal_bridge_width 0.5)
			(island_removal_mode 0)
		)
		(polygon
			(pts
				(xy 449.3387 -227.675186) (xy 450.8373 -227.675186) (xy 450.8373 -228.195124) (xy 449.3387 -228.195124)
			)
		)
	)
	(zone
		(layer "In2.Cu")
		(hatch none 0.5)
		(connect_pads
			(clearance 0)
		)
		(min_thickness 0.25)
		(keepout
			(tracks not_allowed)
			(vias allowed)
			(pads allowed)
			(copperpour not_allowed)
			(footprints allowed)
		)
		(placement
			(enabled no)
			(sheetname "")
		)
		(fill
			(thermal_gap 0.5)
			(thermal_bridge_width 0.5)
			(island_removal_mode 0)
		)
		(polygon
			(pts
				(xy 291.530786 -215.775286) (xy 293.029386 -215.775286) (xy 293.029386 -216.295224) (xy 291.530786 -216.295224)
			)
		)
	)
	(zone
		(layer "In2.Cu")
		(hatch none 0.5)
		(connect_pads
			(clearance 0)
		)
		(min_thickness 0.25)
		(keepout
			(tracks not_allowed)
			(vias allowed)
			(pads allowed)
			(copperpour not_allowed)
			(footprints allowed)
		)
		(placement
			(enabled no)
			(sheetname "")
		)
		(fill
			(thermal_gap 0.5)
			(thermal_bridge_width 0.5)
			(island_removal_mode 0)
		)
		(polygon
			(pts
				(xy 175.322738 -238.725202) (xy 176.821338 -238.725202) (xy 176.821338 -239.24514) (xy 175.322738 -239.24514)
			)
		)
	)
	(zone
		(layer "In2.Cu")
		(hatch none 0.5)
		(connect_pads
			(clearance 0)
		)
		(min_thickness 0.25)
		(keepout
			(tracks allowed)
			(vias allowed)
			(pads allowed)
			(copperpour allowed)
			(footprints allowed)
		)
		(placement
			(enabled no)
			(sheetname "")
		)
		(fill
			(thermal_gap 0.5)
			(thermal_bridge_width 0.5)
			(island_removal_mode 0)
		)
		(polygon
			(pts
				(xy 294.55237 -349.854266) (xy 294.55237 -349.231966) (xy 295.10355 -349.231966) (xy 295.10355 -349.854266)
			)
		)
	)
	(zone
		(layer "In2.Cu")
		(hatch none 0.5)
		(connect_pads
			(clearance 0)
		)
		(min_thickness 0.25)
		(keepout
			(tracks not_allowed)
			(vias allowed)
			(pads allowed)
			(copperpour not_allowed)
			(footprints allowed)
		)
		(placement
			(enabled no)
			(sheetname "")
		)
		(fill
			(thermal_gap 0.5)
			(thermal_bridge_width 0.5)
			(island_removal_mode 0)
		)
		(polygon
			(pts
				(xy 16.858742 -248.075196) (xy 18.357342 -248.075196) (xy 18.357342 -248.595134) (xy 16.858742 -248.595134)
			)
		)
	)
	(zone
		(layer "In2.Cu")
		(hatch none 0.5)
		(connect_pads
			(clearance 0)
		)
		(min_thickness 0.25)
		(keepout
			(tracks not_allowed)
			(vias allowed)
			(pads allowed)
			(copperpour not_allowed)
			(footprints allowed)
		)
		(placement
			(enabled no)
			(sheetname "")
		)
		(fill
			(thermal_gap 0.5)
			(thermal_bridge_width 0.5)
			(island_removal_mode 0)
		)
		(polygon
			(pts
				(xy 272.342864 -304.17516) (xy 273.841464 -304.17516) (xy 273.841464 -304.695098) (xy 272.342864 -304.695098)
			)
		)
	)
	(zone
		(layer "In2.Cu")
		(hatch none 0.5)
		(connect_pads
			(clearance 0)
		)
		(min_thickness 0.25)
		(keepout
			(tracks not_allowed)
			(vias allowed)
			(pads allowed)
			(copperpour not_allowed)
			(footprints allowed)
		)
		(placement
			(enabled no)
			(sheetname "")
		)
		(fill
			(thermal_gap 0.5)
			(thermal_bridge_width 0.5)
			(island_removal_mode 0)
		)
		(polygon
			(pts
				(xy 36.046664 -267.625322) (xy 37.545264 -267.625322) (xy 37.545264 -268.14526) (xy 36.046664 -268.14526)
			)
		)
	)
	(zone
		(layer "In2.Cu")
		(hatch none 0.5)
		(connect_pads
			(clearance 0)
		)
		(min_thickness 0.25)
		(keepout
			(tracks not_allowed)
			(vias allowed)
			(pads allowed)
			(copperpour not_allowed)
			(footprints allowed)
		)
		(placement
			(enabled no)
			(sheetname "")
		)
		(fill
			(thermal_gap 0.5)
			(thermal_bridge_width 0.5)
			(island_removal_mode 0)
		)
		(polygon
			(pts
				(xy 193.854578 -251.47524) (xy 195.353178 -251.47524) (xy 195.353178 -251.995178) (xy 193.854578 -251.995178)
			)
		)
	)
	(zone
		(layer "In2.Cu")
		(hatch none 0.5)
		(connect_pads
			(clearance 0)
		)
		(min_thickness 0.25)
		(keepout
			(tracks not_allowed)
			(vias allowed)
			(pads allowed)
			(copperpour not_allowed)
			(footprints allowed)
		)
		(placement
			(enabled no)
			(sheetname "")
		)
		(fill
			(thermal_gap 0.5)
			(thermal_bridge_width 0.5)
			(island_removal_mode 0)
		)
		(polygon
			(pts
				(xy 197.954646 -270.175228) (xy 199.453246 -270.175228) (xy 199.453246 -270.695166) (xy 197.954646 -270.695166)
			)
		)
	)
	(zone
		(layer "In2.Cu")
		(hatch none 0.5)
		(connect_pads
			(clearance 0)
		)
		(min_thickness 0.25)
		(keepout
			(tracks not_allowed)
			(vias allowed)
			(pads allowed)
			(copperpour not_allowed)
			(footprints allowed)
		)
		(placement
			(enabled no)
			(sheetname "")
		)
		(fill
			(thermal_gap 0.5)
			(thermal_bridge_width 0.5)
			(island_removal_mode 0)
		)
		(polygon
			(pts
				(xy 279.886664 -205.575154) (xy 281.385264 -205.575154) (xy 281.385264 -206.095092) (xy 279.886664 -206.095092)
			)
		)
	)
	(zone
		(layer "In2.Cu")
		(hatch none 0.5)
		(connect_pads
			(clearance 0)
		)
		(min_thickness 0.25)
		(keepout
			(tracks not_allowed)
			(vias allowed)
			(pads allowed)
			(copperpour not_allowed)
			(footprints allowed)
		)
		(placement
			(enabled no)
			(sheetname "")
		)
		(fill
			(thermal_gap 0.5)
			(thermal_bridge_width 0.5)
			(island_removal_mode 0)
		)
		(polygon
			(pts
				(xy 31.946596 -229.375208) (xy 33.445196 -229.375208) (xy 33.445196 -229.895146) (xy 31.946596 -229.895146)
			)
		)
	)
	(zone
		(layer "In2.Cu")
		(hatch none 0.5)
		(connect_pads
			(clearance 0)
		)
		(min_thickness 0.25)
		(keepout
			(tracks not_allowed)
			(vias allowed)
			(pads allowed)
			(copperpour not_allowed)
			(footprints allowed)
		)
		(placement
			(enabled no)
			(sheetname "")
		)
		(fill
			(thermal_gap 0.5)
			(thermal_bridge_width 0.5)
			(island_removal_mode 0)
		)
		(polygon
			(pts
				(xy 449.3387 -197.925182) (xy 450.8373 -197.925182) (xy 450.8373 -198.44512) (xy 449.3387 -198.44512)
			)
		)
	)
	(zone
		(layer "In2.Cu")
		(hatch none 0.5)
		(connect_pads
			(clearance 0)
		)
		(min_thickness 0.25)
		(keepout
			(tracks not_allowed)
			(vias allowed)
			(pads allowed)
			(copperpour not_allowed)
			(footprints allowed)
		)
		(placement
			(enabled no)
			(sheetname "")
		)
		(fill
			(thermal_gap 0.5)
			(thermal_bridge_width 0.5)
			(island_removal_mode 0)
		)
		(polygon
			(pts
				(xy 445.894968 -212.375242) (xy 447.393568 -212.375242) (xy 447.393568 -212.89518) (xy 445.894968 -212.89518)
			)
		)
	)
	(zone
		(layer "In2.Cu")
		(hatch none 0.5)
		(connect_pads
			(clearance 0)
		)
		(min_thickness 0.25)
		(keepout
			(tracks not_allowed)
			(vias allowed)
			(pads allowed)
			(copperpour not_allowed)
			(footprints allowed)
		)
		(placement
			(enabled no)
			(sheetname "")
		)
		(fill
			(thermal_gap 0.5)
			(thermal_bridge_width 0.5)
			(island_removal_mode 0)
		)
		(polygon
			(pts
				(xy 193.854578 -203.875132) (xy 195.353178 -203.875132) (xy 195.353178 -204.39507) (xy 193.854578 -204.39507)
			)
		)
	)
	(zone
		(layer "In2.Cu")
		(hatch none 0.5)
		(connect_pads
			(clearance 0)
		)
		(min_thickness 0.25)
		(keepout
			(tracks not_allowed)
			(vias allowed)
			(pads allowed)
			(copperpour not_allowed)
			(footprints allowed)
		)
		(placement
			(enabled no)
			(sheetname "")
		)
		(fill
			(thermal_gap 0.5)
			(thermal_bridge_width 0.5)
			(island_removal_mode 0)
		)
		(polygon
			(pts
				(xy 276.442932 -292.27526) (xy 277.941532 -292.27526) (xy 277.941532 -292.795198) (xy 276.442932 -292.795198)
			)
		)
	)
	(zone
		(layer "In2.Cu")
		(hatch none 0.5)
		(connect_pads
			(clearance 0)
		)
		(min_thickness 0.25)
		(keepout
			(tracks not_allowed)
			(vias allowed)
			(pads allowed)
			(copperpour not_allowed)
			(footprints allowed)
		)
		(placement
			(enabled no)
			(sheetname "")
		)
		(fill
			(thermal_gap 0.5)
			(thermal_bridge_width 0.5)
			(island_removal_mode 0)
		)
		(polygon
			(pts
				(xy 419.162738 -316.075314) (xy 420.661338 -316.075314) (xy 420.661338 -316.595252) (xy 419.162738 -316.595252)
			)
		)
	)
	(zone
		(layer "In2.Cu")
		(hatch none 0.5)
		(connect_pads
			(clearance 0)
		)
		(min_thickness 0.25)
		(keepout
			(tracks not_allowed)
			(vias allowed)
			(pads allowed)
			(copperpour not_allowed)
			(footprints allowed)
		)
		(placement
			(enabled no)
			(sheetname "")
		)
		(fill
			(thermal_gap 0.5)
			(thermal_bridge_width 0.5)
			(island_removal_mode 0)
		)
		(polygon
			(pts
				(xy 415.718752 -243.825268) (xy 417.217352 -243.825268) (xy 417.217352 -244.345206) (xy 415.718752 -244.345206)
			)
		)
	)
	(zone
		(layer "In2.Cu")
		(hatch none 0.5)
		(connect_pads
			(clearance 0)
		)
		(min_thickness 0.25)
		(keepout
			(tracks not_allowed)
			(vias allowed)
			(pads allowed)
			(copperpour not_allowed)
			(footprints allowed)
		)
		(placement
			(enabled no)
			(sheetname "")
		)
		(fill
			(thermal_gap 0.5)
			(thermal_bridge_width 0.5)
			(island_removal_mode 0)
		)
		(polygon
			(pts
				(xy 415.718752 -270.175228) (xy 417.217352 -270.175228) (xy 417.217352 -270.695166) (xy 415.718752 -270.695166)
			)
		)
	)
	(zone
		(layer "In2.Cu")
		(hatch none 0.5)
		(connect_pads
			(clearance 0)
		)
		(min_thickness 0.25)
		(keepout
			(tracks not_allowed)
			(vias allowed)
			(pads allowed)
			(copperpour not_allowed)
			(footprints allowed)
		)
		(placement
			(enabled no)
			(sheetname "")
		)
		(fill
			(thermal_gap 0.5)
			(thermal_bridge_width 0.5)
			(island_removal_mode 0)
		)
		(polygon
			(pts
				(xy 299.07484 -220.025214) (xy 300.57344 -220.025214) (xy 300.57344 -220.545152) (xy 299.07484 -220.545152)
			)
		)
	)
	(zone
		(layer "In2.Cu")
		(hatch none 0.5)
		(connect_pads
			(clearance 0)
		)
		(min_thickness 0.25)
		(keepout
			(tracks not_allowed)
			(vias allowed)
			(pads allowed)
			(copperpour not_allowed)
			(footprints allowed)
		)
		(placement
			(enabled no)
			(sheetname "")
		)
		(fill
			(thermal_gap 0.5)
			(thermal_bridge_width 0.5)
			(island_removal_mode 0)
		)
		(polygon
			(pts
				(xy 276.442932 -288.875216) (xy 277.941532 -288.875216) (xy 277.941532 -289.395154) (xy 276.442932 -289.395154)
			)
		)
	)
	(zone
		(layer "In2.Cu")
		(hatch none 0.5)
		(connect_pads
			(clearance 0)
		)
		(min_thickness 0.25)
		(keepout
			(tracks not_allowed)
			(vias allowed)
			(pads allowed)
			(copperpour not_allowed)
			(footprints allowed)
		)
		(placement
			(enabled no)
			(sheetname "")
		)
		(fill
			(thermal_gap 0.5)
			(thermal_bridge_width 0.5)
			(island_removal_mode 0)
		)
		(polygon
			(pts
				(xy 28.50261 -315.225176) (xy 30.00121 -315.225176) (xy 30.00121 -315.745114) (xy 28.50261 -315.745114)
			)
		)
	)
	(zone
		(layer "In2.Cu")
		(hatch none 0.5)
		(connect_pads
			(clearance 0)
		)
		(min_thickness 0.25)
		(keepout
			(tracks allowed)
			(vias allowed)
			(pads allowed)
			(copperpour allowed)
			(footprints allowed)
		)
		(placement
			(enabled no)
			(sheetname "")
		)
		(fill
			(thermal_gap 0.5)
			(thermal_bridge_width 0.5)
			(island_removal_mode 0)
		)
		(polygon
			(pts
				(xy 49.96053 -347.557852) (xy 49.96053 -348.467172) (xy 49.72431 -348.467172) (xy 49.72431 -347.557852)
			)
		)
	)
	(zone
		(layer "In2.Cu")
		(hatch none 0.5)
		(connect_pads
			(clearance 0)
		)
		(min_thickness 0.25)
		(keepout
			(tracks not_allowed)
			(vias allowed)
			(pads allowed)
			(copperpour not_allowed)
			(footprints allowed)
		)
		(placement
			(enabled no)
			(sheetname "")
		)
		(fill
			(thermal_gap 0.5)
			(thermal_bridge_width 0.5)
			(island_removal_mode 0)
		)
		(polygon
			(pts
				(xy 36.046664 -279.525222) (xy 37.545264 -279.525222) (xy 37.545264 -280.04516) (xy 36.046664 -280.04516)
			)
		)
	)
	(zone
		(layer "In2.Cu")
		(hatch none 0.5)
		(connect_pads
			(clearance 0)
		)
		(min_thickness 0.25)
		(keepout
			(tracks not_allowed)
			(vias allowed)
			(pads allowed)
			(copperpour not_allowed)
			(footprints allowed)
		)
		(placement
			(enabled no)
			(sheetname "")
		)
		(fill
			(thermal_gap 0.5)
			(thermal_bridge_width 0.5)
			(island_removal_mode 0)
		)
		(polygon
			(pts
				(xy 445.894968 -262.525256) (xy 447.393568 -262.525256) (xy 447.393568 -263.045194) (xy 445.894968 -263.045194)
			)
		)
	)
	(zone
		(layer "In2.Cu")
		(hatch none 0.5)
		(connect_pads
			(clearance 0)
		)
		(min_thickness 0.25)
		(keepout
			(tracks not_allowed)
			(vias allowed)
			(pads allowed)
			(copperpour not_allowed)
			(footprints allowed)
		)
		(placement
			(enabled no)
			(sheetname "")
		)
		(fill
			(thermal_gap 0.5)
			(thermal_bridge_width 0.5)
			(island_removal_mode 0)
		)
		(polygon
			(pts
				(xy 16.858742 -199.625204) (xy 18.357342 -199.625204) (xy 18.357342 -200.145142) (xy 16.858742 -200.145142)
			)
		)
	)
	(zone
		(layer "In2.Cu")
		(hatch none 0.5)
		(connect_pads
			(clearance 0)
		)
		(min_thickness 0.25)
		(keepout
			(tracks not_allowed)
			(vias allowed)
			(pads allowed)
			(copperpour not_allowed)
			(footprints allowed)
		)
		(placement
			(enabled no)
			(sheetname "")
		)
		(fill
			(thermal_gap 0.5)
			(thermal_bridge_width 0.5)
			(island_removal_mode 0)
		)
		(polygon
			(pts
				(xy 31.946596 -237.02518) (xy 33.445196 -237.02518) (xy 33.445196 -237.545118) (xy 31.946596 -237.545118)
			)
		)
	)
	(zone
		(layer "In2.Cu")
		(hatch none 0.5)
		(connect_pads
			(clearance 0)
		)
		(min_thickness 0.25)
		(keepout
			(tracks not_allowed)
			(vias allowed)
			(pads allowed)
			(copperpour not_allowed)
			(footprints allowed)
		)
		(placement
			(enabled no)
			(sheetname "")
		)
		(fill
			(thermal_gap 0.5)
			(thermal_bridge_width 0.5)
			(island_removal_mode 0)
		)
		(polygon
			(pts
				(xy 201.398632 -289.725354) (xy 202.897232 -289.725354) (xy 202.897232 -290.245292) (xy 201.398632 -290.245292)
			)
		)
	)
	(zone
		(layer "In2.Cu")
		(hatch none 0.5)
		(connect_pads
			(clearance 0)
		)
		(min_thickness 0.25)
		(keepout
			(tracks not_allowed)
			(vias allowed)
			(pads allowed)
			(copperpour not_allowed)
			(footprints allowed)
		)
		(placement
			(enabled no)
			(sheetname "")
		)
		(fill
			(thermal_gap 0.5)
			(thermal_bridge_width 0.5)
			(island_removal_mode 0)
		)
		(polygon
			(pts
				(xy 453.438768 -271.87525) (xy 454.937368 -271.87525) (xy 454.937368 -272.395188) (xy 453.438768 -272.395188)
			)
		)
	)
	(zone
		(layer "In2.Cu")
		(hatch none 0.5)
		(connect_pads
			(clearance 0)
		)
		(min_thickness 0.25)
		(keepout
			(tracks allowed)
			(vias allowed)
			(pads allowed)
			(copperpour allowed)
			(footprints allowed)
		)
		(placement
			(enabled no)
			(sheetname "")
		)
		(fill
			(thermal_gap 0.5)
			(thermal_bridge_width 0.5)
			(island_removal_mode 0)
		)
		(polygon
			(pts
				(xy 134.86892 -153.93416) (xy 134.86892 -153.387806) (xy 135.42137 -153.387806) (xy 135.42137 -153.93416)
			)
		)
	)
	(zone
		(layer "In2.Cu")
		(hatch none 0.5)
		(connect_pads
			(clearance 0)
		)
		(min_thickness 0.25)
		(keepout
			(tracks not_allowed)
			(vias allowed)
			(pads allowed)
			(copperpour not_allowed)
			(footprints allowed)
		)
		(placement
			(enabled no)
			(sheetname "")
		)
		(fill
			(thermal_gap 0.5)
			(thermal_bridge_width 0.5)
			(island_removal_mode 0)
		)
		(polygon
			(pts
				(xy 441.7949 -280.375106) (xy 443.2935 -280.375106) (xy 443.2935 -280.895044) (xy 441.7949 -280.895044)
			)
		)
	)
	(zone
		(layer "In2.Cu")
		(hatch none 0.5)
		(connect_pads
			(clearance 0)
		)
		(min_thickness 0.25)
		(keepout
			(tracks not_allowed)
			(vias allowed)
			(pads allowed)
			(copperpour not_allowed)
			(footprints allowed)
		)
		(placement
			(enabled no)
			(sheetname "")
		)
		(fill
			(thermal_gap 0.5)
			(thermal_bridge_width 0.5)
			(island_removal_mode 0)
		)
		(polygon
			(pts
				(xy 438.350914 -271.87525) (xy 439.849514 -271.87525) (xy 439.849514 -272.395188) (xy 438.350914 -272.395188)
			)
		)
	)
	(zone
		(layer "In2.Cu")
		(hatch none 0.5)
		(connect_pads
			(clearance 0)
		)
		(min_thickness 0.25)
		(keepout
			(tracks not_allowed)
			(vias allowed)
			(pads allowed)
			(copperpour not_allowed)
			(footprints allowed)
		)
		(placement
			(enabled no)
			(sheetname "")
		)
		(fill
			(thermal_gap 0.5)
			(thermal_bridge_width 0.5)
			(island_removal_mode 0)
		)
		(polygon
			(pts
				(xy 54.578758 -254.025146) (xy 56.077358 -254.025146) (xy 56.077358 -254.545084) (xy 54.578758 -254.545084)
			)
		)
	)
	(zone
		(layer "In2.Cu")
		(hatch none 0.5)
		(connect_pads
			(clearance 0)
		)
		(min_thickness 0.25)
		(keepout
			(tracks not_allowed)
			(vias allowed)
			(pads allowed)
			(copperpour not_allowed)
			(footprints allowed)
		)
		(placement
			(enabled no)
			(sheetname "")
		)
		(fill
			(thermal_gap 0.5)
			(thermal_bridge_width 0.5)
			(island_removal_mode 0)
		)
		(polygon
			(pts
				(xy 276.442932 -206.425292) (xy 277.941532 -206.425292) (xy 277.941532 -206.94523) (xy 276.442932 -206.94523)
			)
		)
	)
	(zone
		(layer "In2.Cu")
		(hatch none 0.5)
		(connect_pads
			(clearance 0)
		)
		(min_thickness 0.25)
		(keepout
			(tracks not_allowed)
			(vias allowed)
			(pads allowed)
			(copperpour not_allowed)
			(footprints allowed)
		)
		(placement
			(enabled no)
			(sheetname "")
		)
		(fill
			(thermal_gap 0.5)
			(thermal_bridge_width 0.5)
			(island_removal_mode 0)
		)
		(polygon
			(pts
				(xy 51.134772 -237.875318) (xy 52.633372 -237.875318) (xy 52.633372 -238.395256) (xy 51.134772 -238.395256)
			)
		)
	)
	(zone
		(layer "In2.Cu")
		(hatch none 0.5)
		(connect_pads
			(clearance 0)
		)
		(min_thickness 0.25)
		(keepout
			(tracks not_allowed)
			(vias allowed)
			(pads allowed)
			(copperpour not_allowed)
			(footprints allowed)
		)
		(placement
			(enabled no)
			(sheetname "")
		)
		(fill
			(thermal_gap 0.5)
			(thermal_bridge_width 0.5)
			(island_removal_mode 0)
		)
		(polygon
			(pts
				(xy 20.95881 -313.525154) (xy 22.45741 -313.525154) (xy 22.45741 -314.045092) (xy 20.95881 -314.045092)
			)
		)
	)
	(zone
		(layer "In2.Cu")
		(hatch none 0.5)
		(connect_pads
			(clearance 0)
		)
		(min_thickness 0.25)
		(keepout
			(tracks not_allowed)
			(vias allowed)
			(pads allowed)
			(copperpour not_allowed)
			(footprints allowed)
		)
		(placement
			(enabled no)
			(sheetname "")
		)
		(fill
			(thermal_gap 0.5)
			(thermal_bridge_width 0.5)
			(island_removal_mode 0)
		)
		(polygon
			(pts
				(arc
					(start 331.088238 -390.65581)
					(mid 331.079002 -390.675734)
					(end 331.075792 -390.697466)
				)
				(arc
					(start 331.075792 -390.89203)
					(mid 331.09811 -390.945912)
					(end 331.151992 -390.96823)
				)
				(arc
					(start 331.837792 -390.96823)
					(mid 331.891674 -390.945912)
					(end 331.913992 -390.89203)
				)
				(arc
					(start 331.913992 -390.697466)
					(mid 331.910824 -390.675722)
					(end 331.901546 -390.65581)
				)
				(arc
					(start 331.70876 -390.359646)
					(mid 331.696538 -390.317962)
					(end 331.709014 -390.276334)
				)
				(arc
					(start 331.901546 -389.98271)
					(mid 331.910782 -389.962786)
					(end 331.913992 -389.941054)
				)
				(arc
					(start 331.913992 -389.74649)
					(mid 331.891674 -389.692608)
					(end 331.837792 -389.67029)
				)
				(arc
					(start 331.151992 -389.67029)
					(mid 331.09811 -389.692608)
					(end 331.075792 -389.74649)
				)
				(arc
					(start 331.075792 -389.942324)
					(mid 331.07896 -389.964068)
					(end 331.088238 -389.98398)
				)
				(arc
					(start 331.28077 -390.277604)
					(mid 331.293172 -390.31926)
					(end 331.28077 -390.360916)
				)
			)
		)
	)
	(zone
		(layer "In2.Cu")
		(hatch none 0.5)
		(connect_pads
			(clearance 0)
		)
		(min_thickness 0.25)
		(keepout
			(tracks not_allowed)
			(vias allowed)
			(pads allowed)
			(copperpour not_allowed)
			(footprints allowed)
		)
		(placement
			(enabled no)
			(sheetname "")
		)
		(fill
			(thermal_gap 0.5)
			(thermal_bridge_width 0.5)
			(island_removal_mode 0)
		)
		(polygon
			(pts
				(xy 438.350914 -265.9253) (xy 439.849514 -265.9253) (xy 439.849514 -266.445238) (xy 438.350914 -266.445238)
			)
		)
	)
	(zone
		(layer "In2.Cu")
		(hatch none 0.5)
		(connect_pads
			(clearance 0)
		)
		(min_thickness 0.25)
		(keepout
			(tracks not_allowed)
			(vias allowed)
			(pads allowed)
			(copperpour not_allowed)
			(footprints allowed)
		)
		(placement
			(enabled no)
			(sheetname "")
		)
		(fill
			(thermal_gap 0.5)
			(thermal_bridge_width 0.5)
			(island_removal_mode 0)
		)
		(polygon
			(pts
				(xy 31.946596 -254.025146) (xy 33.445196 -254.025146) (xy 33.445196 -254.545084) (xy 31.946596 -254.545084)
			)
		)
	)
	(zone
		(layer "In2.Cu")
		(hatch none 0.5)
		(connect_pads
			(clearance 0)
		)
		(min_thickness 0.25)
		(keepout
			(tracks not_allowed)
			(vias allowed)
			(pads allowed)
			(copperpour not_allowed)
			(footprints allowed)
		)
		(placement
			(enabled no)
			(sheetname "")
		)
		(fill
			(thermal_gap 0.5)
			(thermal_bridge_width 0.5)
			(island_removal_mode 0)
		)
		(polygon
			(pts
				(xy 415.718752 -208.125314) (xy 417.217352 -208.125314) (xy 417.217352 -208.645252) (xy 415.718752 -208.645252)
			)
		)
	)
	(zone
		(layer "In2.Cu")
		(hatch none 0.5)
		(connect_pads
			(clearance 0)
		)
		(min_thickness 0.25)
		(keepout
			(tracks not_allowed)
			(vias allowed)
			(pads allowed)
			(copperpour not_allowed)
			(footprints allowed)
		)
		(placement
			(enabled no)
			(sheetname "")
		)
		(fill
			(thermal_gap 0.5)
			(thermal_bridge_width 0.5)
			(island_removal_mode 0)
		)
		(polygon
			(pts
				(xy 36.046664 -234.475274) (xy 37.545264 -234.475274) (xy 37.545264 -234.995212) (xy 36.046664 -234.995212)
			)
		)
	)
	(zone
		(layer "In2.Cu")
		(hatch none 0.5)
		(connect_pads
			(clearance 0)
		)
		(min_thickness 0.25)
		(keepout
			(tracks not_allowed)
			(vias allowed)
			(pads allowed)
			(copperpour not_allowed)
			(footprints allowed)
		)
		(placement
			(enabled no)
			(sheetname "")
		)
		(fill
			(thermal_gap 0.5)
			(thermal_bridge_width 0.5)
			(island_removal_mode 0)
		)
		(polygon
			(pts
				(xy 415.718752 -267.625322) (xy 417.217352 -267.625322) (xy 417.217352 -268.14526) (xy 415.718752 -268.14526)
			)
		)
	)
	(zone
		(layer "In2.Cu")
		(hatch none 0.5)
		(connect_pads
			(clearance 0)
		)
		(min_thickness 0.25)
		(keepout
			(tracks not_allowed)
			(vias allowed)
			(pads allowed)
			(copperpour not_allowed)
			(footprints allowed)
		)
		(placement
			(enabled no)
			(sheetname "")
		)
		(fill
			(thermal_gap 0.5)
			(thermal_bridge_width 0.5)
			(island_removal_mode 0)
		)
		(polygon
			(pts
				(xy 193.854578 -253.175262) (xy 195.353178 -253.175262) (xy 195.353178 -253.6952) (xy 193.854578 -253.6952)
			)
		)
	)
	(zone
		(layer "In2.Cu")
		(hatch none 0.5)
		(connect_pads
			(clearance 0)
		)
		(min_thickness 0.25)
		(keepout
			(tracks not_allowed)
			(vias allowed)
			(pads allowed)
			(copperpour not_allowed)
			(footprints allowed)
		)
		(placement
			(enabled no)
			(sheetname "")
		)
		(fill
			(thermal_gap 0.5)
			(thermal_bridge_width 0.5)
			(island_removal_mode 0)
		)
		(polygon
			(pts
				(xy 47.034704 -310.12511) (xy 48.533304 -310.12511) (xy 48.533304 -310.645048) (xy 47.034704 -310.645048)
			)
		)
	)
	(zone
		(layer "In2.Cu")
		(hatch none 0.5)
		(connect_pads
			(clearance 0)
		)
		(min_thickness 0.25)
		(keepout
			(tracks not_allowed)
			(vias allowed)
			(pads allowed)
			(copperpour not_allowed)
			(footprints allowed)
		)
		(placement
			(enabled no)
			(sheetname "")
		)
		(fill
			(thermal_gap 0.5)
			(thermal_bridge_width 0.5)
			(island_removal_mode 0)
		)
		(polygon
			(pts
				(xy 28.50261 -206.425292) (xy 30.00121 -206.425292) (xy 30.00121 -206.94523) (xy 28.50261 -206.94523)
			)
		)
	)
	(zone
		(layer "In2.Cu")
		(hatch none 0.5)
		(connect_pads
			(clearance 0)
		)
		(min_thickness 0.25)
		(keepout
			(tracks allowed)
			(vias allowed)
			(pads allowed)
			(copperpour allowed)
			(footprints allowed)
		)
		(placement
			(enabled no)
			(sheetname "")
		)
		(fill
			(thermal_gap 0.5)
			(thermal_bridge_width 0.5)
			(island_removal_mode 0)
		)
		(polygon
			(pts
				(xy 48.61941 -349.122492) (xy 48.61941 -348.500192) (xy 49.17059 -348.500192) (xy 49.17059 -349.122492)
			)
		)
	)
	(zone
		(layer "In2.Cu")
		(hatch none 0.5)
		(connect_pads
			(clearance 0)
		)
		(min_thickness 0.25)
		(keepout
			(tracks not_allowed)
			(vias allowed)
			(pads allowed)
			(copperpour not_allowed)
			(footprints allowed)
		)
		(placement
			(enabled no)
			(sheetname "")
		)
		(fill
			(thermal_gap 0.5)
			(thermal_bridge_width 0.5)
			(island_removal_mode 0)
		)
		(polygon
			(pts
				(xy 190.410846 -309.275226) (xy 191.909446 -309.275226) (xy 191.909446 -309.795164) (xy 190.410846 -309.795164)
			)
		)
	)
	(zone
		(layer "In2.Cu")
		(hatch none 0.5)
		(connect_pads
			(clearance 0)
		)
		(min_thickness 0.25)
		(keepout
			(tracks not_allowed)
			(vias allowed)
			(pads allowed)
			(copperpour not_allowed)
			(footprints allowed)
		)
		(placement
			(enabled no)
			(sheetname "")
		)
		(fill
			(thermal_gap 0.5)
			(thermal_bridge_width 0.5)
			(island_removal_mode 0)
		)
		(polygon
			(pts
				(xy 283.986732 -301.625254) (xy 285.485332 -301.625254) (xy 285.485332 -302.145192) (xy 283.986732 -302.145192)
			)
		)
	)
	(zone
		(layer "In2.Cu")
		(hatch none 0.5)
		(connect_pads
			(clearance 0)
		)
		(min_thickness 0.25)
		(keepout
			(tracks not_allowed)
			(vias allowed)
			(pads allowed)
			(copperpour not_allowed)
			(footprints allowed)
		)
		(placement
			(enabled no)
			(sheetname "")
		)
		(fill
			(thermal_gap 0.5)
			(thermal_bridge_width 0.5)
			(island_removal_mode 0)
		)
		(polygon
			(pts
				(xy 58.678826 -238.725202) (xy 60.177426 -238.725202) (xy 60.177426 -239.24514) (xy 58.678826 -239.24514)
			)
		)
	)
	(zone
		(layer "In2.Cu")
		(hatch none 0.5)
		(connect_pads
			(clearance 0)
		)
		(min_thickness 0.25)
		(keepout
			(tracks not_allowed)
			(vias allowed)
			(pads allowed)
			(copperpour not_allowed)
			(footprints allowed)
		)
		(placement
			(enabled no)
			(sheetname "")
		)
		(fill
			(thermal_gap 0.5)
			(thermal_bridge_width 0.5)
			(island_removal_mode 0)
		)
		(polygon
			(pts
				(xy 453.438768 -277.8252) (xy 454.937368 -277.8252) (xy 454.937368 -278.345138) (xy 453.438768 -278.345138)
			)
		)
	)
	(zone
		(layer "In2.Cu")
		(hatch none 0.5)
		(connect_pads
			(clearance 0)
		)
		(min_thickness 0.25)
		(keepout
			(tracks not_allowed)
			(vias allowed)
			(pads allowed)
			(copperpour not_allowed)
			(footprints allowed)
		)
		(placement
			(enabled no)
			(sheetname "")
		)
		(fill
			(thermal_gap 0.5)
			(thermal_bridge_width 0.5)
			(island_removal_mode 0)
		)
		(polygon
			(pts
				(xy 445.894968 -296.525188) (xy 447.393568 -296.525188) (xy 447.393568 -297.045126) (xy 445.894968 -297.045126)
			)
		)
	)
	(zone
		(layer "In2.Cu")
		(hatch none 0.5)
		(connect_pads
			(clearance 0)
		)
		(min_thickness 0.25)
		(keepout
			(tracks not_allowed)
			(vias allowed)
			(pads allowed)
			(copperpour not_allowed)
			(footprints allowed)
		)
		(placement
			(enabled no)
			(sheetname "")
		)
		(fill
			(thermal_gap 0.5)
			(thermal_bridge_width 0.5)
			(island_removal_mode 0)
		)
		(polygon
			(pts
				(xy 193.854578 -242.97513) (xy 195.353178 -242.97513) (xy 195.353178 -243.495068) (xy 193.854578 -243.495068)
			)
		)
	)
	(zone
		(layer "In2.Cu")
		(hatch none 0.5)
		(connect_pads
			(clearance 0)
		)
		(min_thickness 0.25)
		(keepout
			(tracks not_allowed)
			(vias allowed)
			(pads allowed)
			(copperpour not_allowed)
			(footprints allowed)
		)
		(placement
			(enabled no)
			(sheetname "")
		)
		(fill
			(thermal_gap 0.5)
			(thermal_bridge_width 0.5)
			(island_removal_mode 0)
		)
		(polygon
			(pts
				(xy 16.858742 -313.525154) (xy 18.357342 -313.525154) (xy 18.357342 -314.045092) (xy 16.858742 -314.045092)
			)
		)
	)
	(zone
		(layer "In2.Cu")
		(hatch none 0.5)
		(connect_pads
			(clearance 0)
		)
		(min_thickness 0.25)
		(keepout
			(tracks not_allowed)
			(vias allowed)
			(pads allowed)
			(copperpour not_allowed)
			(footprints allowed)
		)
		(placement
			(enabled no)
			(sheetname "")
		)
		(fill
			(thermal_gap 0.5)
			(thermal_bridge_width 0.5)
			(island_removal_mode 0)
		)
		(polygon
			(pts
				(xy 306.618894 -260.825234) (xy 308.117494 -260.825234) (xy 308.117494 -261.345172) (xy 306.618894 -261.345172)
			)
		)
	)
	(zone
		(layer "In2.Cu")
		(hatch none 0.5)
		(connect_pads
			(clearance 0)
		)
		(min_thickness 0.25)
		(keepout
			(tracks not_allowed)
			(vias allowed)
			(pads allowed)
			(copperpour not_allowed)
			(footprints allowed)
		)
		(placement
			(enabled no)
			(sheetname "")
		)
		(fill
			(thermal_gap 0.5)
			(thermal_bridge_width 0.5)
			(island_removal_mode 0)
		)
		(polygon
			(pts
				(xy 31.946596 -310.12511) (xy 33.445196 -310.12511) (xy 33.445196 -310.645048) (xy 31.946596 -310.645048)
			)
		)
	)
	(zone
		(layer "In2.Cu")
		(hatch none 0.5)
		(connect_pads
			(clearance 0)
		)
		(min_thickness 0.25)
		(keepout
			(tracks not_allowed)
			(vias allowed)
			(pads allowed)
			(copperpour not_allowed)
			(footprints allowed)
		)
		(placement
			(enabled no)
			(sheetname "")
		)
		(fill
			(thermal_gap 0.5)
			(thermal_bridge_width 0.5)
			(island_removal_mode 0)
		)
		(polygon
			(pts
				(xy 36.046664 -303.325276) (xy 37.545264 -303.325276) (xy 37.545264 -303.845214) (xy 36.046664 -303.845214)
			)
		)
	)
	(zone
		(layer "In2.Cu")
		(hatch none 0.5)
		(connect_pads
			(clearance 0)
		)
		(min_thickness 0.25)
		(keepout
			(tracks not_allowed)
			(vias allowed)
			(pads allowed)
			(copperpour not_allowed)
			(footprints allowed)
		)
		(placement
			(enabled no)
			(sheetname "")
		)
		(fill
			(thermal_gap 0.5)
			(thermal_bridge_width 0.5)
			(island_removal_mode 0)
		)
		(polygon
			(pts
				(xy 167.778684 -223.425258) (xy 169.277284 -223.425258) (xy 169.277284 -223.945196) (xy 167.778684 -223.945196)
			)
		)
	)
	(zone
		(layer "In2.Cu")
		(hatch none 0.5)
		(connect_pads
			(clearance 0)
		)
		(min_thickness 0.25)
		(keepout
			(tracks not_allowed)
			(vias allowed)
			(pads allowed)
			(copperpour not_allowed)
			(footprints allowed)
		)
		(placement
			(enabled no)
			(sheetname "")
		)
		(fill
			(thermal_gap 0.5)
			(thermal_bridge_width 0.5)
			(island_removal_mode 0)
		)
		(polygon
			(pts
				(xy 423.262806 -198.77532) (xy 424.761406 -198.77532) (xy 424.761406 -199.295258) (xy 423.262806 -199.295258)
			)
		)
	)
	(zone
		(layer "In2.Cu")
		(hatch none 0.5)
		(connect_pads
			(clearance 0)
		)
		(min_thickness 0.25)
		(keepout
			(tracks not_allowed)
			(vias allowed)
			(pads allowed)
			(copperpour not_allowed)
			(footprints allowed)
		)
		(placement
			(enabled no)
			(sheetname "")
		)
		(fill
			(thermal_gap 0.5)
			(thermal_bridge_width 0.5)
			(island_removal_mode 0)
		)
		(polygon
			(pts
				(xy 294.974772 -218.325192) (xy 296.473372 -218.325192) (xy 296.473372 -218.84513) (xy 294.974772 -218.84513)
			)
		)
	)
	(zone
		(layer "In2.Cu")
		(hatch none 0.5)
		(connect_pads
			(clearance 0)
		)
		(min_thickness 0.25)
		(keepout
			(tracks not_allowed)
			(vias allowed)
			(pads allowed)
			(copperpour not_allowed)
			(footprints allowed)
		)
		(placement
			(enabled no)
			(sheetname "")
		)
		(fill
			(thermal_gap 0.5)
			(thermal_bridge_width 0.5)
			(island_removal_mode 0)
		)
		(polygon
			(pts
				(xy 279.886664 -282.075128) (xy 281.385264 -282.075128) (xy 281.385264 -282.595066) (xy 279.886664 -282.595066)
			)
		)
	)
	(zone
		(layer "In2.Cu")
		(hatch none 0.5)
		(connect_pads
			(clearance 0)
		)
		(min_thickness 0.25)
		(keepout
			(tracks not_allowed)
			(vias allowed)
			(pads allowed)
			(copperpour not_allowed)
			(footprints allowed)
		)
		(placement
			(enabled no)
			(sheetname "")
		)
		(fill
			(thermal_gap 0.5)
			(thermal_bridge_width 0.5)
			(island_removal_mode 0)
		)
		(polygon
			(pts
				(xy 28.50261 -234.475274) (xy 30.00121 -234.475274) (xy 30.00121 -234.995212) (xy 28.50261 -234.995212)
			)
		)
	)
	(zone
		(layer "In2.Cu")
		(hatch none 0.5)
		(connect_pads
			(clearance 0)
		)
		(min_thickness 0.25)
		(keepout
			(tracks not_allowed)
			(vias allowed)
			(pads allowed)
			(copperpour not_allowed)
			(footprints allowed)
		)
		(placement
			(enabled no)
			(sheetname "")
		)
		(fill
			(thermal_gap 0.5)
			(thermal_bridge_width 0.5)
			(island_removal_mode 0)
		)
		(polygon
			(pts
				(xy 415.718752 -197.075298) (xy 417.217352 -197.075298) (xy 417.217352 -197.595236) (xy 415.718752 -197.595236)
			)
		)
	)
	(zone
		(layer "In2.Cu")
		(hatch none 0.5)
		(connect_pads
			(clearance 0)
		)
		(min_thickness 0.25)
		(keepout
			(tracks not_allowed)
			(vias allowed)
			(pads allowed)
			(copperpour not_allowed)
			(footprints allowed)
		)
		(placement
			(enabled no)
			(sheetname "")
		)
		(fill
			(thermal_gap 0.5)
			(thermal_bridge_width 0.5)
			(island_removal_mode 0)
		)
		(polygon
			(pts
				(xy 434.250846 -314.375292) (xy 435.749446 -314.375292) (xy 435.749446 -314.89523) (xy 434.250846 -314.89523)
			)
		)
	)
	(zone
		(layer "In2.Cu")
		(hatch none 0.5)
		(connect_pads
			(clearance 0)
		)
		(min_thickness 0.25)
		(keepout
			(tracks not_allowed)
			(vias allowed)
			(pads allowed)
			(copperpour not_allowed)
			(footprints allowed)
		)
		(placement
			(enabled no)
			(sheetname "")
		)
		(fill
			(thermal_gap 0.5)
			(thermal_bridge_width 0.5)
			(island_removal_mode 0)
		)
		(polygon
			(pts
				(xy 36.046664 -254.025146) (xy 37.545264 -254.025146) (xy 37.545264 -254.545084) (xy 36.046664 -254.545084)
			)
		)
	)
	(zone
		(layer "In2.Cu")
		(hatch none 0.5)
		(connect_pads
			(clearance 0)
		)
		(min_thickness 0.25)
		(keepout
			(tracks not_allowed)
			(vias allowed)
			(pads allowed)
			(copperpour not_allowed)
			(footprints allowed)
		)
		(placement
			(enabled no)
			(sheetname "")
		)
		(fill
			(thermal_gap 0.5)
			(thermal_bridge_width 0.5)
			(island_removal_mode 0)
		)
		(polygon
			(pts
				(xy 411.618684 -231.925114) (xy 413.117284 -231.925114) (xy 413.117284 -232.445052) (xy 411.618684 -232.445052)
			)
		)
	)
	(zone
		(layer "In2.Cu")
		(hatch none 0.5)
		(connect_pads
			(clearance 0)
		)
		(min_thickness 0.25)
		(keepout
			(tracks not_allowed)
			(vias allowed)
			(pads allowed)
			(copperpour not_allowed)
			(footprints allowed)
		)
		(placement
			(enabled no)
			(sheetname "")
		)
		(fill
			(thermal_gap 0.5)
			(thermal_bridge_width 0.5)
			(island_removal_mode 0)
		)
		(polygon
			(pts
				(xy 434.250846 -268.475206) (xy 435.749446 -268.475206) (xy 435.749446 -268.995144) (xy 434.250846 -268.995144)
			)
		)
	)
	(zone
		(layer "In2.Cu")
		(hatch none 0.5)
		(connect_pads
			(clearance 0)
		)
		(min_thickness 0.25)
		(keepout
			(tracks not_allowed)
			(vias allowed)
			(pads allowed)
			(copperpour not_allowed)
			(footprints allowed)
		)
		(placement
			(enabled no)
			(sheetname "")
		)
		(fill
			(thermal_gap 0.5)
			(thermal_bridge_width 0.5)
			(island_removal_mode 0)
		)
		(polygon
			(pts
				(xy 167.778684 -252.325124) (xy 169.277284 -252.325124) (xy 169.277284 -252.845062) (xy 167.778684 -252.845062)
			)
		)
	)
	(zone
		(layer "In2.Cu")
		(hatch none 0.5)
		(connect_pads
			(clearance 0)
		)
		(min_thickness 0.25)
		(keepout
			(tracks not_allowed)
			(vias allowed)
			(pads allowed)
			(copperpour not_allowed)
			(footprints allowed)
		)
		(placement
			(enabled no)
			(sheetname "")
		)
		(fill
			(thermal_gap 0.5)
			(thermal_bridge_width 0.5)
			(island_removal_mode 0)
		)
		(polygon
			(pts
				(xy 287.430718 -316.075314) (xy 288.929318 -316.075314) (xy 288.929318 -316.595252) (xy 287.430718 -316.595252)
			)
		)
	)
	(zone
		(layer "In2.Cu")
		(hatch none 0.5)
		(connect_pads
			(clearance 0)
		)
		(min_thickness 0.25)
		(keepout
			(tracks not_allowed)
			(vias allowed)
			(pads allowed)
			(copperpour not_allowed)
			(footprints allowed)
		)
		(placement
			(enabled no)
			(sheetname "")
		)
		(fill
			(thermal_gap 0.5)
			(thermal_bridge_width 0.5)
			(island_removal_mode 0)
		)
		(polygon
			(pts
				(xy 302.518826 -280.375106) (xy 304.017426 -280.375106) (xy 304.017426 -280.895044) (xy 302.518826 -280.895044)
			)
		)
	)
	(zone
		(layer "In2.Cu")
		(hatch none 0.5)
		(connect_pads
			(clearance 0)
		)
		(min_thickness 0.25)
		(keepout
			(tracks allowed)
			(vias allowed)
			(pads allowed)
			(copperpour allowed)
			(footprints allowed)
		)
		(placement
			(enabled no)
			(sheetname "")
		)
		(fill
			(thermal_gap 0.5)
			(thermal_bridge_width 0.5)
			(island_removal_mode 0)
		)
		(polygon
			(pts
				(xy 66.82613 -335.904332) (xy 66.82613 -336.816192) (xy 66.58991 -336.816192) (xy 66.58991 -335.904332)
			)
		)
	)
	(zone
		(layer "In2.Cu")
		(hatch none 0.5)
		(connect_pads
			(clearance 0)
		)
		(min_thickness 0.25)
		(keepout
			(tracks not_allowed)
			(vias allowed)
			(pads allowed)
			(copperpour not_allowed)
			(footprints allowed)
		)
		(placement
			(enabled no)
			(sheetname "")
		)
		(fill
			(thermal_gap 0.5)
			(thermal_bridge_width 0.5)
			(island_removal_mode 0)
		)
		(polygon
			(pts
				(xy 283.986732 -277.8252) (xy 285.485332 -277.8252) (xy 285.485332 -278.345138) (xy 283.986732 -278.345138)
			)
		)
	)
	(zone
		(layer "In2.Cu")
		(hatch none 0.5)
		(connect_pads
			(clearance 0)
		)
		(min_thickness 0.25)
		(keepout
			(tracks not_allowed)
			(vias allowed)
			(pads allowed)
			(copperpour not_allowed)
			(footprints allowed)
		)
		(placement
			(enabled no)
			(sheetname "")
		)
		(fill
			(thermal_gap 0.5)
			(thermal_bridge_width 0.5)
			(island_removal_mode 0)
		)
		(polygon
			(pts
				(xy 411.618684 -286.32531) (xy 413.117284 -286.32531) (xy 413.117284 -286.845248) (xy 411.618684 -286.845248)
			)
		)
	)
	(zone
		(layer "In2.Cu")
		(hatch none 0.5)
		(connect_pads
			(clearance 0)
		)
		(min_thickness 0.25)
		(keepout
			(tracks not_allowed)
			(vias allowed)
			(pads allowed)
			(copperpour not_allowed)
			(footprints allowed)
		)
		(placement
			(enabled no)
			(sheetname "")
		)
		(fill
			(thermal_gap 0.5)
			(thermal_bridge_width 0.5)
			(island_removal_mode 0)
		)
		(polygon
			(pts
				(xy 423.262806 -270.175228) (xy 424.761406 -270.175228) (xy 424.761406 -270.695166) (xy 423.262806 -270.695166)
			)
		)
	)
	(zone
		(layer "In2.Cu")
		(hatch none 0.5)
		(connect_pads
			(clearance 0)
		)
		(min_thickness 0.25)
		(keepout
			(tracks not_allowed)
			(vias allowed)
			(pads allowed)
			(copperpour not_allowed)
			(footprints allowed)
		)
		(placement
			(enabled no)
			(sheetname "")
		)
		(fill
			(thermal_gap 0.5)
			(thermal_bridge_width 0.5)
			(island_removal_mode 0)
		)
		(polygon
			(pts
				(xy 31.946596 -248.075196) (xy 33.445196 -248.075196) (xy 33.445196 -248.595134) (xy 31.946596 -248.595134)
			)
		)
	)
	(zone
		(layer "In2.Cu")
		(hatch none 0.5)
		(connect_pads
			(clearance 0)
		)
		(min_thickness 0.25)
		(keepout
			(tracks not_allowed)
			(vias allowed)
			(pads allowed)
			(copperpour not_allowed)
			(footprints allowed)
		)
		(placement
			(enabled no)
			(sheetname "")
		)
		(fill
			(thermal_gap 0.5)
			(thermal_bridge_width 0.5)
			(island_removal_mode 0)
		)
		(polygon
			(pts
				(xy 201.398632 -220.025214) (xy 202.897232 -220.025214) (xy 202.897232 -220.545152) (xy 201.398632 -220.545152)
			)
		)
	)
	(zone
		(layer "In2.Cu")
		(hatch none 0.5)
		(connect_pads
			(clearance 0)
		)
		(min_thickness 0.25)
		(keepout
			(tracks allowed)
			(vias allowed)
			(pads allowed)
			(copperpour allowed)
			(footprints allowed)
		)
		(placement
			(enabled no)
			(sheetname "")
		)
		(fill
			(thermal_gap 0.5)
			(thermal_bridge_width 0.5)
			(island_removal_mode 0)
		)
		(polygon
			(pts
				(xy 82.197194 -338.130896) (xy 82.197194 -337.508596) (xy 82.748374 -337.508596) (xy 82.748374 -338.130896)
			)
		)
	)
	(zone
		(layer "In2.Cu")
		(hatch none 0.5)
		(connect_pads
			(clearance 0)
		)
		(min_thickness 0.25)
		(keepout
			(tracks not_allowed)
			(vias allowed)
			(pads allowed)
			(copperpour not_allowed)
			(footprints allowed)
		)
		(placement
			(enabled no)
			(sheetname "")
		)
		(fill
			(thermal_gap 0.5)
			(thermal_bridge_width 0.5)
			(island_removal_mode 0)
		)
		(polygon
			(pts
				(xy 415.718752 -316.925198) (xy 417.217352 -316.925198) (xy 417.217352 -317.445136) (xy 415.718752 -317.445136)
			)
		)
	)
	(zone
		(layer "In2.Cu")
		(hatch none 0.5)
		(connect_pads
			(clearance 0)
		)
		(min_thickness 0.25)
		(keepout
			(tracks not_allowed)
			(vias allowed)
			(pads allowed)
			(copperpour not_allowed)
			(footprints allowed)
		)
		(placement
			(enabled no)
			(sheetname "")
		)
		(fill
			(thermal_gap 0.5)
			(thermal_bridge_width 0.5)
			(island_removal_mode 0)
		)
		(polygon
			(pts
				(xy 453.438768 -303.325276) (xy 454.937368 -303.325276) (xy 454.937368 -303.845214) (xy 453.438768 -303.845214)
			)
		)
	)
	(zone
		(layer "In2.Cu")
		(hatch none 0.5)
		(connect_pads
			(clearance 0)
		)
		(min_thickness 0.25)
		(keepout
			(tracks not_allowed)
			(vias allowed)
			(pads allowed)
			(copperpour not_allowed)
			(footprints allowed)
		)
		(placement
			(enabled no)
			(sheetname "")
		)
		(fill
			(thermal_gap 0.5)
			(thermal_bridge_width 0.5)
			(island_removal_mode 0)
		)
		(polygon
			(pts
				(xy 445.894968 -299.925232) (xy 447.393568 -299.925232) (xy 447.393568 -300.44517) (xy 445.894968 -300.44517)
			)
		)
	)
	(zone
		(layer "In2.Cu")
		(hatch none 0.5)
		(connect_pads
			(clearance 0)
		)
		(min_thickness 0.25)
		(keepout
			(tracks not_allowed)
			(vias allowed)
			(pads allowed)
			(copperpour not_allowed)
			(footprints allowed)
		)
		(placement
			(enabled no)
			(sheetname "")
		)
		(fill
			(thermal_gap 0.5)
			(thermal_bridge_width 0.5)
			(island_removal_mode 0)
		)
		(polygon
			(pts
				(xy 272.342864 -249.775218) (xy 273.841464 -249.775218) (xy 273.841464 -250.295156) (xy 272.342864 -250.295156)
			)
		)
	)
	(zone
		(layer "In2.Cu")
		(hatch none 0.5)
		(connect_pads
			(clearance 0)
		)
		(min_thickness 0.25)
		(keepout
			(tracks not_allowed)
			(vias allowed)
			(pads allowed)
			(copperpour not_allowed)
			(footprints allowed)
		)
		(placement
			(enabled no)
			(sheetname "")
		)
		(fill
			(thermal_gap 0.5)
			(thermal_bridge_width 0.5)
			(island_removal_mode 0)
		)
		(polygon
			(pts
				(xy 47.034704 -230.225346) (xy 48.533304 -230.225346) (xy 48.533304 -230.745284) (xy 47.034704 -230.745284)
			)
		)
	)
	(zone
		(layer "In2.Cu")
		(hatch none 0.5)
		(connect_pads
			(clearance 0)
		)
		(min_thickness 0.25)
		(keepout
			(tracks not_allowed)
			(vias allowed)
			(pads allowed)
			(copperpour not_allowed)
			(footprints allowed)
		)
		(placement
			(enabled no)
			(sheetname "")
		)
		(fill
			(thermal_gap 0.5)
			(thermal_bridge_width 0.5)
			(island_removal_mode 0)
		)
		(polygon
			(pts
				(xy 193.854578 -229.375208) (xy 195.353178 -229.375208) (xy 195.353178 -229.895146) (xy 193.854578 -229.895146)
			)
		)
	)
	(zone
		(layer "In2.Cu")
		(hatch none 0.5)
		(connect_pads
			(clearance 0)
		)
		(min_thickness 0.25)
		(keepout
			(tracks not_allowed)
			(vias allowed)
			(pads allowed)
			(copperpour not_allowed)
			(footprints allowed)
		)
		(placement
			(enabled no)
			(sheetname "")
		)
		(fill
			(thermal_gap 0.5)
			(thermal_bridge_width 0.5)
			(island_removal_mode 0)
		)
		(polygon
			(pts
				(xy 171.22267 -235.325158) (xy 172.72127 -235.325158) (xy 172.72127 -235.845096) (xy 171.22267 -235.845096)
			)
		)
	)
	(zone
		(layer "In2.Cu")
		(hatch none 0.5)
		(connect_pads
			(clearance 0)
		)
		(min_thickness 0.25)
		(keepout
			(tracks not_allowed)
			(vias allowed)
			(pads allowed)
			(copperpour not_allowed)
			(footprints allowed)
		)
		(placement
			(enabled no)
			(sheetname "")
		)
		(fill
			(thermal_gap 0.5)
			(thermal_bridge_width 0.5)
			(island_removal_mode 0)
		)
		(polygon
			(pts
				(xy 283.986732 -285.475172) (xy 285.485332 -285.475172) (xy 285.485332 -285.99511) (xy 283.986732 -285.99511)
			)
		)
	)
	(zone
		(layer "In2.Cu")
		(hatch none 0.5)
		(connect_pads
			(clearance 0)
		)
		(min_thickness 0.25)
		(keepout
			(tracks not_allowed)
			(vias allowed)
			(pads allowed)
			(copperpour not_allowed)
			(footprints allowed)
		)
		(placement
			(enabled no)
			(sheetname "")
		)
		(fill
			(thermal_gap 0.5)
			(thermal_bridge_width 0.5)
			(island_removal_mode 0)
		)
		(polygon
			(pts
				(xy 283.986732 -292.27526) (xy 285.485332 -292.27526) (xy 285.485332 -292.795198) (xy 283.986732 -292.795198)
			)
		)
	)
	(zone
		(layer "In2.Cu")
		(hatch none 0.5)
		(connect_pads
			(clearance 0)
		)
		(min_thickness 0.25)
		(keepout
			(tracks not_allowed)
			(vias allowed)
			(pads allowed)
			(copperpour not_allowed)
			(footprints allowed)
		)
		(placement
			(enabled no)
			(sheetname "")
		)
		(fill
			(thermal_gap 0.5)
			(thermal_bridge_width 0.5)
			(island_removal_mode 0)
		)
		(polygon
			(pts
				(xy 201.398632 -251.47524) (xy 202.897232 -251.47524) (xy 202.897232 -251.995178) (xy 201.398632 -251.995178)
			)
		)
	)
	(zone
		(layer "In2.Cu")
		(hatch none 0.5)
		(connect_pads
			(clearance 0)
		)
		(min_thickness 0.25)
		(keepout
			(tracks not_allowed)
			(vias allowed)
			(pads allowed)
			(copperpour not_allowed)
			(footprints allowed)
		)
		(placement
			(enabled no)
			(sheetname "")
		)
		(fill
			(thermal_gap 0.5)
			(thermal_bridge_width 0.5)
			(island_removal_mode 0)
		)
		(polygon
			(pts
				(xy 449.3387 -253.175262) (xy 450.8373 -253.175262) (xy 450.8373 -253.6952) (xy 449.3387 -253.6952)
			)
		)
	)
	(zone
		(layer "In2.Cu")
		(hatch none 0.5)
		(connect_pads
			(clearance 0)
		)
		(min_thickness 0.25)
		(keepout
			(tracks not_allowed)
			(vias allowed)
			(pads allowed)
			(copperpour not_allowed)
			(footprints allowed)
		)
		(placement
			(enabled no)
			(sheetname "")
		)
		(fill
			(thermal_gap 0.5)
			(thermal_bridge_width 0.5)
			(island_removal_mode 0)
		)
		(polygon
			(pts
				(xy 302.518826 -231.925114) (xy 304.017426 -231.925114) (xy 304.017426 -232.445052) (xy 302.518826 -232.445052)
			)
		)
	)
	(zone
		(layer "In2.Cu")
		(hatch none 0.5)
		(connect_pads
			(clearance 0)
		)
		(min_thickness 0.25)
		(keepout
			(tracks not_allowed)
			(vias allowed)
			(pads allowed)
			(copperpour not_allowed)
			(footprints allowed)
		)
		(placement
			(enabled no)
			(sheetname "")
		)
		(fill
			(thermal_gap 0.5)
			(thermal_bridge_width 0.5)
			(island_removal_mode 0)
		)
		(polygon
			(pts
				(xy 445.894968 -273.575272) (xy 447.393568 -273.575272) (xy 447.393568 -274.09521) (xy 445.894968 -274.09521)
			)
		)
	)
	(zone
		(layer "In2.Cu")
		(hatch none 0.5)
		(connect_pads
			(clearance 0)
		)
		(min_thickness 0.25)
		(keepout
			(tracks not_allowed)
			(vias allowed)
			(pads allowed)
			(copperpour not_allowed)
			(footprints allowed)
		)
		(placement
			(enabled no)
			(sheetname "")
		)
		(fill
			(thermal_gap 0.5)
			(thermal_bridge_width 0.5)
			(island_removal_mode 0)
		)
		(polygon
			(pts
				(xy 438.350914 -270.175228) (xy 439.849514 -270.175228) (xy 439.849514 -270.695166) (xy 438.350914 -270.695166)
			)
		)
	)
	(zone
		(layer "In2.Cu")
		(hatch none 0.5)
		(connect_pads
			(clearance 0)
		)
		(min_thickness 0.25)
		(keepout
			(tracks not_allowed)
			(vias allowed)
			(pads allowed)
			(copperpour not_allowed)
			(footprints allowed)
		)
		(placement
			(enabled no)
			(sheetname "")
		)
		(fill
			(thermal_gap 0.5)
			(thermal_bridge_width 0.5)
			(island_removal_mode 0)
		)
		(polygon
			(pts
				(xy 171.22267 -220.875098) (xy 172.72127 -220.875098) (xy 172.72127 -221.395036) (xy 171.22267 -221.395036)
			)
		)
	)
	(zone
		(layer "In2.Cu")
		(hatch none 0.5)
		(connect_pads
			(clearance 0)
		)
		(min_thickness 0.25)
		(keepout
			(tracks not_allowed)
			(vias allowed)
			(pads allowed)
			(copperpour not_allowed)
			(footprints allowed)
		)
		(placement
			(enabled no)
			(sheetname "")
		)
		(fill
			(thermal_gap 0.5)
			(thermal_bridge_width 0.5)
			(island_removal_mode 0)
		)
		(polygon
			(pts
				(xy 58.678826 -220.025214) (xy 60.177426 -220.025214) (xy 60.177426 -220.545152) (xy 58.678826 -220.545152)
			)
		)
	)
	(zone
		(layer "In2.Cu")
		(hatch none 0.5)
		(connect_pads
			(clearance 0)
		)
		(min_thickness 0.25)
		(keepout
			(tracks not_allowed)
			(vias allowed)
			(pads allowed)
			(copperpour not_allowed)
			(footprints allowed)
		)
		(placement
			(enabled no)
			(sheetname "")
		)
		(fill
			(thermal_gap 0.5)
			(thermal_bridge_width 0.5)
			(island_removal_mode 0)
		)
		(polygon
			(pts
				(xy 24.402542 -304.17516) (xy 25.901142 -304.17516) (xy 25.901142 -304.695098) (xy 24.402542 -304.695098)
			)
		)
	)
	(zone
		(layer "In2.Cu")
		(hatch none 0.5)
		(connect_pads
			(clearance 0)
		)
		(min_thickness 0.25)
		(keepout
			(tracks not_allowed)
			(vias allowed)
			(pads allowed)
			(copperpour not_allowed)
			(footprints allowed)
		)
		(placement
			(enabled no)
			(sheetname "")
		)
		(fill
			(thermal_gap 0.5)
			(thermal_bridge_width 0.5)
			(island_removal_mode 0)
		)
		(polygon
			(pts
				(arc
					(start 405.341328 -11.91768)
					(mid 405.31901 -11.971562)
					(end 405.265128 -11.99388)
				)
				(arc
					(start 404.228554 -11.99388)
					(mid 404.174672 -11.971562)
					(end 404.152354 -11.91768)
				)
				(arc
					(start 404.152354 -10.51814)
					(mid 404.174672 -10.464258)
					(end 404.228554 -10.44194)
				)
				(arc
					(start 405.265128 -10.44194)
					(mid 405.31901 -10.464258)
					(end 405.341328 -10.51814)
				)
			)
		)
	)
	(zone
		(layer "In2.Cu")
		(hatch none 0.5)
		(connect_pads
			(clearance 0)
		)
		(min_thickness 0.25)
		(keepout
			(tracks not_allowed)
			(vias allowed)
			(pads allowed)
			(copperpour not_allowed)
			(footprints allowed)
		)
		(placement
			(enabled no)
			(sheetname "")
		)
		(fill
			(thermal_gap 0.5)
			(thermal_bridge_width 0.5)
			(island_removal_mode 0)
		)
		(polygon
			(pts
				(xy 51.134772 -204.72527) (xy 52.633372 -204.72527) (xy 52.633372 -205.245208) (xy 51.134772 -205.245208)
			)
		)
	)
	(zone
		(layer "In2.Cu")
		(hatch none 0.5)
		(connect_pads
			(clearance 0)
		)
		(min_thickness 0.25)
		(keepout
			(tracks not_allowed)
			(vias allowed)
			(pads allowed)
			(copperpour not_allowed)
			(footprints allowed)
		)
		(placement
			(enabled no)
			(sheetname "")
		)
		(fill
			(thermal_gap 0.5)
			(thermal_bridge_width 0.5)
			(island_removal_mode 0)
		)
		(polygon
			(pts
				(xy 441.7949 -294.825166) (xy 443.2935 -294.825166) (xy 443.2935 -295.345104) (xy 441.7949 -295.345104)
			)
		)
	)
	(zone
		(layer "In2.Cu")
		(hatch none 0.5)
		(connect_pads
			(clearance 0)
		)
		(min_thickness 0.25)
		(keepout
			(tracks not_allowed)
			(vias allowed)
			(pads allowed)
			(copperpour not_allowed)
			(footprints allowed)
		)
		(placement
			(enabled no)
			(sheetname "")
		)
		(fill
			(thermal_gap 0.5)
			(thermal_bridge_width 0.5)
			(island_removal_mode 0)
		)
		(polygon
			(pts
				(xy 193.854578 -314.375292) (xy 195.353178 -314.375292) (xy 195.353178 -314.89523) (xy 193.854578 -314.89523)
			)
		)
	)
	(zone
		(layer "In2.Cu")
		(hatch none 0.5)
		(connect_pads
			(clearance 0)
		)
		(min_thickness 0.25)
		(keepout
			(tracks not_allowed)
			(vias allowed)
			(pads allowed)
			(copperpour not_allowed)
			(footprints allowed)
		)
		(placement
			(enabled no)
			(sheetname "")
		)
		(fill
			(thermal_gap 0.5)
			(thermal_bridge_width 0.5)
			(island_removal_mode 0)
		)
		(polygon
			(pts
				(xy 167.778684 -279.525222) (xy 169.277284 -279.525222) (xy 169.277284 -280.04516) (xy 167.778684 -280.04516)
			)
		)
	)
	(zone
		(layer "In2.Cu")
		(hatch none 0.5)
		(connect_pads
			(clearance 0)
		)
		(min_thickness 0.25)
		(keepout
			(tracks not_allowed)
			(vias allowed)
			(pads allowed)
			(copperpour not_allowed)
			(footprints allowed)
		)
		(placement
			(enabled no)
			(sheetname "")
		)
		(fill
			(thermal_gap 0.5)
			(thermal_bridge_width 0.5)
			(island_removal_mode 0)
		)
		(polygon
			(pts
				(xy 302.518826 -242.97513) (xy 304.017426 -242.97513) (xy 304.017426 -243.495068) (xy 302.518826 -243.495068)
			)
		)
	)
	(zone
		(layer "In2.Cu")
		(hatch none 0.5)
		(connect_pads
			(clearance 0)
		)
		(min_thickness 0.25)
		(keepout
			(tracks not_allowed)
			(vias allowed)
			(pads allowed)
			(copperpour not_allowed)
			(footprints allowed)
		)
		(placement
			(enabled no)
			(sheetname "")
		)
		(fill
			(thermal_gap 0.5)
			(thermal_bridge_width 0.5)
			(island_removal_mode 0)
		)
		(polygon
			(pts
				(xy 47.034704 -220.025214) (xy 48.533304 -220.025214) (xy 48.533304 -220.545152) (xy 47.034704 -220.545152)
			)
		)
	)
	(zone
		(layer "In2.Cu")
		(hatch none 0.5)
		(connect_pads
			(clearance 0)
		)
		(min_thickness 0.25)
		(keepout
			(tracks not_allowed)
			(vias allowed)
			(pads allowed)
			(copperpour not_allowed)
			(footprints allowed)
		)
		(placement
			(enabled no)
			(sheetname "")
		)
		(fill
			(thermal_gap 0.5)
			(thermal_bridge_width 0.5)
			(island_removal_mode 0)
		)
		(polygon
			(pts
				(xy 453.438768 -197.075298) (xy 454.937368 -197.075298) (xy 454.937368 -197.595236) (xy 453.438768 -197.595236)
			)
		)
	)
	(zone
		(layer "In2.Cu")
		(hatch none 0.5)
		(connect_pads
			(clearance 0)
		)
		(min_thickness 0.25)
		(keepout
			(tracks not_allowed)
			(vias allowed)
			(pads allowed)
			(copperpour not_allowed)
			(footprints allowed)
		)
		(placement
			(enabled no)
			(sheetname "")
		)
		(fill
			(thermal_gap 0.5)
			(thermal_bridge_width 0.5)
			(island_removal_mode 0)
		)
		(polygon
			(pts
				(xy 426.706792 -207.275176) (xy 428.205392 -207.275176) (xy 428.205392 -207.795114) (xy 426.706792 -207.795114)
			)
		)
	)
	(zone
		(layer "In2.Cu")
		(hatch none 0.5)
		(connect_pads
			(clearance 0)
		)
		(min_thickness 0.25)
		(keepout
			(tracks not_allowed)
			(vias allowed)
			(pads allowed)
			(copperpour not_allowed)
			(footprints allowed)
		)
		(placement
			(enabled no)
			(sheetname "")
		)
		(fill
			(thermal_gap 0.5)
			(thermal_bridge_width 0.5)
			(island_removal_mode 0)
		)
		(polygon
			(pts
				(xy 201.398632 -302.475138) (xy 202.897232 -302.475138) (xy 202.897232 -302.995076) (xy 201.398632 -302.995076)
			)
		)
	)
	(zone
		(layer "In2.Cu")
		(hatch none 0.5)
		(connect_pads
			(clearance 0)
		)
		(min_thickness 0.25)
		(keepout
			(tracks not_allowed)
			(vias allowed)
			(pads allowed)
			(copperpour not_allowed)
			(footprints allowed)
		)
		(placement
			(enabled no)
			(sheetname "")
		)
		(fill
			(thermal_gap 0.5)
			(thermal_bridge_width 0.5)
			(island_removal_mode 0)
		)
		(polygon
			(pts
				(xy 453.438768 -284.625288) (xy 454.937368 -284.625288) (xy 454.937368 -285.145226) (xy 453.438768 -285.145226)
			)
		)
	)
	(zone
		(layer "In2.Cu")
		(hatch none 0.5)
		(connect_pads
			(clearance 0)
		)
		(min_thickness 0.25)
		(keepout
			(tracks not_allowed)
			(vias allowed)
			(pads allowed)
			(copperpour not_allowed)
			(footprints allowed)
		)
		(placement
			(enabled no)
			(sheetname "")
		)
		(fill
			(thermal_gap 0.5)
			(thermal_bridge_width 0.5)
			(island_removal_mode 0)
		)
		(polygon
			(pts
				(xy 449.3387 -254.025146) (xy 450.8373 -254.025146) (xy 450.8373 -254.545084) (xy 449.3387 -254.545084)
			)
		)
	)
	(zone
		(layer "In2.Cu")
		(hatch none 0.5)
		(connect_pads
			(clearance 0)
		)
		(min_thickness 0.25)
		(keepout
			(tracks not_allowed)
			(vias allowed)
			(pads allowed)
			(copperpour not_allowed)
			(footprints allowed)
		)
		(placement
			(enabled no)
			(sheetname "")
		)
		(fill
			(thermal_gap 0.5)
			(thermal_bridge_width 0.5)
			(island_removal_mode 0)
		)
		(polygon
			(pts
				(xy 268.898878 -305.875182) (xy 270.397478 -305.875182) (xy 270.397478 -306.39512) (xy 268.898878 -306.39512)
			)
		)
	)
	(zone
		(layer "In2.Cu")
		(hatch none 0.5)
		(connect_pads
			(clearance 0)
		)
		(min_thickness 0.25)
		(keepout
			(tracks not_allowed)
			(vias allowed)
			(pads allowed)
			(copperpour not_allowed)
			(footprints allowed)
		)
		(placement
			(enabled no)
			(sheetname "")
		)
		(fill
			(thermal_gap 0.5)
			(thermal_bridge_width 0.5)
			(island_removal_mode 0)
		)
		(polygon
			(pts
				(xy 197.954646 -275.275294) (xy 199.453246 -275.275294) (xy 199.453246 -275.795232) (xy 197.954646 -275.795232)
			)
		)
	)
	(zone
		(layer "In2.Cu")
		(hatch none 0.5)
		(connect_pads
			(clearance 0)
		)
		(min_thickness 0.25)
		(keepout
			(tracks not_allowed)
			(vias allowed)
			(pads allowed)
			(copperpour not_allowed)
			(footprints allowed)
		)
		(placement
			(enabled no)
			(sheetname "")
		)
		(fill
			(thermal_gap 0.5)
			(thermal_bridge_width 0.5)
			(island_removal_mode 0)
		)
		(polygon
			(pts
				(xy 291.530786 -313.525154) (xy 293.029386 -313.525154) (xy 293.029386 -314.045092) (xy 291.530786 -314.045092)
			)
		)
	)
	(zone
		(layer "In2.Cu")
		(hatch none 0.5)
		(connect_pads
			(clearance 0)
		)
		(min_thickness 0.25)
		(keepout
			(tracks not_allowed)
			(vias allowed)
			(pads allowed)
			(copperpour not_allowed)
			(footprints allowed)
		)
		(placement
			(enabled no)
			(sheetname "")
		)
		(fill
			(thermal_gap 0.5)
			(thermal_bridge_width 0.5)
			(island_removal_mode 0)
		)
		(polygon
			(pts
				(xy 268.898878 -296.525188) (xy 270.397478 -296.525188) (xy 270.397478 -297.045126) (xy 268.898878 -297.045126)
			)
		)
	)
	(zone
		(layer "In2.Cu")
		(hatch none 0.5)
		(connect_pads
			(clearance 0)
		)
		(min_thickness 0.25)
		(keepout
			(tracks not_allowed)
			(vias allowed)
			(pads allowed)
			(copperpour not_allowed)
			(footprints allowed)
		)
		(placement
			(enabled no)
			(sheetname "")
		)
		(fill
			(thermal_gap 0.5)
			(thermal_bridge_width 0.5)
			(island_removal_mode 0)
		)
		(polygon
			(pts
				(xy 175.322738 -203.025248) (xy 176.821338 -203.025248) (xy 176.821338 -203.545186) (xy 175.322738 -203.545186)
			)
		)
	)
	(zone
		(layer "In2.Cu")
		(hatch none 0.5)
		(connect_pads
			(clearance 0)
		)
		(min_thickness 0.25)
		(keepout
			(tracks not_allowed)
			(vias allowed)
			(pads allowed)
			(copperpour not_allowed)
			(footprints allowed)
		)
		(placement
			(enabled no)
			(sheetname "")
		)
		(fill
			(thermal_gap 0.5)
			(thermal_bridge_width 0.5)
			(island_removal_mode 0)
		)
		(polygon
			(pts
				(xy 411.618684 -314.375292) (xy 413.117284 -314.375292) (xy 413.117284 -314.89523) (xy 411.618684 -314.89523)
			)
		)
	)
	(zone
		(layer "In2.Cu")
		(hatch none 0.5)
		(connect_pads
			(clearance 0)
		)
		(min_thickness 0.25)
		(keepout
			(tracks not_allowed)
			(vias allowed)
			(pads allowed)
			(copperpour not_allowed)
			(footprints allowed)
		)
		(placement
			(enabled no)
			(sheetname "")
		)
		(fill
			(thermal_gap 0.5)
			(thermal_bridge_width 0.5)
			(island_removal_mode 0)
		)
		(polygon
			(pts
				(xy 445.894968 -303.325276) (xy 447.393568 -303.325276) (xy 447.393568 -303.845214) (xy 445.894968 -303.845214)
			)
		)
	)
	(zone
		(layer "In2.Cu")
		(hatch none 0.5)
		(connect_pads
			(clearance 0)
		)
		(min_thickness 0.25)
		(keepout
			(tracks not_allowed)
			(vias allowed)
			(pads allowed)
			(copperpour not_allowed)
			(footprints allowed)
		)
		(placement
			(enabled no)
			(sheetname "")
		)
		(fill
			(thermal_gap 0.5)
			(thermal_bridge_width 0.5)
			(island_removal_mode 0)
		)
		(polygon
			(pts
				(xy 20.95881 -240.425224) (xy 22.45741 -240.425224) (xy 22.45741 -240.945162) (xy 20.95881 -240.945162)
			)
		)
	)
	(zone
		(layer "In2.Cu")
		(hatch none 0.5)
		(connect_pads
			(clearance 0)
		)
		(min_thickness 0.25)
		(keepout
			(tracks not_allowed)
			(vias allowed)
			(pads allowed)
			(copperpour not_allowed)
			(footprints allowed)
		)
		(placement
			(enabled no)
			(sheetname "")
		)
		(fill
			(thermal_gap 0.5)
			(thermal_bridge_width 0.5)
			(island_removal_mode 0)
		)
		(polygon
			(pts
				(xy 268.898878 -252.325124) (xy 270.397478 -252.325124) (xy 270.397478 -252.845062) (xy 268.898878 -252.845062)
			)
		)
	)
	(zone
		(layer "In2.Cu")
		(hatch none 0.5)
		(connect_pads
			(clearance 0)
		)
		(min_thickness 0.25)
		(keepout
			(tracks not_allowed)
			(vias allowed)
			(pads allowed)
			(copperpour not_allowed)
			(footprints allowed)
		)
		(placement
			(enabled no)
			(sheetname "")
		)
		(fill
			(thermal_gap 0.5)
			(thermal_bridge_width 0.5)
			(island_removal_mode 0)
		)
		(polygon
			(pts
				(xy 411.618684 -248.075196) (xy 413.117284 -248.075196) (xy 413.117284 -248.595134) (xy 411.618684 -248.595134)
			)
		)
	)
	(zone
		(layer "In2.Cu")
		(hatch none 0.5)
		(connect_pads
			(clearance 0)
		)
		(min_thickness 0.25)
		(keepout
			(tracks not_allowed)
			(vias allowed)
			(pads allowed)
			(copperpour not_allowed)
			(footprints allowed)
		)
		(placement
			(enabled no)
			(sheetname "")
		)
		(fill
			(thermal_gap 0.5)
			(thermal_bridge_width 0.5)
			(island_removal_mode 0)
		)
		(polygon
			(pts
				(xy 190.410846 -210.67522) (xy 191.909446 -210.67522) (xy 191.909446 -211.195158) (xy 190.410846 -211.195158)
			)
		)
	)
	(zone
		(layer "In2.Cu")
		(hatch none 0.5)
		(connect_pads
			(clearance 0)
		)
		(min_thickness 0.25)
		(keepout
			(tracks not_allowed)
			(vias allowed)
			(pads allowed)
			(copperpour not_allowed)
			(footprints allowed)
		)
		(placement
			(enabled no)
			(sheetname "")
		)
		(fill
			(thermal_gap 0.5)
			(thermal_bridge_width 0.5)
			(island_removal_mode 0)
		)
		(polygon
			(pts
				(xy 294.974772 -306.72532) (xy 296.473372 -306.72532) (xy 296.473372 -307.245258) (xy 294.974772 -307.245258)
			)
		)
	)
	(zone
		(layer "In2.Cu")
		(hatch none 0.5)
		(connect_pads
			(clearance 0)
		)
		(min_thickness 0.25)
		(keepout
			(tracks not_allowed)
			(vias allowed)
			(pads allowed)
			(copperpour not_allowed)
			(footprints allowed)
		)
		(placement
			(enabled no)
			(sheetname "")
		)
		(fill
			(thermal_gap 0.5)
			(thermal_bridge_width 0.5)
			(island_removal_mode 0)
		)
		(polygon
			(pts
				(xy 272.342864 -286.32531) (xy 273.841464 -286.32531) (xy 273.841464 -286.845248) (xy 272.342864 -286.845248)
			)
		)
	)
	(zone
		(layer "In2.Cu")
		(hatch none 0.5)
		(connect_pads
			(clearance 0)
		)
		(min_thickness 0.25)
		(keepout
			(tracks not_allowed)
			(vias allowed)
			(pads allowed)
			(copperpour not_allowed)
			(footprints allowed)
		)
		(placement
			(enabled no)
			(sheetname "")
		)
		(fill
			(thermal_gap 0.5)
			(thermal_bridge_width 0.5)
			(island_removal_mode 0)
		)
		(polygon
			(pts
				(xy 190.410846 -200.475342) (xy 191.909446 -200.475342) (xy 191.909446 -200.99528) (xy 190.410846 -200.99528)
			)
		)
	)
	(zone
		(layer "In2.Cu")
		(hatch none 0.5)
		(connect_pads
			(clearance 0)
		)
		(min_thickness 0.25)
		(keepout
			(tracks not_allowed)
			(vias allowed)
			(pads allowed)
			(copperpour not_allowed)
			(footprints allowed)
		)
		(placement
			(enabled no)
			(sheetname "")
		)
		(fill
			(thermal_gap 0.5)
			(thermal_bridge_width 0.5)
			(island_removal_mode 0)
		)
		(polygon
			(pts
				(xy 186.310778 -265.075162) (xy 187.809378 -265.075162) (xy 187.809378 -265.5951) (xy 186.310778 -265.5951)
			)
		)
	)
	(zone
		(layer "In2.Cu")
		(hatch none 0.5)
		(connect_pads
			(clearance 0)
		)
		(min_thickness 0.25)
		(keepout
			(tracks not_allowed)
			(vias allowed)
			(pads allowed)
			(copperpour not_allowed)
			(footprints allowed)
		)
		(placement
			(enabled no)
			(sheetname "")
		)
		(fill
			(thermal_gap 0.5)
			(thermal_bridge_width 0.5)
			(island_removal_mode 0)
		)
		(polygon
			(pts
				(xy 449.3387 -316.075314) (xy 450.8373 -316.075314) (xy 450.8373 -316.595252) (xy 449.3387 -316.595252)
			)
		)
	)
	(zone
		(layer "In2.Cu")
		(hatch none 0.5)
		(connect_pads
			(clearance 0)
		)
		(min_thickness 0.25)
		(keepout
			(tracks not_allowed)
			(vias allowed)
			(pads allowed)
			(copperpour not_allowed)
			(footprints allowed)
		)
		(placement
			(enabled no)
			(sheetname "")
		)
		(fill
			(thermal_gap 0.5)
			(thermal_bridge_width 0.5)
			(island_removal_mode 0)
		)
		(polygon
			(pts
				(xy 47.034704 -213.225126) (xy 48.533304 -213.225126) (xy 48.533304 -213.745064) (xy 47.034704 -213.745064)
			)
		)
	)
	(zone
		(layer "In2.Cu")
		(hatch none 0.5)
		(connect_pads
			(clearance 0)
		)
		(min_thickness 0.25)
		(keepout
			(tracks not_allowed)
			(vias allowed)
			(pads allowed)
			(copperpour not_allowed)
			(footprints allowed)
		)
		(placement
			(enabled no)
			(sheetname "")
		)
		(fill
			(thermal_gap 0.5)
			(thermal_bridge_width 0.5)
			(island_removal_mode 0)
		)
		(polygon
			(pts
				(xy 441.7949 -197.925182) (xy 443.2935 -197.925182) (xy 443.2935 -198.44512) (xy 441.7949 -198.44512)
			)
		)
	)
	(zone
		(layer "In2.Cu")
		(hatch none 0.5)
		(connect_pads
			(clearance 0)
		)
		(min_thickness 0.25)
		(keepout
			(tracks not_allowed)
			(vias allowed)
			(pads allowed)
			(copperpour not_allowed)
			(footprints allowed)
		)
		(placement
			(enabled no)
			(sheetname "")
		)
		(fill
			(thermal_gap 0.5)
			(thermal_bridge_width 0.5)
			(island_removal_mode 0)
		)
		(polygon
			(pts
				(xy 47.034704 -311.825132) (xy 48.533304 -311.825132) (xy 48.533304 -312.34507) (xy 47.034704 -312.34507)
			)
		)
	)
	(zone
		(layer "In2.Cu")
		(hatch none 0.5)
		(connect_pads
			(clearance 0)
		)
		(min_thickness 0.25)
		(keepout
			(tracks not_allowed)
			(vias allowed)
			(pads allowed)
			(copperpour not_allowed)
			(footprints allowed)
		)
		(placement
			(enabled no)
			(sheetname "")
		)
		(fill
			(thermal_gap 0.5)
			(thermal_bridge_width 0.5)
			(island_removal_mode 0)
		)
		(polygon
			(pts
				(xy 299.07484 -284.625288) (xy 300.57344 -284.625288) (xy 300.57344 -285.145226) (xy 299.07484 -285.145226)
			)
		)
	)
	(zone
		(layer "In2.Cu")
		(hatch none 0.5)
		(connect_pads
			(clearance 0)
		)
		(min_thickness 0.25)
		(keepout
			(tracks not_allowed)
			(vias allowed)
			(pads allowed)
			(copperpour not_allowed)
			(footprints allowed)
		)
		(placement
			(enabled no)
			(sheetname "")
		)
		(fill
			(thermal_gap 0.5)
			(thermal_bridge_width 0.5)
			(island_removal_mode 0)
		)
		(polygon
			(pts
				(xy 24.402542 -225.975164) (xy 25.901142 -225.975164) (xy 25.901142 -226.495102) (xy 24.402542 -226.495102)
			)
		)
	)
	(zone
		(layer "In2.Cu")
		(hatch none 0.5)
		(connect_pads
			(clearance 0)
		)
		(min_thickness 0.25)
		(keepout
			(tracks not_allowed)
			(vias allowed)
			(pads allowed)
			(copperpour not_allowed)
			(footprints allowed)
		)
		(placement
			(enabled no)
			(sheetname "")
		)
		(fill
			(thermal_gap 0.5)
			(thermal_bridge_width 0.5)
			(island_removal_mode 0)
		)
		(polygon
			(pts
				(xy 197.954646 -203.025248) (xy 199.453246 -203.025248) (xy 199.453246 -203.545186) (xy 197.954646 -203.545186)
			)
		)
	)
	(zone
		(layer "In2.Cu")
		(hatch none 0.5)
		(connect_pads
			(clearance 0)
		)
		(min_thickness 0.25)
		(keepout
			(tracks not_allowed)
			(vias allowed)
			(pads allowed)
			(copperpour not_allowed)
			(footprints allowed)
		)
		(placement
			(enabled no)
			(sheetname "")
		)
		(fill
			(thermal_gap 0.5)
			(thermal_bridge_width 0.5)
			(island_removal_mode 0)
		)
		(polygon
			(pts
				(xy 411.618684 -263.37514) (xy 413.117284 -263.37514) (xy 413.117284 -263.895078) (xy 411.618684 -263.895078)
			)
		)
	)
	(zone
		(layer "In2.Cu")
		(hatch none 0.5)
		(connect_pads
			(clearance 0)
		)
		(min_thickness 0.25)
		(keepout
			(tracks not_allowed)
			(vias allowed)
			(pads allowed)
			(copperpour not_allowed)
			(footprints allowed)
		)
		(placement
			(enabled no)
			(sheetname "")
		)
		(fill
			(thermal_gap 0.5)
			(thermal_bridge_width 0.5)
			(island_removal_mode 0)
		)
		(polygon
			(pts
				(arc
					(start 321.906646 -379.360684)
					(mid 321.92657 -379.36992)
					(end 321.948302 -379.37313)
				)
				(arc
					(start 322.142866 -379.37313)
					(mid 322.196748 -379.350812)
					(end 322.219066 -379.29693)
				)
				(arc
					(start 322.219066 -378.61113)
					(mid 322.196748 -378.557248)
					(end 322.142866 -378.53493)
				)
				(arc
					(start 321.948302 -378.53493)
					(mid 321.926558 -378.538098)
					(end 321.906646 -378.547376)
				)
				(arc
					(start 321.610482 -378.740162)
					(mid 321.568798 -378.752384)
					(end 321.52717 -378.739908)
				)
				(arc
					(start 321.233546 -378.547376)
					(mid 321.213622 -378.53814)
					(end 321.19189 -378.53493)
				)
				(arc
					(start 320.997326 -378.53493)
					(mid 320.943444 -378.557248)
					(end 320.921126 -378.61113)
				)
				(arc
					(start 320.921126 -379.29693)
					(mid 320.943444 -379.350812)
					(end 320.997326 -379.37313)
				)
				(arc
					(start 321.19316 -379.37313)
					(mid 321.214904 -379.369962)
					(end 321.234816 -379.360684)
				)
				(arc
					(start 321.52844 -379.168152)
					(mid 321.570096 -379.15575)
					(end 321.611752 -379.168152)
				)
			)
		)
	)
	(zone
		(layer "In2.Cu")
		(hatch none 0.5)
		(connect_pads
			(clearance 0)
		)
		(min_thickness 0.25)
		(keepout
			(tracks not_allowed)
			(vias allowed)
			(pads allowed)
			(copperpour not_allowed)
			(footprints allowed)
		)
		(placement
			(enabled no)
			(sheetname "")
		)
		(fill
			(thermal_gap 0.5)
			(thermal_bridge_width 0.5)
			(island_removal_mode 0)
		)
		(polygon
			(pts
				(xy 283.986732 -243.825268) (xy 285.485332 -243.825268) (xy 285.485332 -244.345206) (xy 283.986732 -244.345206)
			)
		)
	)
	(zone
		(layer "In2.Cu")
		(hatch none 0.5)
		(connect_pads
			(clearance 0)
		)
		(min_thickness 0.25)
		(keepout
			(tracks not_allowed)
			(vias allowed)
			(pads allowed)
			(copperpour not_allowed)
			(footprints allowed)
		)
		(placement
			(enabled no)
			(sheetname "")
		)
		(fill
			(thermal_gap 0.5)
			(thermal_bridge_width 0.5)
			(island_removal_mode 0)
		)
		(polygon
			(pts
				(xy 20.95881 -275.275294) (xy 22.45741 -275.275294) (xy 22.45741 -275.795232) (xy 20.95881 -275.795232)
			)
		)
	)
	(zone
		(layer "In2.Cu")
		(hatch none 0.5)
		(connect_pads
			(clearance 0)
		)
		(min_thickness 0.25)
		(keepout
			(tracks not_allowed)
			(vias allowed)
			(pads allowed)
			(copperpour not_allowed)
			(footprints allowed)
		)
		(placement
			(enabled no)
			(sheetname "")
		)
		(fill
			(thermal_gap 0.5)
			(thermal_bridge_width 0.5)
			(island_removal_mode 0)
		)
		(polygon
			(pts
				(xy 283.986732 -315.225176) (xy 285.485332 -315.225176) (xy 285.485332 -315.745114) (xy 283.986732 -315.745114)
			)
		)
	)
	(zone
		(layer "In2.Cu")
		(hatch none 0.5)
		(connect_pads
			(clearance 0)
		)
		(min_thickness 0.25)
		(keepout
			(tracks not_allowed)
			(vias allowed)
			(pads allowed)
			(copperpour not_allowed)
			(footprints allowed)
		)
		(placement
			(enabled no)
			(sheetname "")
		)
		(fill
			(thermal_gap 0.5)
			(thermal_bridge_width 0.5)
			(island_removal_mode 0)
		)
		(polygon
			(pts
				(xy 36.046664 -240.425224) (xy 37.545264 -240.425224) (xy 37.545264 -240.945162) (xy 36.046664 -240.945162)
			)
		)
	)
	(zone
		(layer "In2.Cu")
		(hatch none 0.5)
		(connect_pads
			(clearance 0)
		)
		(min_thickness 0.25)
		(keepout
			(tracks not_allowed)
			(vias allowed)
			(pads allowed)
			(copperpour not_allowed)
			(footprints allowed)
		)
		(placement
			(enabled no)
			(sheetname "")
		)
		(fill
			(thermal_gap 0.5)
			(thermal_bridge_width 0.5)
			(island_removal_mode 0)
		)
		(polygon
			(pts
				(xy 294.974772 -282.075128) (xy 296.473372 -282.075128) (xy 296.473372 -282.595066) (xy 294.974772 -282.595066)
			)
		)
	)
	(zone
		(layer "In2.Cu")
		(hatch none 0.5)
		(connect_pads
			(clearance 0)
		)
		(min_thickness 0.25)
		(keepout
			(tracks not_allowed)
			(vias allowed)
			(pads allowed)
			(copperpour not_allowed)
			(footprints allowed)
		)
		(placement
			(enabled no)
			(sheetname "")
		)
		(fill
			(thermal_gap 0.5)
			(thermal_bridge_width 0.5)
			(island_removal_mode 0)
		)
		(polygon
			(pts
				(xy 163.678616 -310.12511) (xy 165.177216 -310.12511) (xy 165.177216 -310.645048) (xy 163.678616 -310.645048)
			)
		)
	)
	(zone
		(layer "In2.Cu")
		(hatch none 0.5)
		(connect_pads
			(clearance 0)
		)
		(min_thickness 0.25)
		(keepout
			(tracks not_allowed)
			(vias allowed)
			(pads allowed)
			(copperpour not_allowed)
			(footprints allowed)
		)
		(placement
			(enabled no)
			(sheetname "")
		)
		(fill
			(thermal_gap 0.5)
			(thermal_bridge_width 0.5)
			(island_removal_mode 0)
		)
		(polygon
			(pts
				(xy 299.07484 -312.67527) (xy 300.57344 -312.67527) (xy 300.57344 -313.195208) (xy 299.07484 -313.195208)
			)
		)
	)
	(zone
		(layer "In2.Cu")
		(hatch none 0.5)
		(connect_pads
			(clearance 0)
		)
		(min_thickness 0.25)
		(keepout
			(tracks not_allowed)
			(vias allowed)
			(pads allowed)
			(copperpour not_allowed)
			(footprints allowed)
		)
		(placement
			(enabled no)
			(sheetname "")
		)
		(fill
			(thermal_gap 0.5)
			(thermal_bridge_width 0.5)
			(island_removal_mode 0)
		)
		(polygon
			(pts
				(xy 16.858742 -282.075128) (xy 18.357342 -282.075128) (xy 18.357342 -282.595066) (xy 16.858742 -282.595066)
			)
		)
	)
	(zone
		(layer "In2.Cu")
		(hatch none 0.5)
		(connect_pads
			(clearance 0)
		)
		(min_thickness 0.25)
		(keepout
			(tracks not_allowed)
			(vias allowed)
			(pads allowed)
			(copperpour not_allowed)
			(footprints allowed)
		)
		(placement
			(enabled no)
			(sheetname "")
		)
		(fill
			(thermal_gap 0.5)
			(thermal_bridge_width 0.5)
			(island_removal_mode 0)
		)
		(polygon
			(pts
				(xy 426.706792 -233.625136) (xy 428.205392 -233.625136) (xy 428.205392 -234.145074) (xy 426.706792 -234.145074)
			)
		)
	)
	(zone
		(layer "In2.Cu")
		(hatch none 0.5)
		(connect_pads
			(clearance 0)
		)
		(min_thickness 0.25)
		(keepout
			(tracks not_allowed)
			(vias allowed)
			(pads allowed)
			(copperpour not_allowed)
			(footprints allowed)
		)
		(placement
			(enabled no)
			(sheetname "")
		)
		(fill
			(thermal_gap 0.5)
			(thermal_bridge_width 0.5)
			(island_removal_mode 0)
		)
		(polygon
			(pts
				(xy 430.80686 -310.975248) (xy 432.30546 -310.975248) (xy 432.30546 -311.495186) (xy 430.80686 -311.495186)
			)
		)
	)
	(zone
		(layer "In2.Cu")
		(hatch none 0.5)
		(connect_pads
			(clearance 0)
		)
		(min_thickness 0.25)
		(keepout
			(tracks not_allowed)
			(vias allowed)
			(pads allowed)
			(copperpour not_allowed)
			(footprints allowed)
		)
		(placement
			(enabled no)
			(sheetname "")
		)
		(fill
			(thermal_gap 0.5)
			(thermal_bridge_width 0.5)
			(island_removal_mode 0)
		)
		(polygon
			(pts
				(xy 28.50261 -269.325344) (xy 30.00121 -269.325344) (xy 30.00121 -269.845282) (xy 28.50261 -269.845282)
			)
		)
	)
	(zone
		(layer "In2.Cu")
		(hatch none 0.5)
		(connect_pads
			(clearance 0)
		)
		(min_thickness 0.25)
		(keepout
			(tracks not_allowed)
			(vias allowed)
			(pads allowed)
			(copperpour not_allowed)
			(footprints allowed)
		)
		(placement
			(enabled no)
			(sheetname "")
		)
		(fill
			(thermal_gap 0.5)
			(thermal_bridge_width 0.5)
			(island_removal_mode 0)
		)
		(polygon
			(pts
				(xy 302.518826 -268.475206) (xy 304.017426 -268.475206) (xy 304.017426 -268.995144) (xy 302.518826 -268.995144)
			)
		)
	)
	(zone
		(layer "In2.Cu")
		(hatch none 0.5)
		(connect_pads
			(clearance 0)
		)
		(min_thickness 0.25)
		(keepout
			(tracks not_allowed)
			(vias allowed)
			(pads allowed)
			(copperpour not_allowed)
			(footprints allowed)
		)
		(placement
			(enabled no)
			(sheetname "")
		)
		(fill
			(thermal_gap 0.5)
			(thermal_bridge_width 0.5)
			(island_removal_mode 0)
		)
		(polygon
			(pts
				(xy 441.7949 -293.125144) (xy 443.2935 -293.125144) (xy 443.2935 -293.645082) (xy 441.7949 -293.645082)
			)
		)
	)
	(zone
		(layer "In2.Cu")
		(hatch none 0.5)
		(connect_pads
			(clearance 0)
		)
		(min_thickness 0.25)
		(keepout
			(tracks not_allowed)
			(vias allowed)
			(pads allowed)
			(copperpour not_allowed)
			(footprints allowed)
		)
		(placement
			(enabled no)
			(sheetname "")
		)
		(fill
			(thermal_gap 0.5)
			(thermal_bridge_width 0.5)
			(island_removal_mode 0)
		)
		(polygon
			(pts
				(xy 167.778684 -232.775252) (xy 169.277284 -232.775252) (xy 169.277284 -233.29519) (xy 167.778684 -233.29519)
			)
		)
	)
	(zone
		(layer "In2.Cu")
		(hatch none 0.5)
		(connect_pads
			(clearance 0)
		)
		(min_thickness 0.25)
		(keepout
			(tracks not_allowed)
			(vias allowed)
			(pads allowed)
			(copperpour not_allowed)
			(footprints allowed)
		)
		(placement
			(enabled no)
			(sheetname "")
		)
		(fill
			(thermal_gap 0.5)
			(thermal_bridge_width 0.5)
			(island_removal_mode 0)
		)
		(polygon
			(pts
				(xy 186.310778 -310.12511) (xy 187.809378 -310.12511) (xy 187.809378 -310.645048) (xy 186.310778 -310.645048)
			)
		)
	)
	(zone
		(layer "In2.Cu")
		(hatch none 0.5)
		(connect_pads
			(clearance 0)
		)
		(min_thickness 0.25)
		(keepout
			(tracks not_allowed)
			(vias allowed)
			(pads allowed)
			(copperpour not_allowed)
			(footprints allowed)
		)
		(placement
			(enabled no)
			(sheetname "")
		)
		(fill
			(thermal_gap 0.5)
			(thermal_bridge_width 0.5)
			(island_removal_mode 0)
		)
		(polygon
			(pts
				(xy 430.80686 -305.875182) (xy 432.30546 -305.875182) (xy 432.30546 -306.39512) (xy 430.80686 -306.39512)
			)
		)
	)
	(zone
		(layer "In2.Cu")
		(hatch none 0.5)
		(connect_pads
			(clearance 0)
		)
		(min_thickness 0.25)
		(keepout
			(tracks not_allowed)
			(vias allowed)
			(pads allowed)
			(copperpour not_allowed)
			(footprints allowed)
		)
		(placement
			(enabled no)
			(sheetname "")
		)
		(fill
			(thermal_gap 0.5)
			(thermal_bridge_width 0.5)
			(island_removal_mode 0)
		)
		(polygon
			(pts
				(xy 20.95881 -237.875318) (xy 22.45741 -237.875318) (xy 22.45741 -238.395256) (xy 20.95881 -238.395256)
			)
		)
	)
	(zone
		(layer "In2.Cu")
		(hatch none 0.5)
		(connect_pads
			(clearance 0)
		)
		(min_thickness 0.25)
		(keepout
			(tracks not_allowed)
			(vias allowed)
			(pads allowed)
			(copperpour not_allowed)
			(footprints allowed)
		)
		(placement
			(enabled no)
			(sheetname "")
		)
		(fill
			(thermal_gap 0.5)
			(thermal_bridge_width 0.5)
			(island_removal_mode 0)
		)
		(polygon
			(pts
				(xy 171.22267 -246.375174) (xy 172.72127 -246.375174) (xy 172.72127 -246.895112) (xy 171.22267 -246.895112)
			)
		)
	)
	(zone
		(layer "In2.Cu")
		(hatch none 0.5)
		(connect_pads
			(clearance 0)
		)
		(min_thickness 0.25)
		(keepout
			(tracks not_allowed)
			(vias allowed)
			(pads allowed)
			(copperpour not_allowed)
			(footprints allowed)
		)
		(placement
			(enabled no)
			(sheetname "")
		)
		(fill
			(thermal_gap 0.5)
			(thermal_bridge_width 0.5)
			(island_removal_mode 0)
		)
		(polygon
			(pts
				(xy 175.322738 -217.475308) (xy 176.821338 -217.475308) (xy 176.821338 -217.995246) (xy 175.322738 -217.995246)
			)
		)
	)
	(zone
		(layer "In2.Cu")
		(hatch none 0.5)
		(connect_pads
			(clearance 0)
		)
		(min_thickness 0.25)
		(keepout
			(tracks not_allowed)
			(vias allowed)
			(pads allowed)
			(copperpour not_allowed)
			(footprints allowed)
		)
		(placement
			(enabled no)
			(sheetname "")
		)
		(fill
			(thermal_gap 0.5)
			(thermal_bridge_width 0.5)
			(island_removal_mode 0)
		)
		(polygon
			(pts
				(xy 171.22267 -201.325226) (xy 172.72127 -201.325226) (xy 172.72127 -201.845164) (xy 171.22267 -201.845164)
			)
		)
	)
	(zone
		(layer "In2.Cu")
		(hatch none 0.5)
		(connect_pads
			(clearance 0)
		)
		(min_thickness 0.25)
		(keepout
			(tracks not_allowed)
			(vias allowed)
			(pads allowed)
			(copperpour not_allowed)
			(footprints allowed)
		)
		(placement
			(enabled no)
			(sheetname "")
		)
		(fill
			(thermal_gap 0.5)
			(thermal_bridge_width 0.5)
			(island_removal_mode 0)
		)
		(polygon
			(pts
				(arc
					(start 53.57241 -7.672324)
					(mid 53.594728 -7.618442)
					(end 53.64861 -7.596124)
				)
				(arc
					(start 54.685184 -7.596124)
					(mid 54.739066 -7.618442)
					(end 54.761384 -7.672324)
				)
				(arc
					(start 54.761384 -9.071864)
					(mid 54.739066 -9.125746)
					(end 54.685184 -9.148064)
				)
				(arc
					(start 53.64861 -9.148064)
					(mid 53.594728 -9.125746)
					(end 53.57241 -9.071864)
				)
			)
		)
	)
	(zone
		(layer "In2.Cu")
		(hatch none 0.5)
		(connect_pads
			(clearance 0)
		)
		(min_thickness 0.25)
		(keepout
			(tracks not_allowed)
			(vias allowed)
			(pads allowed)
			(copperpour not_allowed)
			(footprints allowed)
		)
		(placement
			(enabled no)
			(sheetname "")
		)
		(fill
			(thermal_gap 0.5)
			(thermal_bridge_width 0.5)
			(island_removal_mode 0)
		)
		(polygon
			(pts
				(xy 445.894968 -201.325226) (xy 447.393568 -201.325226) (xy 447.393568 -201.845164) (xy 445.894968 -201.845164)
			)
		)
	)
	(zone
		(layer "In2.Cu")
		(hatch none 0.5)
		(connect_pads
			(clearance 0)
		)
		(min_thickness 0.25)
		(keepout
			(tracks not_allowed)
			(vias allowed)
			(pads allowed)
			(copperpour not_allowed)
			(footprints allowed)
		)
		(placement
			(enabled no)
			(sheetname "")
		)
		(fill
			(thermal_gap 0.5)
			(thermal_bridge_width 0.5)
			(island_removal_mode 0)
		)
		(polygon
			(pts
				(xy 175.322738 -243.825268) (xy 176.821338 -243.825268) (xy 176.821338 -244.345206) (xy 175.322738 -244.345206)
			)
		)
	)
	(zone
		(layer "In2.Cu")
		(hatch none 0.5)
		(connect_pads
			(clearance 0)
		)
		(min_thickness 0.25)
		(keepout
			(tracks not_allowed)
			(vias allowed)
			(pads allowed)
			(copperpour not_allowed)
			(footprints allowed)
		)
		(placement
			(enabled no)
			(sheetname "")
		)
		(fill
			(thermal_gap 0.5)
			(thermal_bridge_width 0.5)
			(island_removal_mode 0)
		)
		(polygon
			(pts
				(xy 163.678616 -244.675152) (xy 165.177216 -244.675152) (xy 165.177216 -245.19509) (xy 163.678616 -245.19509)
			)
		)
	)
	(zone
		(layer "In2.Cu")
		(hatch none 0.5)
		(connect_pads
			(clearance 0)
		)
		(min_thickness 0.25)
		(keepout
			(tracks not_allowed)
			(vias allowed)
			(pads allowed)
			(copperpour not_allowed)
			(footprints allowed)
		)
		(placement
			(enabled no)
			(sheetname "")
		)
		(fill
			(thermal_gap 0.5)
			(thermal_bridge_width 0.5)
			(island_removal_mode 0)
		)
		(polygon
			(pts
				(xy 272.342864 -295.675304) (xy 273.841464 -295.675304) (xy 273.841464 -296.195242) (xy 272.342864 -296.195242)
			)
		)
	)
	(zone
		(layer "In2.Cu")
		(hatch none 0.5)
		(connect_pads
			(clearance 0)
		)
		(min_thickness 0.25)
		(keepout
			(tracks not_allowed)
			(vias allowed)
			(pads allowed)
			(copperpour not_allowed)
			(footprints allowed)
		)
		(placement
			(enabled no)
			(sheetname "")
		)
		(fill
			(thermal_gap 0.5)
			(thermal_bridge_width 0.5)
			(island_removal_mode 0)
		)
		(polygon
			(pts
				(xy 419.162738 -241.275108) (xy 420.661338 -241.275108) (xy 420.661338 -241.795046) (xy 419.162738 -241.795046)
			)
		)
	)
	(zone
		(layer "In2.Cu")
		(hatch none 0.5)
		(connect_pads
			(clearance 0)
		)
		(min_thickness 0.25)
		(keepout
			(tracks not_allowed)
			(vias allowed)
			(pads allowed)
			(copperpour not_allowed)
			(footprints allowed)
		)
		(placement
			(enabled no)
			(sheetname "")
		)
		(fill
			(thermal_gap 0.5)
			(thermal_bridge_width 0.5)
			(island_removal_mode 0)
		)
		(polygon
			(pts
				(xy 430.80686 -299.925232) (xy 432.30546 -299.925232) (xy 432.30546 -300.44517) (xy 430.80686 -300.44517)
			)
		)
	)
	(zone
		(layer "In2.Cu")
		(hatch none 0.5)
		(connect_pads
			(clearance 0)
		)
		(min_thickness 0.25)
		(keepout
			(tracks not_allowed)
			(vias allowed)
			(pads allowed)
			(copperpour not_allowed)
			(footprints allowed)
		)
		(placement
			(enabled no)
			(sheetname "")
		)
		(fill
			(thermal_gap 0.5)
			(thermal_bridge_width 0.5)
			(island_removal_mode 0)
		)
		(polygon
			(pts
				(xy 24.402542 -253.175262) (xy 25.901142 -253.175262) (xy 25.901142 -253.6952) (xy 24.402542 -253.6952)
			)
		)
	)
	(zone
		(layer "In2.Cu")
		(hatch none 0.5)
		(connect_pads
			(clearance 0)
		)
		(min_thickness 0.25)
		(keepout
			(tracks not_allowed)
			(vias allowed)
			(pads allowed)
			(copperpour not_allowed)
			(footprints allowed)
		)
		(placement
			(enabled no)
			(sheetname "")
		)
		(fill
			(thermal_gap 0.5)
			(thermal_bridge_width 0.5)
			(island_removal_mode 0)
		)
		(polygon
			(pts
				(xy 426.706792 -241.275108) (xy 428.205392 -241.275108) (xy 428.205392 -241.795046) (xy 426.706792 -241.795046)
			)
		)
	)
	(zone
		(layer "In2.Cu")
		(hatch none 0.5)
		(connect_pads
			(clearance 0)
		)
		(min_thickness 0.25)
		(keepout
			(tracks not_allowed)
			(vias allowed)
			(pads allowed)
			(copperpour not_allowed)
			(footprints allowed)
		)
		(placement
			(enabled no)
			(sheetname "")
		)
		(fill
			(thermal_gap 0.5)
			(thermal_bridge_width 0.5)
			(island_removal_mode 0)
		)
		(polygon
			(pts
				(xy 58.678826 -214.075264) (xy 60.177426 -214.075264) (xy 60.177426 -214.595202) (xy 58.678826 -214.595202)
			)
		)
	)
	(zone
		(layer "In2.Cu")
		(hatch none 0.5)
		(connect_pads
			(clearance 0)
		)
		(min_thickness 0.25)
		(keepout
			(tracks not_allowed)
			(vias allowed)
			(pads allowed)
			(copperpour not_allowed)
			(footprints allowed)
		)
		(placement
			(enabled no)
			(sheetname "")
		)
		(fill
			(thermal_gap 0.5)
			(thermal_bridge_width 0.5)
			(island_removal_mode 0)
		)
		(polygon
			(pts
				(xy 171.22267 -293.125144) (xy 172.72127 -293.125144) (xy 172.72127 -293.645082) (xy 171.22267 -293.645082)
			)
		)
	)
	(zone
		(layer "In2.Cu")
		(hatch none 0.5)
		(connect_pads
			(clearance 0)
		)
		(min_thickness 0.25)
		(keepout
			(tracks not_allowed)
			(vias allowed)
			(pads allowed)
			(copperpour not_allowed)
			(footprints allowed)
		)
		(placement
			(enabled no)
			(sheetname "")
		)
		(fill
			(thermal_gap 0.5)
			(thermal_bridge_width 0.5)
			(island_removal_mode 0)
		)
		(polygon
			(pts
				(xy 283.986732 -203.025248) (xy 285.485332 -203.025248) (xy 285.485332 -203.545186) (xy 283.986732 -203.545186)
			)
		)
	)
	(zone
		(layer "In2.Cu")
		(hatch none 0.5)
		(connect_pads
			(clearance 0)
		)
		(min_thickness 0.25)
		(keepout
			(tracks not_allowed)
			(vias allowed)
			(pads allowed)
			(copperpour not_allowed)
			(footprints allowed)
		)
		(placement
			(enabled no)
			(sheetname "")
		)
		(fill
			(thermal_gap 0.5)
			(thermal_bridge_width 0.5)
			(island_removal_mode 0)
		)
		(polygon
			(pts
				(xy 163.678616 -306.72532) (xy 165.177216 -306.72532) (xy 165.177216 -307.245258) (xy 163.678616 -307.245258)
			)
		)
	)
	(zone
		(layer "In2.Cu")
		(hatch none 0.5)
		(connect_pads
			(clearance 0)
		)
		(min_thickness 0.25)
		(keepout
			(tracks not_allowed)
			(vias allowed)
			(pads allowed)
			(copperpour not_allowed)
			(footprints allowed)
		)
		(placement
			(enabled no)
			(sheetname "")
		)
		(fill
			(thermal_gap 0.5)
			(thermal_bridge_width 0.5)
			(island_removal_mode 0)
		)
		(polygon
			(pts
				(xy 453.438768 -270.175228) (xy 454.937368 -270.175228) (xy 454.937368 -270.695166) (xy 453.438768 -270.695166)
			)
		)
	)
	(zone
		(layer "In2.Cu")
		(hatch none 0.5)
		(connect_pads
			(clearance 0)
		)
		(min_thickness 0.25)
		(keepout
			(tracks not_allowed)
			(vias allowed)
			(pads allowed)
			(copperpour not_allowed)
			(footprints allowed)
		)
		(placement
			(enabled no)
			(sheetname "")
		)
		(fill
			(thermal_gap 0.5)
			(thermal_bridge_width 0.5)
			(island_removal_mode 0)
		)
		(polygon
			(pts
				(xy 438.350914 -215.775286) (xy 439.849514 -215.775286) (xy 439.849514 -216.295224) (xy 438.350914 -216.295224)
			)
		)
	)
	(zone
		(layer "In2.Cu")
		(hatch none 0.5)
		(connect_pads
			(clearance 0)
		)
		(min_thickness 0.25)
		(keepout
			(tracks not_allowed)
			(vias allowed)
			(pads allowed)
			(copperpour not_allowed)
			(footprints allowed)
		)
		(placement
			(enabled no)
			(sheetname "")
		)
		(fill
			(thermal_gap 0.5)
			(thermal_bridge_width 0.5)
			(island_removal_mode 0)
		)
		(polygon
			(pts
				(xy 279.886664 -199.625204) (xy 281.385264 -199.625204) (xy 281.385264 -200.145142) (xy 279.886664 -200.145142)
			)
		)
	)
	(zone
		(layer "In2.Cu")
		(hatch none 0.5)
		(connect_pads
			(clearance 0)
		)
		(min_thickness 0.25)
		(keepout
			(tracks not_allowed)
			(vias allowed)
			(pads allowed)
			(copperpour not_allowed)
			(footprints allowed)
		)
		(placement
			(enabled no)
			(sheetname "")
		)
		(fill
			(thermal_gap 0.5)
			(thermal_bridge_width 0.5)
			(island_removal_mode 0)
		)
		(polygon
			(pts
				(xy 47.034704 -201.325226) (xy 48.533304 -201.325226) (xy 48.533304 -201.845164) (xy 47.034704 -201.845164)
			)
		)
	)
	(zone
		(layer "In2.Cu")
		(hatch none 0.5)
		(connect_pads
			(clearance 0)
		)
		(min_thickness 0.25)
		(keepout
			(tracks not_allowed)
			(vias allowed)
			(pads allowed)
			(copperpour not_allowed)
			(footprints allowed)
		)
		(placement
			(enabled no)
			(sheetname "")
		)
		(fill
			(thermal_gap 0.5)
			(thermal_bridge_width 0.5)
			(island_removal_mode 0)
		)
		(polygon
			(pts
				(xy 36.046664 -242.125246) (xy 37.545264 -242.125246) (xy 37.545264 -242.645184) (xy 36.046664 -242.645184)
			)
		)
	)
	(zone
		(layer "In2.Cu")
		(hatch none 0.5)
		(connect_pads
			(clearance 0)
		)
		(min_thickness 0.25)
		(keepout
			(tracks not_allowed)
			(vias allowed)
			(pads allowed)
			(copperpour not_allowed)
			(footprints allowed)
		)
		(placement
			(enabled no)
			(sheetname "")
		)
		(fill
			(thermal_gap 0.5)
			(thermal_bridge_width 0.5)
			(island_removal_mode 0)
		)
		(polygon
			(pts
				(xy 438.350914 -310.975248) (xy 439.849514 -310.975248) (xy 439.849514 -311.495186) (xy 438.350914 -311.495186)
			)
		)
	)
	(zone
		(layer "In2.Cu")
		(hatch none 0.5)
		(connect_pads
			(clearance 0)
		)
		(min_thickness 0.25)
		(keepout
			(tracks not_allowed)
			(vias allowed)
			(pads allowed)
			(copperpour not_allowed)
			(footprints allowed)
		)
		(placement
			(enabled no)
			(sheetname "")
		)
		(fill
			(thermal_gap 0.5)
			(thermal_bridge_width 0.5)
			(island_removal_mode 0)
		)
		(polygon
			(pts
				(xy 175.322738 -247.225312) (xy 176.821338 -247.225312) (xy 176.821338 -247.74525) (xy 175.322738 -247.74525)
			)
		)
	)
	(zone
		(layer "In2.Cu")
		(hatch none 0.5)
		(connect_pads
			(clearance 0)
		)
		(min_thickness 0.25)
		(keepout
			(tracks not_allowed)
			(vias allowed)
			(pads allowed)
			(copperpour not_allowed)
			(footprints allowed)
		)
		(placement
			(enabled no)
			(sheetname "")
		)
		(fill
			(thermal_gap 0.5)
			(thermal_bridge_width 0.5)
			(island_removal_mode 0)
		)
		(polygon
			(pts
				(xy 276.442932 -304.17516) (xy 277.941532 -304.17516) (xy 277.941532 -304.695098) (xy 276.442932 -304.695098)
			)
		)
	)
	(zone
		(layer "In2.Cu")
		(hatch none 0.5)
		(connect_pads
			(clearance 0)
		)
		(min_thickness 0.25)
		(keepout
			(tracks not_allowed)
			(vias allowed)
			(pads allowed)
			(copperpour not_allowed)
			(footprints allowed)
		)
		(placement
			(enabled no)
			(sheetname "")
		)
		(fill
			(thermal_gap 0.5)
			(thermal_bridge_width 0.5)
			(island_removal_mode 0)
		)
		(polygon
			(pts
				(xy 279.886664 -218.325192) (xy 281.385264 -218.325192) (xy 281.385264 -218.84513) (xy 279.886664 -218.84513)
			)
		)
	)
	(zone
		(layer "In2.Cu")
		(hatch none 0.5)
		(connect_pads
			(clearance 0)
		)
		(min_thickness 0.25)
		(keepout
			(tracks not_allowed)
			(vias allowed)
			(pads allowed)
			(copperpour not_allowed)
			(footprints allowed)
		)
		(placement
			(enabled no)
			(sheetname "")
		)
		(fill
			(thermal_gap 0.5)
			(thermal_bridge_width 0.5)
			(island_removal_mode 0)
		)
		(polygon
			(pts
				(xy 197.954646 -254.025146) (xy 199.453246 -254.025146) (xy 199.453246 -254.545084) (xy 197.954646 -254.545084)
			)
		)
	)
	(zone
		(layer "In2.Cu")
		(hatch none 0.5)
		(connect_pads
			(clearance 0)
		)
		(min_thickness 0.25)
		(keepout
			(tracks not_allowed)
			(vias allowed)
			(pads allowed)
			(copperpour not_allowed)
			(footprints allowed)
		)
		(placement
			(enabled no)
			(sheetname "")
		)
		(fill
			(thermal_gap 0.5)
			(thermal_bridge_width 0.5)
			(island_removal_mode 0)
		)
		(polygon
			(pts
				(xy 47.034704 -272.725134) (xy 48.533304 -272.725134) (xy 48.533304 -273.245072) (xy 47.034704 -273.245072)
			)
		)
	)
	(zone
		(layer "In2.Cu")
		(hatch none 0.5)
		(connect_pads
			(clearance 0)
		)
		(min_thickness 0.25)
		(keepout
			(tracks not_allowed)
			(vias allowed)
			(pads allowed)
			(copperpour not_allowed)
			(footprints allowed)
		)
		(placement
			(enabled no)
			(sheetname "")
		)
		(fill
			(thermal_gap 0.5)
			(thermal_bridge_width 0.5)
			(island_removal_mode 0)
		)
		(polygon
			(pts
				(xy 287.430718 -231.925114) (xy 288.929318 -231.925114) (xy 288.929318 -232.445052) (xy 287.430718 -232.445052)
			)
		)
	)
	(zone
		(layer "In2.Cu")
		(hatch none 0.5)
		(connect_pads
			(clearance 0)
		)
		(min_thickness 0.25)
		(keepout
			(tracks not_allowed)
			(vias allowed)
			(pads allowed)
			(copperpour not_allowed)
			(footprints allowed)
		)
		(placement
			(enabled no)
			(sheetname "")
		)
		(fill
			(thermal_gap 0.5)
			(thermal_bridge_width 0.5)
			(island_removal_mode 0)
		)
		(polygon
			(pts
				(xy 415.718752 -281.225244) (xy 417.217352 -281.225244) (xy 417.217352 -281.745182) (xy 415.718752 -281.745182)
			)
		)
	)
	(zone
		(layer "In2.Cu")
		(hatch none 0.5)
		(connect_pads
			(clearance 0)
		)
		(min_thickness 0.25)
		(keepout
			(tracks not_allowed)
			(vias allowed)
			(pads allowed)
			(copperpour not_allowed)
			(footprints allowed)
		)
		(placement
			(enabled no)
			(sheetname "")
		)
		(fill
			(thermal_gap 0.5)
			(thermal_bridge_width 0.5)
			(island_removal_mode 0)
		)
		(polygon
			(pts
				(xy 411.618684 -293.125144) (xy 413.117284 -293.125144) (xy 413.117284 -293.645082) (xy 411.618684 -293.645082)
			)
		)
	)
	(zone
		(layer "In2.Cu")
		(hatch none 0.5)
		(connect_pads
			(clearance 0)
		)
		(min_thickness 0.25)
		(keepout
			(tracks not_allowed)
			(vias allowed)
			(pads allowed)
			(copperpour not_allowed)
			(footprints allowed)
		)
		(placement
			(enabled no)
			(sheetname "")
		)
		(fill
			(thermal_gap 0.5)
			(thermal_bridge_width 0.5)
			(island_removal_mode 0)
		)
		(polygon
			(pts
				(xy 283.986732 -209.825336) (xy 285.485332 -209.825336) (xy 285.485332 -210.345274) (xy 283.986732 -210.345274)
			)
		)
	)
	(zone
		(layer "In2.Cu")
		(hatch none 0.5)
		(connect_pads
			(clearance 0)
		)
		(min_thickness 0.25)
		(keepout
			(tracks not_allowed)
			(vias allowed)
			(pads allowed)
			(copperpour not_allowed)
			(footprints allowed)
		)
		(placement
			(enabled no)
			(sheetname "")
		)
		(fill
			(thermal_gap 0.5)
			(thermal_bridge_width 0.5)
			(island_removal_mode 0)
		)
		(polygon
			(pts
				(xy 299.07484 -303.325276) (xy 300.57344 -303.325276) (xy 300.57344 -303.845214) (xy 299.07484 -303.845214)
			)
		)
	)
	(zone
		(layer "In2.Cu")
		(hatch none 0.5)
		(connect_pads
			(clearance 0)
		)
		(min_thickness 0.25)
		(keepout
			(tracks not_allowed)
			(vias allowed)
			(pads allowed)
			(copperpour not_allowed)
			(footprints allowed)
		)
		(placement
			(enabled no)
			(sheetname "")
		)
		(fill
			(thermal_gap 0.5)
			(thermal_bridge_width 0.5)
			(island_removal_mode 0)
		)
		(polygon
			(pts
				(xy 445.894968 -276.125178) (xy 447.393568 -276.125178) (xy 447.393568 -276.645116) (xy 445.894968 -276.645116)
			)
		)
	)
	(zone
		(layer "In2.Cu")
		(hatch none 0.5)
		(connect_pads
			(clearance 0)
		)
		(min_thickness 0.25)
		(keepout
			(tracks not_allowed)
			(vias allowed)
			(pads allowed)
			(copperpour not_allowed)
			(footprints allowed)
		)
		(placement
			(enabled no)
			(sheetname "")
		)
		(fill
			(thermal_gap 0.5)
			(thermal_bridge_width 0.5)
			(island_removal_mode 0)
		)
		(polygon
			(pts
				(xy 193.854578 -306.72532) (xy 195.353178 -306.72532) (xy 195.353178 -307.245258) (xy 193.854578 -307.245258)
			)
		)
	)
	(zone
		(layer "In2.Cu")
		(hatch none 0.5)
		(connect_pads
			(clearance 0)
		)
		(min_thickness 0.25)
		(keepout
			(tracks not_allowed)
			(vias allowed)
			(pads allowed)
			(copperpour not_allowed)
			(footprints allowed)
		)
		(placement
			(enabled no)
			(sheetname "")
		)
		(fill
			(thermal_gap 0.5)
			(thermal_bridge_width 0.5)
			(island_removal_mode 0)
		)
		(polygon
			(pts
				(xy 279.886664 -274.425156) (xy 281.385264 -274.425156) (xy 281.385264 -274.945094) (xy 279.886664 -274.945094)
			)
		)
	)
	(zone
		(layer "In2.Cu")
		(hatch none 0.5)
		(connect_pads
			(clearance 0)
		)
		(min_thickness 0.25)
		(keepout
			(tracks not_allowed)
			(vias allowed)
			(pads allowed)
			(copperpour not_allowed)
			(footprints allowed)
		)
		(placement
			(enabled no)
			(sheetname "")
		)
		(fill
			(thermal_gap 0.5)
			(thermal_bridge_width 0.5)
			(island_removal_mode 0)
		)
		(polygon
			(pts
				(xy 419.162738 -295.675304) (xy 420.661338 -295.675304) (xy 420.661338 -296.195242) (xy 419.162738 -296.195242)
			)
		)
	)
	(zone
		(layer "In2.Cu")
		(hatch none 0.5)
		(connect_pads
			(clearance 0)
		)
		(min_thickness 0.25)
		(keepout
			(tracks not_allowed)
			(vias allowed)
			(pads allowed)
			(copperpour not_allowed)
			(footprints allowed)
		)
		(placement
			(enabled no)
			(sheetname "")
		)
		(fill
			(thermal_gap 0.5)
			(thermal_bridge_width 0.5)
			(island_removal_mode 0)
		)
		(polygon
			(pts
				(xy 31.946596 -289.725354) (xy 33.445196 -289.725354) (xy 33.445196 -290.245292) (xy 31.946596 -290.245292)
			)
		)
	)
	(zone
		(layer "In2.Cu")
		(hatch none 0.5)
		(connect_pads
			(clearance 0)
		)
		(min_thickness 0.25)
		(keepout
			(tracks not_allowed)
			(vias allowed)
			(pads allowed)
			(copperpour not_allowed)
			(footprints allowed)
		)
		(placement
			(enabled no)
			(sheetname "")
		)
		(fill
			(thermal_gap 0.5)
			(thermal_bridge_width 0.5)
			(island_removal_mode 0)
		)
		(polygon
			(pts
				(xy 294.974772 -272.725134) (xy 296.473372 -272.725134) (xy 296.473372 -273.245072) (xy 294.974772 -273.245072)
			)
		)
	)
	(zone
		(layer "In2.Cu")
		(hatch none 0.5)
		(connect_pads
			(clearance 0)
		)
		(min_thickness 0.25)
		(keepout
			(tracks not_allowed)
			(vias allowed)
			(pads allowed)
			(copperpour not_allowed)
			(footprints allowed)
		)
		(placement
			(enabled no)
			(sheetname "")
		)
		(fill
			(thermal_gap 0.5)
			(thermal_bridge_width 0.5)
			(island_removal_mode 0)
		)
		(polygon
			(pts
				(xy 186.310778 -205.575154) (xy 187.809378 -205.575154) (xy 187.809378 -206.095092) (xy 186.310778 -206.095092)
			)
		)
	)
	(zone
		(layer "In2.Cu")
		(hatch none 0.5)
		(connect_pads
			(clearance 0)
		)
		(min_thickness 0.25)
		(keepout
			(tracks not_allowed)
			(vias allowed)
			(pads allowed)
			(copperpour not_allowed)
			(footprints allowed)
		)
		(placement
			(enabled no)
			(sheetname "")
		)
		(fill
			(thermal_gap 0.5)
			(thermal_bridge_width 0.5)
			(island_removal_mode 0)
		)
		(polygon
			(pts
				(xy 272.342864 -199.625204) (xy 273.841464 -199.625204) (xy 273.841464 -200.145142) (xy 272.342864 -200.145142)
			)
		)
	)
	(zone
		(layer "In2.Cu")
		(hatch none 0.5)
		(connect_pads
			(clearance 0)
		)
		(min_thickness 0.25)
		(keepout
			(tracks not_allowed)
			(vias allowed)
			(pads allowed)
			(copperpour not_allowed)
			(footprints allowed)
		)
		(placement
			(enabled no)
			(sheetname "")
		)
		(fill
			(thermal_gap 0.5)
			(thermal_bridge_width 0.5)
			(island_removal_mode 0)
		)
		(polygon
			(pts
				(xy 190.410846 -228.525324) (xy 191.909446 -228.525324) (xy 191.909446 -229.045262) (xy 190.410846 -229.045262)
			)
		)
	)
	(zone
		(layer "In2.Cu")
		(hatch none 0.5)
		(connect_pads
			(clearance 0)
		)
		(min_thickness 0.25)
		(keepout
			(tracks not_allowed)
			(vias allowed)
			(pads allowed)
			(copperpour not_allowed)
			(footprints allowed)
		)
		(placement
			(enabled no)
			(sheetname "")
		)
		(fill
			(thermal_gap 0.5)
			(thermal_bridge_width 0.5)
			(island_removal_mode 0)
		)
		(polygon
			(pts
				(xy 201.398632 -285.475172) (xy 202.897232 -285.475172) (xy 202.897232 -285.99511) (xy 201.398632 -285.99511)
			)
		)
	)
	(zone
		(layer "In2.Cu")
		(hatch none 0.5)
		(connect_pads
			(clearance 0)
		)
		(min_thickness 0.25)
		(keepout
			(tracks not_allowed)
			(vias allowed)
			(pads allowed)
			(copperpour not_allowed)
			(footprints allowed)
		)
		(placement
			(enabled no)
			(sheetname "")
		)
		(fill
			(thermal_gap 0.5)
			(thermal_bridge_width 0.5)
			(island_removal_mode 0)
		)
		(polygon
			(pts
				(xy 445.894968 -238.725202) (xy 447.393568 -238.725202) (xy 447.393568 -239.24514) (xy 445.894968 -239.24514)
			)
		)
	)
	(zone
		(layer "In2.Cu")
		(hatch none 0.5)
		(connect_pads
			(clearance 0)
		)
		(min_thickness 0.25)
		(keepout
			(tracks not_allowed)
			(vias allowed)
			(pads allowed)
			(copperpour not_allowed)
			(footprints allowed)
		)
		(placement
			(enabled no)
			(sheetname "")
		)
		(fill
			(thermal_gap 0.5)
			(thermal_bridge_width 0.5)
			(island_removal_mode 0)
		)
		(polygon
			(pts
				(xy 20.95881 -250.625102) (xy 22.45741 -250.625102) (xy 22.45741 -251.14504) (xy 20.95881 -251.14504)
			)
		)
	)
	(zone
		(layer "In2.Cu")
		(hatch none 0.5)
		(connect_pads
			(clearance 0)
		)
		(min_thickness 0.25)
		(keepout
			(tracks not_allowed)
			(vias allowed)
			(pads allowed)
			(copperpour not_allowed)
			(footprints allowed)
		)
		(placement
			(enabled no)
			(sheetname "")
		)
		(fill
			(thermal_gap 0.5)
			(thermal_bridge_width 0.5)
			(island_removal_mode 0)
		)
		(polygon
			(pts
				(xy 430.80686 -275.275294) (xy 432.30546 -275.275294) (xy 432.30546 -275.795232) (xy 430.80686 -275.795232)
			)
		)
	)
	(zone
		(layer "In2.Cu")
		(hatch none 0.5)
		(connect_pads
			(clearance 0)
		)
		(min_thickness 0.25)
		(keepout
			(tracks not_allowed)
			(vias allowed)
			(pads allowed)
			(copperpour not_allowed)
			(footprints allowed)
		)
		(placement
			(enabled no)
			(sheetname "")
		)
		(fill
			(thermal_gap 0.5)
			(thermal_bridge_width 0.5)
			(island_removal_mode 0)
		)
		(polygon
			(pts
				(xy 58.678826 -210.67522) (xy 60.177426 -210.67522) (xy 60.177426 -211.195158) (xy 58.678826 -211.195158)
			)
		)
	)
	(zone
		(layer "In2.Cu")
		(hatch none 0.5)
		(connect_pads
			(clearance 0)
		)
		(min_thickness 0.25)
		(keepout
			(tracks not_allowed)
			(vias allowed)
			(pads allowed)
			(copperpour not_allowed)
			(footprints allowed)
		)
		(placement
			(enabled no)
			(sheetname "")
		)
		(fill
			(thermal_gap 0.5)
			(thermal_bridge_width 0.5)
			(island_removal_mode 0)
		)
		(polygon
			(pts
				(arc
					(start 325.334122 -385.243578)
					(mid 325.324886 -385.263502)
					(end 325.321676 -385.285234)
				)
				(arc
					(start 325.321676 -385.479798)
					(mid 325.343994 -385.53368)
					(end 325.397876 -385.555998)
				)
				(arc
					(start 326.083676 -385.555998)
					(mid 326.137558 -385.53368)
					(end 326.159876 -385.479798)
				)
				(arc
					(start 326.159876 -385.285234)
					(mid 326.156708 -385.26349)
					(end 326.14743 -385.243578)
				)
				(arc
					(start 325.954644 -384.947414)
					(mid 325.942422 -384.90573)
					(end 325.954898 -384.864102)
				)
				(arc
					(start 326.14743 -384.570478)
					(mid 326.156666 -384.550554)
					(end 326.159876 -384.528822)
				)
				(arc
					(start 326.159876 -384.334258)
					(mid 326.137558 -384.280376)
					(end 326.083676 -384.258058)
				)
				(arc
					(start 325.397876 -384.258058)
					(mid 325.343994 -384.280376)
					(end 325.321676 -384.334258)
				)
				(arc
					(start 325.321676 -384.530092)
					(mid 325.324844 -384.551836)
					(end 325.334122 -384.571748)
				)
				(arc
					(start 325.526654 -384.865372)
					(mid 325.539056 -384.907028)
					(end 325.526654 -384.948684)
				)
			)
		)
	)
	(zone
		(layer "In2.Cu")
		(hatch none 0.5)
		(connect_pads
			(clearance 0)
		)
		(min_thickness 0.25)
		(keepout
			(tracks not_allowed)
			(vias allowed)
			(pads allowed)
			(copperpour not_allowed)
			(footprints allowed)
		)
		(placement
			(enabled no)
			(sheetname "")
		)
		(fill
			(thermal_gap 0.5)
			(thermal_bridge_width 0.5)
			(island_removal_mode 0)
		)
		(polygon
			(pts
				(xy 306.618894 -303.325276) (xy 308.117494 -303.325276) (xy 308.117494 -303.845214) (xy 306.618894 -303.845214)
			)
		)
	)
	(zone
		(layer "In2.Cu")
		(hatch none 0.5)
		(connect_pads
			(clearance 0)
		)
		(min_thickness 0.25)
		(keepout
			(tracks not_allowed)
			(vias allowed)
			(pads allowed)
			(copperpour not_allowed)
			(footprints allowed)
		)
		(placement
			(enabled no)
			(sheetname "")
		)
		(fill
			(thermal_gap 0.5)
			(thermal_bridge_width 0.5)
			(island_removal_mode 0)
		)
		(polygon
			(pts
				(xy 434.250846 -278.675338) (xy 435.749446 -278.675338) (xy 435.749446 -279.195276) (xy 434.250846 -279.195276)
			)
		)
	)
	(zone
		(layer "In2.Cu")
		(hatch none 0.5)
		(connect_pads
			(clearance 0)
		)
		(min_thickness 0.25)
		(keepout
			(tracks not_allowed)
			(vias allowed)
			(pads allowed)
			(copperpour not_allowed)
			(footprints allowed)
		)
		(placement
			(enabled no)
			(sheetname "")
		)
		(fill
			(thermal_gap 0.5)
			(thermal_bridge_width 0.5)
			(island_removal_mode 0)
		)
		(polygon
			(pts
				(xy 302.518826 -311.825132) (xy 304.017426 -311.825132) (xy 304.017426 -312.34507) (xy 302.518826 -312.34507)
			)
		)
	)
	(zone
		(layer "In2.Cu")
		(hatch none 0.5)
		(connect_pads
			(clearance 0)
		)
		(min_thickness 0.25)
		(keepout
			(tracks not_allowed)
			(vias allowed)
			(pads allowed)
			(copperpour not_allowed)
			(footprints allowed)
		)
		(placement
			(enabled no)
			(sheetname "")
		)
		(fill
			(thermal_gap 0.5)
			(thermal_bridge_width 0.5)
			(island_removal_mode 0)
		)
		(polygon
			(pts
				(xy 28.50261 -288.875216) (xy 30.00121 -288.875216) (xy 30.00121 -289.395154) (xy 28.50261 -289.395154)
			)
		)
	)
	(zone
		(layer "In2.Cu")
		(hatch none 0.5)
		(connect_pads
			(clearance 0)
		)
		(min_thickness 0.25)
		(keepout
			(tracks not_allowed)
			(vias allowed)
			(pads allowed)
			(copperpour not_allowed)
			(footprints allowed)
		)
		(placement
			(enabled no)
			(sheetname "")
		)
		(fill
			(thermal_gap 0.5)
			(thermal_bridge_width 0.5)
			(island_removal_mode 0)
		)
		(polygon
			(pts
				(xy 441.7949 -288.025332) (xy 443.2935 -288.025332) (xy 443.2935 -288.54527) (xy 441.7949 -288.54527)
			)
		)
	)
	(zone
		(layer "In2.Cu")
		(hatch none 0.5)
		(connect_pads
			(clearance 0)
		)
		(min_thickness 0.25)
		(keepout
			(tracks not_allowed)
			(vias allowed)
			(pads allowed)
			(copperpour not_allowed)
			(footprints allowed)
		)
		(placement
			(enabled no)
			(sheetname "")
		)
		(fill
			(thermal_gap 0.5)
			(thermal_bridge_width 0.5)
			(island_removal_mode 0)
		)
		(polygon
			(pts
				(xy 272.342864 -313.525154) (xy 273.841464 -313.525154) (xy 273.841464 -314.045092) (xy 272.342864 -314.045092)
			)
		)
	)
	(zone
		(layer "In2.Cu")
		(hatch none 0.5)
		(connect_pads
			(clearance 0)
		)
		(min_thickness 0.25)
		(keepout
			(tracks not_allowed)
			(vias allowed)
			(pads allowed)
			(copperpour not_allowed)
			(footprints allowed)
		)
		(placement
			(enabled no)
			(sheetname "")
		)
		(fill
			(thermal_gap 0.5)
			(thermal_bridge_width 0.5)
			(island_removal_mode 0)
		)
		(polygon
			(pts
				(xy 423.262806 -234.475274) (xy 424.761406 -234.475274) (xy 424.761406 -234.995212) (xy 423.262806 -234.995212)
			)
		)
	)
	(zone
		(layer "In2.Cu")
		(hatch none 0.5)
		(connect_pads
			(clearance 0)
		)
		(min_thickness 0.25)
		(keepout
			(tracks allowed)
			(vias allowed)
			(pads allowed)
			(copperpour allowed)
			(footprints allowed)
		)
		(placement
			(enabled no)
			(sheetname "")
		)
		(fill
			(thermal_gap 0.5)
			(thermal_bridge_width 0.5)
			(island_removal_mode 0)
		)
		(polygon
			(pts
				(xy 288.116772 -349.93834) (xy 288.116772 -349.31604) (xy 288.667952 -349.31604) (xy 288.667952 -349.93834)
			)
		)
	)
	(zone
		(layer "In2.Cu")
		(hatch none 0.5)
		(connect_pads
			(clearance 0)
		)
		(min_thickness 0.25)
		(keepout
			(tracks not_allowed)
			(vias allowed)
			(pads allowed)
			(copperpour not_allowed)
			(footprints allowed)
		)
		(placement
			(enabled no)
			(sheetname "")
		)
		(fill
			(thermal_gap 0.5)
			(thermal_bridge_width 0.5)
			(island_removal_mode 0)
		)
		(polygon
			(pts
				(xy 20.95881 -209.825336) (xy 22.45741 -209.825336) (xy 22.45741 -210.345274) (xy 20.95881 -210.345274)
			)
		)
	)
	(zone
		(layer "In2.Cu")
		(hatch none 0.5)
		(connect_pads
			(clearance 0)
		)
		(min_thickness 0.25)
		(keepout
			(tracks not_allowed)
			(vias allowed)
			(pads allowed)
			(copperpour not_allowed)
			(footprints allowed)
		)
		(placement
			(enabled no)
			(sheetname "")
		)
		(fill
			(thermal_gap 0.5)
			(thermal_bridge_width 0.5)
			(island_removal_mode 0)
		)
		(polygon
			(pts
				(xy 51.134772 -310.975248) (xy 52.633372 -310.975248) (xy 52.633372 -311.495186) (xy 51.134772 -311.495186)
			)
		)
	)
	(zone
		(layer "In2.Cu")
		(hatch none 0.5)
		(connect_pads
			(clearance 0)
		)
		(min_thickness 0.25)
		(keepout
			(tracks not_allowed)
			(vias allowed)
			(pads allowed)
			(copperpour not_allowed)
			(footprints allowed)
		)
		(placement
			(enabled no)
			(sheetname "")
		)
		(fill
			(thermal_gap 0.5)
			(thermal_bridge_width 0.5)
			(island_removal_mode 0)
		)
		(polygon
			(pts
				(xy 20.95881 -200.475342) (xy 22.45741 -200.475342) (xy 22.45741 -200.99528) (xy 20.95881 -200.99528)
			)
		)
	)
	(zone
		(layer "In2.Cu")
		(hatch none 0.5)
		(connect_pads
			(clearance 0)
		)
		(min_thickness 0.25)
		(keepout
			(tracks not_allowed)
			(vias allowed)
			(pads allowed)
			(copperpour not_allowed)
			(footprints allowed)
		)
		(placement
			(enabled no)
			(sheetname "")
		)
		(fill
			(thermal_gap 0.5)
			(thermal_bridge_width 0.5)
			(island_removal_mode 0)
		)
		(polygon
			(pts
				(xy 279.886664 -304.17516) (xy 281.385264 -304.17516) (xy 281.385264 -304.695098) (xy 279.886664 -304.695098)
			)
		)
	)
	(zone
		(layer "In2.Cu")
		(hatch none 0.5)
		(connect_pads
			(clearance 0)
		)
		(min_thickness 0.25)
		(keepout
			(tracks not_allowed)
			(vias allowed)
			(pads allowed)
			(copperpour not_allowed)
			(footprints allowed)
		)
		(placement
			(enabled no)
			(sheetname "")
		)
		(fill
			(thermal_gap 0.5)
			(thermal_bridge_width 0.5)
			(island_removal_mode 0)
		)
		(polygon
			(pts
				(xy 306.618894 -264.225278) (xy 308.117494 -264.225278) (xy 308.117494 -264.745216) (xy 306.618894 -264.745216)
			)
		)
	)
	(zone
		(layer "In2.Cu")
		(hatch none 0.5)
		(connect_pads
			(clearance 0)
		)
		(min_thickness 0.25)
		(keepout
			(tracks not_allowed)
			(vias allowed)
			(pads allowed)
			(copperpour not_allowed)
			(footprints allowed)
		)
		(placement
			(enabled no)
			(sheetname "")
		)
		(fill
			(thermal_gap 0.5)
			(thermal_bridge_width 0.5)
			(island_removal_mode 0)
		)
		(polygon
			(pts
				(xy 197.954646 -269.325344) (xy 199.453246 -269.325344) (xy 199.453246 -269.845282) (xy 197.954646 -269.845282)
			)
		)
	)
	(zone
		(layer "In2.Cu")
		(hatch none 0.5)
		(connect_pads
			(clearance 0)
		)
		(min_thickness 0.25)
		(keepout
			(tracks not_allowed)
			(vias allowed)
			(pads allowed)
			(copperpour not_allowed)
			(footprints allowed)
		)
		(placement
			(enabled no)
			(sheetname "")
		)
		(fill
			(thermal_gap 0.5)
			(thermal_bridge_width 0.5)
			(island_removal_mode 0)
		)
		(polygon
			(pts
				(xy 272.342864 -253.175262) (xy 273.841464 -253.175262) (xy 273.841464 -253.6952) (xy 272.342864 -253.6952)
			)
		)
	)
	(zone
		(layer "In2.Cu")
		(hatch none 0.5)
		(connect_pads
			(clearance 0)
		)
		(min_thickness 0.25)
		(keepout
			(tracks not_allowed)
			(vias allowed)
			(pads allowed)
			(copperpour not_allowed)
			(footprints allowed)
		)
		(placement
			(enabled no)
			(sheetname "")
		)
		(fill
			(thermal_gap 0.5)
			(thermal_bridge_width 0.5)
			(island_removal_mode 0)
		)
		(polygon
			(pts
				(xy 36.046664 -315.225176) (xy 37.545264 -315.225176) (xy 37.545264 -315.745114) (xy 36.046664 -315.745114)
			)
		)
	)
	(zone
		(layer "In2.Cu")
		(hatch none 0.5)
		(connect_pads
			(clearance 0)
		)
		(min_thickness 0.25)
		(keepout
			(tracks not_allowed)
			(vias allowed)
			(pads allowed)
			(copperpour not_allowed)
			(footprints allowed)
		)
		(placement
			(enabled no)
			(sheetname "")
		)
		(fill
			(thermal_gap 0.5)
			(thermal_bridge_width 0.5)
			(island_removal_mode 0)
		)
		(polygon
			(pts
				(xy 36.046664 -270.175228) (xy 37.545264 -270.175228) (xy 37.545264 -270.695166) (xy 36.046664 -270.695166)
			)
		)
	)
	(zone
		(layer "In2.Cu")
		(hatch none 0.5)
		(connect_pads
			(clearance 0)
		)
		(min_thickness 0.25)
		(keepout
			(tracks not_allowed)
			(vias allowed)
			(pads allowed)
			(copperpour not_allowed)
			(footprints allowed)
		)
		(placement
			(enabled no)
			(sheetname "")
		)
		(fill
			(thermal_gap 0.5)
			(thermal_bridge_width 0.5)
			(island_removal_mode 0)
		)
		(polygon
			(pts
				(xy 449.3387 -276.975316) (xy 450.8373 -276.975316) (xy 450.8373 -277.495254) (xy 449.3387 -277.495254)
			)
		)
	)
	(zone
		(layer "In2.Cu")
		(hatch none 0.5)
		(connect_pads
			(clearance 0)
		)
		(min_thickness 0.25)
		(keepout
			(tracks not_allowed)
			(vias allowed)
			(pads allowed)
			(copperpour not_allowed)
			(footprints allowed)
		)
		(placement
			(enabled no)
			(sheetname "")
		)
		(fill
			(thermal_gap 0.5)
			(thermal_bridge_width 0.5)
			(island_removal_mode 0)
		)
		(polygon
			(pts
				(xy 190.410846 -229.375208) (xy 191.909446 -229.375208) (xy 191.909446 -229.895146) (xy 190.410846 -229.895146)
			)
		)
	)
	(zone
		(layer "In2.Cu")
		(hatch none 0.5)
		(connect_pads
			(clearance 0)
		)
		(min_thickness 0.25)
		(keepout
			(tracks not_allowed)
			(vias allowed)
			(pads allowed)
			(copperpour not_allowed)
			(footprints allowed)
		)
		(placement
			(enabled no)
			(sheetname "")
		)
		(fill
			(thermal_gap 0.5)
			(thermal_bridge_width 0.5)
			(island_removal_mode 0)
		)
		(polygon
			(pts
				(xy 302.518826 -288.025332) (xy 304.017426 -288.025332) (xy 304.017426 -288.54527) (xy 302.518826 -288.54527)
			)
		)
	)
	(zone
		(layer "In2.Cu")
		(hatch none 0.5)
		(connect_pads
			(clearance 0)
		)
		(min_thickness 0.25)
		(keepout
			(tracks not_allowed)
			(vias allowed)
			(pads allowed)
			(copperpour not_allowed)
			(footprints allowed)
		)
		(placement
			(enabled no)
			(sheetname "")
		)
		(fill
			(thermal_gap 0.5)
			(thermal_bridge_width 0.5)
			(island_removal_mode 0)
		)
		(polygon
			(pts
				(xy 197.954646 -243.825268) (xy 199.453246 -243.825268) (xy 199.453246 -244.345206) (xy 197.954646 -244.345206)
			)
		)
	)
	(zone
		(layer "In2.Cu")
		(hatch none 0.5)
		(connect_pads
			(clearance 0)
		)
		(min_thickness 0.25)
		(keepout
			(tracks not_allowed)
			(vias allowed)
			(pads allowed)
			(copperpour not_allowed)
			(footprints allowed)
		)
		(placement
			(enabled no)
			(sheetname "")
		)
		(fill
			(thermal_gap 0.5)
			(thermal_bridge_width 0.5)
			(island_removal_mode 0)
		)
		(polygon
			(pts
				(xy 58.678826 -234.475274) (xy 60.177426 -234.475274) (xy 60.177426 -234.995212) (xy 58.678826 -234.995212)
			)
		)
	)
	(zone
		(layer "In2.Cu")
		(hatch none 0.5)
		(connect_pads
			(clearance 0)
		)
		(min_thickness 0.25)
		(keepout
			(tracks not_allowed)
			(vias allowed)
			(pads allowed)
			(copperpour not_allowed)
			(footprints allowed)
		)
		(placement
			(enabled no)
			(sheetname "")
		)
		(fill
			(thermal_gap 0.5)
			(thermal_bridge_width 0.5)
			(island_removal_mode 0)
		)
		(polygon
			(pts
				(xy 54.578758 -224.275142) (xy 56.077358 -224.275142) (xy 56.077358 -224.79508) (xy 54.578758 -224.79508)
			)
		)
	)
	(zone
		(layer "In2.Cu")
		(hatch none 0.5)
		(connect_pads
			(clearance 0)
		)
		(min_thickness 0.25)
		(keepout
			(tracks not_allowed)
			(vias allowed)
			(pads allowed)
			(copperpour not_allowed)
			(footprints allowed)
		)
		(placement
			(enabled no)
			(sheetname "")
		)
		(fill
			(thermal_gap 0.5)
			(thermal_bridge_width 0.5)
			(island_removal_mode 0)
		)
		(polygon
			(pts
				(xy 47.034704 -238.725202) (xy 48.533304 -238.725202) (xy 48.533304 -239.24514) (xy 47.034704 -239.24514)
			)
		)
	)
	(zone
		(layer "In2.Cu")
		(hatch none 0.5)
		(connect_pads
			(clearance 0)
		)
		(min_thickness 0.25)
		(keepout
			(tracks not_allowed)
			(vias allowed)
			(pads allowed)
			(copperpour not_allowed)
			(footprints allowed)
		)
		(placement
			(enabled no)
			(sheetname "")
		)
		(fill
			(thermal_gap 0.5)
			(thermal_bridge_width 0.5)
			(island_removal_mode 0)
		)
		(polygon
			(pts
				(xy 24.402542 -218.325192) (xy 25.901142 -218.325192) (xy 25.901142 -218.84513) (xy 24.402542 -218.84513)
			)
		)
	)
	(zone
		(layer "In2.Cu")
		(hatch none 0.5)
		(connect_pads
			(clearance 0)
		)
		(min_thickness 0.25)
		(keepout
			(tracks not_allowed)
			(vias allowed)
			(pads allowed)
			(copperpour not_allowed)
			(footprints allowed)
		)
		(placement
			(enabled no)
			(sheetname "")
		)
		(fill
			(thermal_gap 0.5)
			(thermal_bridge_width 0.5)
			(island_removal_mode 0)
		)
		(polygon
			(pts
				(xy 283.986732 -276.125178) (xy 285.485332 -276.125178) (xy 285.485332 -276.645116) (xy 283.986732 -276.645116)
			)
		)
	)
	(zone
		(layer "In2.Cu")
		(hatch none 0.5)
		(connect_pads
			(clearance 0)
		)
		(min_thickness 0.25)
		(keepout
			(tracks not_allowed)
			(vias allowed)
			(pads allowed)
			(copperpour not_allowed)
			(footprints allowed)
		)
		(placement
			(enabled no)
			(sheetname "")
		)
		(fill
			(thermal_gap 0.5)
			(thermal_bridge_width 0.5)
			(island_removal_mode 0)
		)
		(polygon
			(pts
				(xy 276.442932 -294.825166) (xy 277.941532 -294.825166) (xy 277.941532 -295.345104) (xy 276.442932 -295.345104)
			)
		)
	)
	(zone
		(layer "In2.Cu")
		(hatch none 0.5)
		(connect_pads
			(clearance 0)
		)
		(min_thickness 0.25)
		(keepout
			(tracks not_allowed)
			(vias allowed)
			(pads allowed)
			(copperpour not_allowed)
			(footprints allowed)
		)
		(placement
			(enabled no)
			(sheetname "")
		)
		(fill
			(thermal_gap 0.5)
			(thermal_bridge_width 0.5)
			(island_removal_mode 0)
		)
		(polygon
			(pts
				(xy 279.886664 -288.025332) (xy 281.385264 -288.025332) (xy 281.385264 -288.54527) (xy 279.886664 -288.54527)
			)
		)
	)
	(zone
		(layer "In2.Cu")
		(hatch none 0.5)
		(connect_pads
			(clearance 0)
		)
		(min_thickness 0.25)
		(keepout
			(tracks not_allowed)
			(vias allowed)
			(pads allowed)
			(copperpour not_allowed)
			(footprints allowed)
		)
		(placement
			(enabled no)
			(sheetname "")
		)
		(fill
			(thermal_gap 0.5)
			(thermal_bridge_width 0.5)
			(island_removal_mode 0)
		)
		(polygon
			(pts
				(xy 31.946596 -227.675186) (xy 33.445196 -227.675186) (xy 33.445196 -228.195124) (xy 31.946596 -228.195124)
			)
		)
	)
	(zone
		(layer "In2.Cu")
		(hatch none 0.5)
		(connect_pads
			(clearance 0)
		)
		(min_thickness 0.25)
		(keepout
			(tracks not_allowed)
			(vias allowed)
			(pads allowed)
			(copperpour not_allowed)
			(footprints allowed)
		)
		(placement
			(enabled no)
			(sheetname "")
		)
		(fill
			(thermal_gap 0.5)
			(thermal_bridge_width 0.5)
			(island_removal_mode 0)
		)
		(polygon
			(pts
				(arc
					(start 41.751758 -11.91768)
					(mid 41.72944 -11.971562)
					(end 41.675558 -11.99388)
				)
				(arc
					(start 40.638984 -11.99388)
					(mid 40.585102 -11.971562)
					(end 40.562784 -11.91768)
				)
				(arc
					(start 40.562784 -10.51814)
					(mid 40.585102 -10.464258)
					(end 40.638984 -10.44194)
				)
				(arc
					(start 41.675558 -10.44194)
					(mid 41.72944 -10.464258)
					(end 41.751758 -10.51814)
				)
			)
		)
	)
	(zone
		(layer "In2.Cu")
		(hatch none 0.5)
		(connect_pads
			(clearance 0)
		)
		(min_thickness 0.25)
		(keepout
			(tracks not_allowed)
			(vias allowed)
			(pads allowed)
			(copperpour not_allowed)
			(footprints allowed)
		)
		(placement
			(enabled no)
			(sheetname "")
		)
		(fill
			(thermal_gap 0.5)
			(thermal_bridge_width 0.5)
			(island_removal_mode 0)
		)
		(polygon
			(pts
				(xy 31.946596 -251.47524) (xy 33.445196 -251.47524) (xy 33.445196 -251.995178) (xy 31.946596 -251.995178)
			)
		)
	)
	(zone
		(layer "In2.Cu")
		(hatch none 0.5)
		(connect_pads
			(clearance 0)
		)
		(min_thickness 0.25)
		(keepout
			(tracks not_allowed)
			(vias allowed)
			(pads allowed)
			(copperpour not_allowed)
			(footprints allowed)
		)
		(placement
			(enabled no)
			(sheetname "")
		)
		(fill
			(thermal_gap 0.5)
			(thermal_bridge_width 0.5)
			(island_removal_mode 0)
		)
		(polygon
			(pts
				(xy 58.678826 -219.17533) (xy 60.177426 -219.17533) (xy 60.177426 -219.695268) (xy 58.678826 -219.695268)
			)
		)
	)
	(zone
		(layer "In2.Cu")
		(hatch none 0.5)
		(connect_pads
			(clearance 0)
		)
		(min_thickness 0.25)
		(keepout
			(tracks allowed)
			(vias allowed)
			(pads allowed)
			(copperpour allowed)
			(footprints allowed)
		)
		(placement
			(enabled no)
			(sheetname "")
		)
		(fill
			(thermal_gap 0.5)
			(thermal_bridge_width 0.5)
			(island_removal_mode 0)
		)
		(polygon
			(pts
				(xy 313.338972 -338.217256) (xy 313.338972 -337.594956) (xy 313.890152 -337.594956) (xy 313.890152 -338.217256)
			)
		)
	)
	(zone
		(layer "In2.Cu")
		(hatch none 0.5)
		(connect_pads
			(clearance 0)
		)
		(min_thickness 0.25)
		(keepout
			(tracks not_allowed)
			(vias allowed)
			(pads allowed)
			(copperpour not_allowed)
			(footprints allowed)
		)
		(placement
			(enabled no)
			(sheetname "")
		)
		(fill
			(thermal_gap 0.5)
			(thermal_bridge_width 0.5)
			(island_removal_mode 0)
		)
		(polygon
			(pts
				(xy 47.034704 -239.57534) (xy 48.533304 -239.57534) (xy 48.533304 -240.095278) (xy 47.034704 -240.095278)
			)
		)
	)
	(zone
		(layer "In2.Cu")
		(hatch none 0.5)
		(connect_pads
			(clearance 0)
		)
		(min_thickness 0.25)
		(keepout
			(tracks not_allowed)
			(vias allowed)
			(pads allowed)
			(copperpour not_allowed)
			(footprints allowed)
		)
		(placement
			(enabled no)
			(sheetname "")
		)
		(fill
			(thermal_gap 0.5)
			(thermal_bridge_width 0.5)
			(island_removal_mode 0)
		)
		(polygon
			(pts
				(xy 411.618684 -251.47524) (xy 413.117284 -251.47524) (xy 413.117284 -251.995178) (xy 411.618684 -251.995178)
			)
		)
	)
	(zone
		(layer "In2.Cu")
		(hatch none 0.5)
		(connect_pads
			(clearance 0)
		)
		(min_thickness 0.25)
		(keepout
			(tracks not_allowed)
			(vias allowed)
			(pads allowed)
			(copperpour not_allowed)
			(footprints allowed)
		)
		(placement
			(enabled no)
			(sheetname "")
		)
		(fill
			(thermal_gap 0.5)
			(thermal_bridge_width 0.5)
			(island_removal_mode 0)
		)
		(polygon
			(pts
				(xy 306.618894 -220.025214) (xy 308.117494 -220.025214) (xy 308.117494 -220.545152) (xy 306.618894 -220.545152)
			)
		)
	)
	(zone
		(layer "In2.Cu")
		(hatch none 0.5)
		(connect_pads
			(clearance 0)
		)
		(min_thickness 0.25)
		(keepout
			(tracks not_allowed)
			(vias allowed)
			(pads allowed)
			(copperpour not_allowed)
			(footprints allowed)
		)
		(placement
			(enabled no)
			(sheetname "")
		)
		(fill
			(thermal_gap 0.5)
			(thermal_bridge_width 0.5)
			(island_removal_mode 0)
		)
		(polygon
			(pts
				(xy 58.678826 -208.125314) (xy 60.177426 -208.125314) (xy 60.177426 -208.645252) (xy 58.678826 -208.645252)
			)
		)
	)
	(zone
		(layer "In2.Cu")
		(hatch none 0.5)
		(connect_pads
			(clearance 0)
		)
		(min_thickness 0.25)
		(keepout
			(tracks not_allowed)
			(vias allowed)
			(pads allowed)
			(copperpour not_allowed)
			(footprints allowed)
		)
		(placement
			(enabled no)
			(sheetname "")
		)
		(fill
			(thermal_gap 0.5)
			(thermal_bridge_width 0.5)
			(island_removal_mode 0)
		)
		(polygon
			(pts
				(xy 276.442932 -269.325344) (xy 277.941532 -269.325344) (xy 277.941532 -269.845282) (xy 276.442932 -269.845282)
			)
		)
	)
	(zone
		(layer "In2.Cu")
		(hatch none 0.5)
		(connect_pads
			(clearance 0)
		)
		(min_thickness 0.25)
		(keepout
			(tracks not_allowed)
			(vias allowed)
			(pads allowed)
			(copperpour not_allowed)
			(footprints allowed)
		)
		(placement
			(enabled no)
			(sheetname "")
		)
		(fill
			(thermal_gap 0.5)
			(thermal_bridge_width 0.5)
			(island_removal_mode 0)
		)
		(polygon
			(pts
				(xy 415.718752 -294.825166) (xy 417.217352 -294.825166) (xy 417.217352 -295.345104) (xy 415.718752 -295.345104)
			)
		)
	)
	(zone
		(layer "In2.Cu")
		(hatch none 0.5)
		(connect_pads
			(clearance 0)
		)
		(min_thickness 0.25)
		(keepout
			(tracks not_allowed)
			(vias allowed)
			(pads allowed)
			(copperpour not_allowed)
			(footprints allowed)
		)
		(placement
			(enabled no)
			(sheetname "")
		)
		(fill
			(thermal_gap 0.5)
			(thermal_bridge_width 0.5)
			(island_removal_mode 0)
		)
		(polygon
			(pts
				(xy 415.718752 -310.975248) (xy 417.217352 -310.975248) (xy 417.217352 -311.495186) (xy 415.718752 -311.495186)
			)
		)
	)
	(zone
		(layer "In2.Cu")
		(hatch none 0.5)
		(connect_pads
			(clearance 0)
		)
		(min_thickness 0.25)
		(keepout
			(tracks not_allowed)
			(vias allowed)
			(pads allowed)
			(copperpour not_allowed)
			(footprints allowed)
		)
		(placement
			(enabled no)
			(sheetname "")
		)
		(fill
			(thermal_gap 0.5)
			(thermal_bridge_width 0.5)
			(island_removal_mode 0)
		)
		(polygon
			(pts
				(xy 299.07484 -236.175296) (xy 300.57344 -236.175296) (xy 300.57344 -236.695234) (xy 299.07484 -236.695234)
			)
		)
	)
	(zone
		(layer "In2.Cu")
		(hatch none 0.5)
		(connect_pads
			(clearance 0)
		)
		(min_thickness 0.25)
		(keepout
			(tracks not_allowed)
			(vias allowed)
			(pads allowed)
			(copperpour not_allowed)
			(footprints allowed)
		)
		(placement
			(enabled no)
			(sheetname "")
		)
		(fill
			(thermal_gap 0.5)
			(thermal_bridge_width 0.5)
			(island_removal_mode 0)
		)
		(polygon
			(pts
				(xy 51.134772 -287.175194) (xy 52.633372 -287.175194) (xy 52.633372 -287.695132) (xy 51.134772 -287.695132)
			)
		)
	)
	(zone
		(layer "In2.Cu")
		(hatch none 0.5)
		(connect_pads
			(clearance 0)
		)
		(min_thickness 0.25)
		(keepout
			(tracks not_allowed)
			(vias allowed)
			(pads allowed)
			(copperpour not_allowed)
			(footprints allowed)
		)
		(placement
			(enabled no)
			(sheetname "")
		)
		(fill
			(thermal_gap 0.5)
			(thermal_bridge_width 0.5)
			(island_removal_mode 0)
		)
		(polygon
			(pts
				(xy 423.262806 -265.9253) (xy 424.761406 -265.9253) (xy 424.761406 -266.445238) (xy 423.262806 -266.445238)
			)
		)
	)
	(zone
		(layer "In2.Cu")
		(hatch none 0.5)
		(connect_pads
			(clearance 0)
		)
		(min_thickness 0.25)
		(keepout
			(tracks not_allowed)
			(vias allowed)
			(pads allowed)
			(copperpour not_allowed)
			(footprints allowed)
		)
		(placement
			(enabled no)
			(sheetname "")
		)
		(fill
			(thermal_gap 0.5)
			(thermal_bridge_width 0.5)
			(island_removal_mode 0)
		)
		(polygon
			(pts
				(xy 426.706792 -299.075348) (xy 428.205392 -299.075348) (xy 428.205392 -299.595286) (xy 426.706792 -299.595286)
			)
		)
	)
	(zone
		(layer "In2.Cu")
		(hatch none 0.5)
		(connect_pads
			(clearance 0)
		)
		(min_thickness 0.25)
		(keepout
			(tracks not_allowed)
			(vias allowed)
			(pads allowed)
			(copperpour not_allowed)
			(footprints allowed)
		)
		(placement
			(enabled no)
			(sheetname "")
		)
		(fill
			(thermal_gap 0.5)
			(thermal_bridge_width 0.5)
			(island_removal_mode 0)
		)
		(polygon
			(pts
				(xy 449.3387 -283.77515) (xy 450.8373 -283.77515) (xy 450.8373 -284.295088) (xy 449.3387 -284.295088)
			)
		)
	)
	(zone
		(layer "In2.Cu")
		(hatch none 0.5)
		(connect_pads
			(clearance 0)
		)
		(min_thickness 0.25)
		(keepout
			(tracks not_allowed)
			(vias allowed)
			(pads allowed)
			(copperpour not_allowed)
			(footprints allowed)
		)
		(placement
			(enabled no)
			(sheetname "")
		)
		(fill
			(thermal_gap 0.5)
			(thermal_bridge_width 0.5)
			(island_removal_mode 0)
		)
		(polygon
			(pts
				(xy 186.310778 -214.925148) (xy 187.809378 -214.925148) (xy 187.809378 -215.445086) (xy 186.310778 -215.445086)
			)
		)
	)
	(zone
		(layer "In2.Cu")
		(hatch none 0.5)
		(connect_pads
			(clearance 0)
		)
		(min_thickness 0.25)
		(keepout
			(tracks not_allowed)
			(vias allowed)
			(pads allowed)
			(copperpour not_allowed)
			(footprints allowed)
		)
		(placement
			(enabled no)
			(sheetname "")
		)
		(fill
			(thermal_gap 0.5)
			(thermal_bridge_width 0.5)
			(island_removal_mode 0)
		)
		(polygon
			(pts
				(xy 171.22267 -280.375106) (xy 172.72127 -280.375106) (xy 172.72127 -280.895044) (xy 171.22267 -280.895044)
			)
		)
	)
	(zone
		(layer "In2.Cu")
		(hatch none 0.5)
		(connect_pads
			(clearance 0)
		)
		(min_thickness 0.25)
		(keepout
			(tracks not_allowed)
			(vias allowed)
			(pads allowed)
			(copperpour not_allowed)
			(footprints allowed)
		)
		(placement
			(enabled no)
			(sheetname "")
		)
		(fill
			(thermal_gap 0.5)
			(thermal_bridge_width 0.5)
			(island_removal_mode 0)
		)
		(polygon
			(pts
				(xy 438.350914 -307.575204) (xy 439.849514 -307.575204) (xy 439.849514 -308.095142) (xy 438.350914 -308.095142)
			)
		)
	)
	(zone
		(layer "In2.Cu")
		(hatch none 0.5)
		(connect_pads
			(clearance 0)
		)
		(min_thickness 0.25)
		(keepout
			(tracks not_allowed)
			(vias allowed)
			(pads allowed)
			(copperpour not_allowed)
			(footprints allowed)
		)
		(placement
			(enabled no)
			(sheetname "")
		)
		(fill
			(thermal_gap 0.5)
			(thermal_bridge_width 0.5)
			(island_removal_mode 0)
		)
		(polygon
			(pts
				(xy 445.894968 -204.72527) (xy 447.393568 -204.72527) (xy 447.393568 -205.245208) (xy 445.894968 -205.245208)
			)
		)
	)
	(zone
		(layer "In2.Cu")
		(hatch none 0.5)
		(connect_pads
			(clearance 0)
		)
		(min_thickness 0.25)
		(keepout
			(tracks not_allowed)
			(vias allowed)
			(pads allowed)
			(copperpour not_allowed)
			(footprints allowed)
		)
		(placement
			(enabled no)
			(sheetname "")
		)
		(fill
			(thermal_gap 0.5)
			(thermal_bridge_width 0.5)
			(island_removal_mode 0)
		)
		(polygon
			(pts
				(xy 186.310778 -242.97513) (xy 187.809378 -242.97513) (xy 187.809378 -243.495068) (xy 186.310778 -243.495068)
			)
		)
	)
	(zone
		(layer "In2.Cu")
		(hatch none 0.5)
		(connect_pads
			(clearance 0)
		)
		(min_thickness 0.25)
		(keepout
			(tracks not_allowed)
			(vias allowed)
			(pads allowed)
			(copperpour not_allowed)
			(footprints allowed)
		)
		(placement
			(enabled no)
			(sheetname "")
		)
		(fill
			(thermal_gap 0.5)
			(thermal_bridge_width 0.5)
			(island_removal_mode 0)
		)
		(polygon
			(pts
				(xy 445.894968 -287.175194) (xy 447.393568 -287.175194) (xy 447.393568 -287.695132) (xy 445.894968 -287.695132)
			)
		)
	)
	(zone
		(layer "In2.Cu")
		(hatch none 0.5)
		(connect_pads
			(clearance 0)
		)
		(min_thickness 0.25)
		(keepout
			(tracks not_allowed)
			(vias allowed)
			(pads allowed)
			(copperpour not_allowed)
			(footprints allowed)
		)
		(placement
			(enabled no)
			(sheetname "")
		)
		(fill
			(thermal_gap 0.5)
			(thermal_bridge_width 0.5)
			(island_removal_mode 0)
		)
		(polygon
			(pts
				(xy 415.718752 -269.325344) (xy 417.217352 -269.325344) (xy 417.217352 -269.845282) (xy 415.718752 -269.845282)
			)
		)
	)
	(zone
		(layer "In2.Cu")
		(hatch none 0.5)
		(connect_pads
			(clearance 0)
		)
		(min_thickness 0.25)
		(keepout
			(tracks not_allowed)
			(vias allowed)
			(pads allowed)
			(copperpour not_allowed)
			(footprints allowed)
		)
		(placement
			(enabled no)
			(sheetname "")
		)
		(fill
			(thermal_gap 0.5)
			(thermal_bridge_width 0.5)
			(island_removal_mode 0)
		)
		(polygon
			(pts
				(xy 411.618684 -295.675304) (xy 413.117284 -295.675304) (xy 413.117284 -296.195242) (xy 411.618684 -296.195242)
			)
		)
	)
	(zone
		(layer "In2.Cu")
		(hatch none 0.5)
		(connect_pads
			(clearance 0)
		)
		(min_thickness 0.25)
		(keepout
			(tracks not_allowed)
			(vias allowed)
			(pads allowed)
			(copperpour not_allowed)
			(footprints allowed)
		)
		(placement
			(enabled no)
			(sheetname "")
		)
		(fill
			(thermal_gap 0.5)
			(thermal_bridge_width 0.5)
			(island_removal_mode 0)
		)
		(polygon
			(pts
				(xy 441.7949 -300.775116) (xy 443.2935 -300.775116) (xy 443.2935 -301.295054) (xy 441.7949 -301.295054)
			)
		)
	)
	(zone
		(layer "In2.Cu")
		(hatch none 0.5)
		(connect_pads
			(clearance 0)
		)
		(min_thickness 0.25)
		(keepout
			(tracks not_allowed)
			(vias allowed)
			(pads allowed)
			(copperpour not_allowed)
			(footprints allowed)
		)
		(placement
			(enabled no)
			(sheetname "")
		)
		(fill
			(thermal_gap 0.5)
			(thermal_bridge_width 0.5)
			(island_removal_mode 0)
		)
		(polygon
			(pts
				(xy 445.894968 -252.325124) (xy 447.393568 -252.325124) (xy 447.393568 -252.845062) (xy 445.894968 -252.845062)
			)
		)
	)
	(zone
		(layer "In2.Cu")
		(hatch none 0.5)
		(connect_pads
			(clearance 0)
		)
		(min_thickness 0.25)
		(keepout
			(tracks allowed)
			(vias allowed)
			(pads allowed)
			(copperpour allowed)
			(footprints allowed)
		)
		(placement
			(enabled no)
			(sheetname "")
		)
		(fill
			(thermal_gap 0.5)
			(thermal_bridge_width 0.5)
			(island_removal_mode 0)
		)
		(polygon
			(pts
				(xy 383.522728 -180.14696) (xy 383.522728 -179.600606) (xy 384.075178 -179.600606) (xy 384.075178 -180.14696)
			)
		)
	)
	(zone
		(layer "In2.Cu")
		(hatch none 0.5)
		(connect_pads
			(clearance 0)
		)
		(min_thickness 0.25)
		(keepout
			(tracks not_allowed)
			(vias allowed)
			(pads allowed)
			(copperpour not_allowed)
			(footprints allowed)
		)
		(placement
			(enabled no)
			(sheetname "")
		)
		(fill
			(thermal_gap 0.5)
			(thermal_bridge_width 0.5)
			(island_removal_mode 0)
		)
		(polygon
			(pts
				(xy 445.894968 -247.225312) (xy 447.393568 -247.225312) (xy 447.393568 -247.74525) (xy 445.894968 -247.74525)
			)
		)
	)
	(zone
		(layer "In2.Cu")
		(hatch none 0.5)
		(connect_pads
			(clearance 0)
		)
		(min_thickness 0.25)
		(keepout
			(tracks not_allowed)
			(vias allowed)
			(pads allowed)
			(copperpour not_allowed)
			(footprints allowed)
		)
		(placement
			(enabled no)
			(sheetname "")
		)
		(fill
			(thermal_gap 0.5)
			(thermal_bridge_width 0.5)
			(island_removal_mode 0)
		)
		(polygon
			(pts
				(xy 441.7949 -238.725202) (xy 443.2935 -238.725202) (xy 443.2935 -239.24514) (xy 441.7949 -239.24514)
			)
		)
	)
	(zone
		(layer "In2.Cu")
		(hatch none 0.5)
		(connect_pads
			(clearance 0)
		)
		(min_thickness 0.25)
		(keepout
			(tracks not_allowed)
			(vias allowed)
			(pads allowed)
			(copperpour not_allowed)
			(footprints allowed)
		)
		(placement
			(enabled no)
			(sheetname "")
		)
		(fill
			(thermal_gap 0.5)
			(thermal_bridge_width 0.5)
			(island_removal_mode 0)
		)
		(polygon
			(pts
				(xy 24.402542 -317.775336) (xy 25.901142 -317.775336) (xy 25.901142 -318.295274) (xy 24.402542 -318.295274)
			)
		)
	)
	(zone
		(layer "In2.Cu")
		(hatch none 0.5)
		(connect_pads
			(clearance 0)
		)
		(min_thickness 0.25)
		(keepout
			(tracks allowed)
			(vias allowed)
			(pads allowed)
			(copperpour allowed)
			(footprints allowed)
		)
		(placement
			(enabled no)
			(sheetname "")
		)
		(fill
			(thermal_gap 0.5)
			(thermal_bridge_width 0.5)
			(island_removal_mode 0)
		)
		(polygon
			(pts
				(xy 100.72624 -343.161366) (xy 100.72624 -342.539066) (xy 101.27742 -342.539066) (xy 101.27742 -343.161366)
			)
		)
	)
	(zone
		(layer "In2.Cu")
		(hatch none 0.5)
		(connect_pads
			(clearance 0)
		)
		(min_thickness 0.25)
		(keepout
			(tracks not_allowed)
			(vias allowed)
			(pads allowed)
			(copperpour not_allowed)
			(footprints allowed)
		)
		(placement
			(enabled no)
			(sheetname "")
		)
		(fill
			(thermal_gap 0.5)
			(thermal_bridge_width 0.5)
			(island_removal_mode 0)
		)
		(polygon
			(pts
				(xy 299.07484 -290.575238) (xy 300.57344 -290.575238) (xy 300.57344 -291.095176) (xy 299.07484 -291.095176)
			)
		)
	)
	(zone
		(layer "In2.Cu")
		(hatch none 0.5)
		(connect_pads
			(clearance 0)
		)
		(min_thickness 0.25)
		(keepout
			(tracks not_allowed)
			(vias allowed)
			(pads allowed)
			(copperpour not_allowed)
			(footprints allowed)
		)
		(placement
			(enabled no)
			(sheetname "")
		)
		(fill
			(thermal_gap 0.5)
			(thermal_bridge_width 0.5)
			(island_removal_mode 0)
		)
		(polygon
			(pts
				(xy 445.894968 -315.225176) (xy 447.393568 -315.225176) (xy 447.393568 -315.745114) (xy 445.894968 -315.745114)
			)
		)
	)
	(zone
		(layer "In2.Cu")
		(hatch none 0.5)
		(connect_pads
			(clearance 0)
		)
		(min_thickness 0.25)
		(keepout
			(tracks not_allowed)
			(vias allowed)
			(pads allowed)
			(copperpour not_allowed)
			(footprints allowed)
		)
		(placement
			(enabled no)
			(sheetname "")
		)
		(fill
			(thermal_gap 0.5)
			(thermal_bridge_width 0.5)
			(island_removal_mode 0)
		)
		(polygon
			(pts
				(xy 167.778684 -309.275226) (xy 169.277284 -309.275226) (xy 169.277284 -309.795164) (xy 167.778684 -309.795164)
			)
		)
	)
	(zone
		(layer "In2.Cu")
		(hatch none 0.5)
		(connect_pads
			(clearance 0)
		)
		(min_thickness 0.25)
		(keepout
			(tracks not_allowed)
			(vias allowed)
			(pads allowed)
			(copperpour not_allowed)
			(footprints allowed)
		)
		(placement
			(enabled no)
			(sheetname "")
		)
		(fill
			(thermal_gap 0.5)
			(thermal_bridge_width 0.5)
			(island_removal_mode 0)
		)
		(polygon
			(pts
				(xy 135.555228 -15.82674) (xy 136.536176 -15.82674) (xy 136.536176 -17.27454) (xy 135.555228 -17.27454)
			)
		)
	)
	(zone
		(layer "In2.Cu")
		(hatch none 0.5)
		(connect_pads
			(clearance 0)
		)
		(min_thickness 0.25)
		(keepout
			(tracks not_allowed)
			(vias allowed)
			(pads allowed)
			(copperpour not_allowed)
			(footprints allowed)
		)
		(placement
			(enabled no)
			(sheetname "")
		)
		(fill
			(thermal_gap 0.5)
			(thermal_bridge_width 0.5)
			(island_removal_mode 0)
		)
		(polygon
			(pts
				(xy 272.342864 -300.775116) (xy 273.841464 -300.775116) (xy 273.841464 -301.295054) (xy 272.342864 -301.295054)
			)
		)
	)
	(zone
		(layer "In2.Cu")
		(hatch none 0.5)
		(connect_pads
			(clearance 0)
		)
		(min_thickness 0.25)
		(keepout
			(tracks not_allowed)
			(vias allowed)
			(pads allowed)
			(copperpour not_allowed)
			(footprints allowed)
		)
		(placement
			(enabled no)
			(sheetname "")
		)
		(fill
			(thermal_gap 0.5)
			(thermal_bridge_width 0.5)
			(island_removal_mode 0)
		)
		(polygon
			(pts
				(xy 167.778684 -212.375242) (xy 169.277284 -212.375242) (xy 169.277284 -212.89518) (xy 167.778684 -212.89518)
			)
		)
	)
	(zone
		(layer "In2.Cu")
		(hatch none 0.5)
		(connect_pads
			(clearance 0)
		)
		(min_thickness 0.25)
		(keepout
			(tracks not_allowed)
			(vias allowed)
			(pads allowed)
			(copperpour not_allowed)
			(footprints allowed)
		)
		(placement
			(enabled no)
			(sheetname "")
		)
		(fill
			(thermal_gap 0.5)
			(thermal_bridge_width 0.5)
			(island_removal_mode 0)
		)
		(polygon
			(pts
				(xy 438.350914 -269.325344) (xy 439.849514 -269.325344) (xy 439.849514 -269.845282) (xy 438.350914 -269.845282)
			)
		)
	)
	(zone
		(layer "In2.Cu")
		(hatch none 0.5)
		(connect_pads
			(clearance 0)
		)
		(min_thickness 0.25)
		(keepout
			(tracks not_allowed)
			(vias allowed)
			(pads allowed)
			(copperpour not_allowed)
			(footprints allowed)
		)
		(placement
			(enabled no)
			(sheetname "")
		)
		(fill
			(thermal_gap 0.5)
			(thermal_bridge_width 0.5)
			(island_removal_mode 0)
		)
		(polygon
			(pts
				(xy 302.518826 -207.275176) (xy 304.017426 -207.275176) (xy 304.017426 -207.795114) (xy 302.518826 -207.795114)
			)
		)
	)
	(zone
		(layer "In2.Cu")
		(hatch none 0.5)
		(connect_pads
			(clearance 0)
		)
		(min_thickness 0.25)
		(keepout
			(tracks not_allowed)
			(vias allowed)
			(pads allowed)
			(copperpour not_allowed)
			(footprints allowed)
		)
		(placement
			(enabled no)
			(sheetname "")
		)
		(fill
			(thermal_gap 0.5)
			(thermal_bridge_width 0.5)
			(island_removal_mode 0)
		)
		(polygon
			(pts
				(xy 193.854578 -205.575154) (xy 195.353178 -205.575154) (xy 195.353178 -206.095092) (xy 193.854578 -206.095092)
			)
		)
	)
	(zone
		(layer "In2.Cu")
		(hatch none 0.5)
		(connect_pads
			(clearance 0)
		)
		(min_thickness 0.25)
		(keepout
			(tracks not_allowed)
			(vias allowed)
			(pads allowed)
			(copperpour not_allowed)
			(footprints allowed)
		)
		(placement
			(enabled no)
			(sheetname "")
		)
		(fill
			(thermal_gap 0.5)
			(thermal_bridge_width 0.5)
			(island_removal_mode 0)
		)
		(polygon
			(pts
				(xy 175.322738 -281.225244) (xy 176.821338 -281.225244) (xy 176.821338 -281.745182) (xy 175.322738 -281.745182)
			)
		)
	)
	(zone
		(layer "In2.Cu")
		(hatch none 0.5)
		(connect_pads
			(clearance 0)
		)
		(min_thickness 0.25)
		(keepout
			(tracks not_allowed)
			(vias allowed)
			(pads allowed)
			(copperpour not_allowed)
			(footprints allowed)
		)
		(placement
			(enabled no)
			(sheetname "")
		)
		(fill
			(thermal_gap 0.5)
			(thermal_bridge_width 0.5)
			(island_removal_mode 0)
		)
		(polygon
			(pts
				(xy 423.262806 -243.825268) (xy 424.761406 -243.825268) (xy 424.761406 -244.345206) (xy 423.262806 -244.345206)
			)
		)
	)
	(zone
		(layer "In2.Cu")
		(hatch none 0.5)
		(connect_pads
			(clearance 0)
		)
		(min_thickness 0.25)
		(keepout
			(tracks not_allowed)
			(vias allowed)
			(pads allowed)
			(copperpour not_allowed)
			(footprints allowed)
		)
		(placement
			(enabled no)
			(sheetname "")
		)
		(fill
			(thermal_gap 0.5)
			(thermal_bridge_width 0.5)
			(island_removal_mode 0)
		)
		(polygon
			(pts
				(xy 58.678826 -294.825166) (xy 60.177426 -294.825166) (xy 60.177426 -295.345104) (xy 58.678826 -295.345104)
			)
		)
	)
	(zone
		(layer "In2.Cu")
		(hatch none 0.5)
		(connect_pads
			(clearance 0)
		)
		(min_thickness 0.25)
		(keepout
			(tracks not_allowed)
			(vias allowed)
			(pads allowed)
			(copperpour not_allowed)
			(footprints allowed)
		)
		(placement
			(enabled no)
			(sheetname "")
		)
		(fill
			(thermal_gap 0.5)
			(thermal_bridge_width 0.5)
			(island_removal_mode 0)
		)
		(polygon
			(pts
				(xy 306.618894 -252.325124) (xy 308.117494 -252.325124) (xy 308.117494 -252.845062) (xy 306.618894 -252.845062)
			)
		)
	)
	(zone
		(layer "In2.Cu")
		(hatch none 0.5)
		(connect_pads
			(clearance 0)
		)
		(min_thickness 0.25)
		(keepout
			(tracks not_allowed)
			(vias allowed)
			(pads allowed)
			(copperpour not_allowed)
			(footprints allowed)
		)
		(placement
			(enabled no)
			(sheetname "")
		)
		(fill
			(thermal_gap 0.5)
			(thermal_bridge_width 0.5)
			(island_removal_mode 0)
		)
		(polygon
			(pts
				(xy 51.134772 -313.525154) (xy 52.633372 -313.525154) (xy 52.633372 -314.045092) (xy 51.134772 -314.045092)
			)
		)
	)
	(zone
		(layer "In2.Cu")
		(hatch none 0.5)
		(connect_pads
			(clearance 0)
		)
		(min_thickness 0.25)
		(keepout
			(tracks not_allowed)
			(vias allowed)
			(pads allowed)
			(copperpour not_allowed)
			(footprints allowed)
		)
		(placement
			(enabled no)
			(sheetname "")
		)
		(fill
			(thermal_gap 0.5)
			(thermal_bridge_width 0.5)
			(island_removal_mode 0)
		)
		(polygon
			(pts
				(xy 54.578758 -210.67522) (xy 56.077358 -210.67522) (xy 56.077358 -211.195158) (xy 54.578758 -211.195158)
			)
		)
	)
	(zone
		(layer "In2.Cu")
		(hatch none 0.5)
		(connect_pads
			(clearance 0)
		)
		(min_thickness 0.25)
		(keepout
			(tracks not_allowed)
			(vias allowed)
			(pads allowed)
			(copperpour not_allowed)
			(footprints allowed)
		)
		(placement
			(enabled no)
			(sheetname "")
		)
		(fill
			(thermal_gap 0.5)
			(thermal_bridge_width 0.5)
			(island_removal_mode 0)
		)
		(polygon
			(pts
				(xy 419.162738 -272.725134) (xy 420.661338 -272.725134) (xy 420.661338 -273.245072) (xy 419.162738 -273.245072)
			)
		)
	)
	(zone
		(layer "In2.Cu")
		(hatch none 0.5)
		(connect_pads
			(clearance 0)
		)
		(min_thickness 0.25)
		(keepout
			(tracks allowed)
			(vias allowed)
			(pads allowed)
			(copperpour allowed)
			(footprints allowed)
		)
		(placement
			(enabled no)
			(sheetname "")
		)
		(fill
			(thermal_gap 0.5)
			(thermal_bridge_width 0.5)
			(island_removal_mode 0)
		)
		(polygon
			(pts
				(xy 82.197194 -338.867496) (xy 82.197194 -338.245196) (xy 82.748374 -338.245196) (xy 82.748374 -338.867496)
			)
		)
	)
	(zone
		(layer "In2.Cu")
		(hatch none 0.5)
		(connect_pads
			(clearance 0)
		)
		(min_thickness 0.25)
		(keepout
			(tracks not_allowed)
			(vias allowed)
			(pads allowed)
			(copperpour not_allowed)
			(footprints allowed)
		)
		(placement
			(enabled no)
			(sheetname "")
		)
		(fill
			(thermal_gap 0.5)
			(thermal_bridge_width 0.5)
			(island_removal_mode 0)
		)
		(polygon
			(pts
				(xy 430.80686 -223.425258) (xy 432.30546 -223.425258) (xy 432.30546 -223.945196) (xy 430.80686 -223.945196)
			)
		)
	)
	(zone
		(layer "In2.Cu")
		(hatch none 0.5)
		(connect_pads
			(clearance 0)
		)
		(min_thickness 0.25)
		(keepout
			(tracks not_allowed)
			(vias allowed)
			(pads allowed)
			(copperpour not_allowed)
			(footprints allowed)
		)
		(placement
			(enabled no)
			(sheetname "")
		)
		(fill
			(thermal_gap 0.5)
			(thermal_bridge_width 0.5)
			(island_removal_mode 0)
		)
		(polygon
			(pts
				(xy 31.946596 -220.875098) (xy 33.445196 -220.875098) (xy 33.445196 -221.395036) (xy 31.946596 -221.395036)
			)
		)
	)
	(zone
		(layer "In2.Cu")
		(hatch none 0.5)
		(connect_pads
			(clearance 0)
		)
		(min_thickness 0.25)
		(keepout
			(tracks not_allowed)
			(vias allowed)
			(pads allowed)
			(copperpour not_allowed)
			(footprints allowed)
		)
		(placement
			(enabled no)
			(sheetname "")
		)
		(fill
			(thermal_gap 0.5)
			(thermal_bridge_width 0.5)
			(island_removal_mode 0)
		)
		(polygon
			(pts
				(xy 31.946596 -218.325192) (xy 33.445196 -218.325192) (xy 33.445196 -218.84513) (xy 31.946596 -218.84513)
			)
		)
	)
	(zone
		(layer "In2.Cu")
		(hatch none 0.5)
		(connect_pads
			(clearance 0)
		)
		(min_thickness 0.25)
		(keepout
			(tracks not_allowed)
			(vias allowed)
			(pads allowed)
			(copperpour not_allowed)
			(footprints allowed)
		)
		(placement
			(enabled no)
			(sheetname "")
		)
		(fill
			(thermal_gap 0.5)
			(thermal_bridge_width 0.5)
			(island_removal_mode 0)
		)
		(polygon
			(pts
				(xy 16.858742 -297.375326) (xy 18.357342 -297.375326) (xy 18.357342 -297.895264) (xy 16.858742 -297.895264)
			)
		)
	)
	(zone
		(layer "In2.Cu")
		(hatch none 0.5)
		(connect_pads
			(clearance 0)
		)
		(min_thickness 0.25)
		(keepout
			(tracks not_allowed)
			(vias allowed)
			(pads allowed)
			(copperpour not_allowed)
			(footprints allowed)
		)
		(placement
			(enabled no)
			(sheetname "")
		)
		(fill
			(thermal_gap 0.5)
			(thermal_bridge_width 0.5)
			(island_removal_mode 0)
		)
		(polygon
			(pts
				(xy 294.974772 -222.57512) (xy 296.473372 -222.57512) (xy 296.473372 -223.095058) (xy 294.974772 -223.095058)
			)
		)
	)
	(zone
		(layer "In2.Cu")
		(hatch none 0.5)
		(connect_pads
			(clearance 0)
		)
		(min_thickness 0.25)
		(keepout
			(tracks not_allowed)
			(vias allowed)
			(pads allowed)
			(copperpour not_allowed)
			(footprints allowed)
		)
		(placement
			(enabled no)
			(sheetname "")
		)
		(fill
			(thermal_gap 0.5)
			(thermal_bridge_width 0.5)
			(island_removal_mode 0)
		)
		(polygon
			(pts
				(xy 426.706792 -231.925114) (xy 428.205392 -231.925114) (xy 428.205392 -232.445052) (xy 426.706792 -232.445052)
			)
		)
	)
	(zone
		(layer "In2.Cu")
		(hatch none 0.5)
		(connect_pads
			(clearance 0)
		)
		(min_thickness 0.25)
		(keepout
			(tracks not_allowed)
			(vias allowed)
			(pads allowed)
			(copperpour not_allowed)
			(footprints allowed)
		)
		(placement
			(enabled no)
			(sheetname "")
		)
		(fill
			(thermal_gap 0.5)
			(thermal_bridge_width 0.5)
			(island_removal_mode 0)
		)
		(polygon
			(pts
				(xy 299.07484 -285.475172) (xy 300.57344 -285.475172) (xy 300.57344 -285.99511) (xy 299.07484 -285.99511)
			)
		)
	)
	(zone
		(layer "In2.Cu")
		(hatch none 0.5)
		(connect_pads
			(clearance 0)
		)
		(min_thickness 0.25)
		(keepout
			(tracks not_allowed)
			(vias allowed)
			(pads allowed)
			(copperpour not_allowed)
			(footprints allowed)
		)
		(placement
			(enabled no)
			(sheetname "")
		)
		(fill
			(thermal_gap 0.5)
			(thermal_bridge_width 0.5)
			(island_removal_mode 0)
		)
		(polygon
			(pts
				(xy 411.618684 -220.025214) (xy 413.117284 -220.025214) (xy 413.117284 -220.545152) (xy 411.618684 -220.545152)
			)
		)
	)
	(zone
		(layer "In2.Cu")
		(hatch none 0.5)
		(connect_pads
			(clearance 0)
		)
		(min_thickness 0.25)
		(keepout
			(tracks not_allowed)
			(vias allowed)
			(pads allowed)
			(copperpour not_allowed)
			(footprints allowed)
		)
		(placement
			(enabled no)
			(sheetname "")
		)
		(fill
			(thermal_gap 0.5)
			(thermal_bridge_width 0.5)
			(island_removal_mode 0)
		)
		(polygon
			(pts
				(xy 279.886664 -214.925148) (xy 281.385264 -214.925148) (xy 281.385264 -215.445086) (xy 279.886664 -215.445086)
			)
		)
	)
	(zone
		(layer "In2.Cu")
		(hatch none 0.5)
		(connect_pads
			(clearance 0)
		)
		(min_thickness 0.25)
		(keepout
			(tracks not_allowed)
			(vias allowed)
			(pads allowed)
			(copperpour not_allowed)
			(footprints allowed)
		)
		(placement
			(enabled no)
			(sheetname "")
		)
		(fill
			(thermal_gap 0.5)
			(thermal_bridge_width 0.5)
			(island_removal_mode 0)
		)
		(polygon
			(pts
				(xy 445.894968 -243.825268) (xy 447.393568 -243.825268) (xy 447.393568 -244.345206) (xy 445.894968 -244.345206)
			)
		)
	)
	(zone
		(layer "In2.Cu")
		(hatch none 0.5)
		(connect_pads
			(clearance 0)
		)
		(min_thickness 0.25)
		(keepout
			(tracks not_allowed)
			(vias allowed)
			(pads allowed)
			(copperpour not_allowed)
			(footprints allowed)
		)
		(placement
			(enabled no)
			(sheetname "")
		)
		(fill
			(thermal_gap 0.5)
			(thermal_bridge_width 0.5)
			(island_removal_mode 0)
		)
		(polygon
			(pts
				(xy 47.034704 -225.975164) (xy 48.533304 -225.975164) (xy 48.533304 -226.495102) (xy 47.034704 -226.495102)
			)
		)
	)
	(zone
		(layer "In2.Cu")
		(hatch none 0.5)
		(connect_pads
			(clearance 0)
		)
		(min_thickness 0.25)
		(keepout
			(tracks not_allowed)
			(vias allowed)
			(pads allowed)
			(copperpour not_allowed)
			(footprints allowed)
		)
		(placement
			(enabled no)
			(sheetname "")
		)
		(fill
			(thermal_gap 0.5)
			(thermal_bridge_width 0.5)
			(island_removal_mode 0)
		)
		(polygon
			(pts
				(xy 438.350914 -281.225244) (xy 439.849514 -281.225244) (xy 439.849514 -281.745182) (xy 438.350914 -281.745182)
			)
		)
	)
	(zone
		(layer "In2.Cu")
		(hatch none 0.5)
		(connect_pads
			(clearance 0)
		)
		(min_thickness 0.25)
		(keepout
			(tracks not_allowed)
			(vias allowed)
			(pads allowed)
			(copperpour not_allowed)
			(footprints allowed)
		)
		(placement
			(enabled no)
			(sheetname "")
		)
		(fill
			(thermal_gap 0.5)
			(thermal_bridge_width 0.5)
			(island_removal_mode 0)
		)
		(polygon
			(pts
				(xy 36.046664 -231.07523) (xy 37.545264 -231.07523) (xy 37.545264 -231.595168) (xy 36.046664 -231.595168)
			)
		)
	)
	(zone
		(layer "In2.Cu")
		(hatch none 0.5)
		(connect_pads
			(clearance 0)
		)
		(min_thickness 0.25)
		(keepout
			(tracks not_allowed)
			(vias allowed)
			(pads allowed)
			(copperpour not_allowed)
			(footprints allowed)
		)
		(placement
			(enabled no)
			(sheetname "")
		)
		(fill
			(thermal_gap 0.5)
			(thermal_bridge_width 0.5)
			(island_removal_mode 0)
		)
		(polygon
			(pts
				(xy 415.718752 -315.225176) (xy 417.217352 -315.225176) (xy 417.217352 -315.745114) (xy 415.718752 -315.745114)
			)
		)
	)
	(zone
		(layer "In2.Cu")
		(hatch none 0.5)
		(connect_pads
			(clearance 0)
		)
		(min_thickness 0.25)
		(keepout
			(tracks not_allowed)
			(vias allowed)
			(pads allowed)
			(copperpour not_allowed)
			(footprints allowed)
		)
		(placement
			(enabled no)
			(sheetname "")
		)
		(fill
			(thermal_gap 0.5)
			(thermal_bridge_width 0.5)
			(island_removal_mode 0)
		)
		(polygon
			(pts
				(xy 28.50261 -225.12528) (xy 30.00121 -225.12528) (xy 30.00121 -225.645218) (xy 28.50261 -225.645218)
			)
		)
	)
	(zone
		(layer "In2.Cu")
		(hatch none 0.5)
		(connect_pads
			(clearance 0)
		)
		(min_thickness 0.25)
		(keepout
			(tracks not_allowed)
			(vias allowed)
			(pads allowed)
			(copperpour not_allowed)
			(footprints allowed)
		)
		(placement
			(enabled no)
			(sheetname "")
		)
		(fill
			(thermal_gap 0.5)
			(thermal_bridge_width 0.5)
			(island_removal_mode 0)
		)
		(polygon
			(pts
				(xy 163.678616 -253.175262) (xy 165.177216 -253.175262) (xy 165.177216 -253.6952) (xy 163.678616 -253.6952)
			)
		)
	)
	(zone
		(layer "In2.Cu")
		(hatch none 0.5)
		(connect_pads
			(clearance 0)
		)
		(min_thickness 0.25)
		(keepout
			(tracks not_allowed)
			(vias allowed)
			(pads allowed)
			(copperpour not_allowed)
			(footprints allowed)
		)
		(placement
			(enabled no)
			(sheetname "")
		)
		(fill
			(thermal_gap 0.5)
			(thermal_bridge_width 0.5)
			(island_removal_mode 0)
		)
		(polygon
			(pts
				(xy 54.578758 -201.325226) (xy 56.077358 -201.325226) (xy 56.077358 -201.845164) (xy 54.578758 -201.845164)
			)
		)
	)
	(zone
		(layer "In2.Cu")
		(hatch none 0.5)
		(connect_pads
			(clearance 0)
		)
		(min_thickness 0.25)
		(keepout
			(tracks not_allowed)
			(vias allowed)
			(pads allowed)
			(copperpour not_allowed)
			(footprints allowed)
		)
		(placement
			(enabled no)
			(sheetname "")
		)
		(fill
			(thermal_gap 0.5)
			(thermal_bridge_width 0.5)
			(island_removal_mode 0)
		)
		(polygon
			(pts
				(xy 197.954646 -277.8252) (xy 199.453246 -277.8252) (xy 199.453246 -278.345138) (xy 197.954646 -278.345138)
			)
		)
	)
	(zone
		(layer "In2.Cu")
		(hatch none 0.5)
		(connect_pads
			(clearance 0)
		)
		(min_thickness 0.25)
		(keepout
			(tracks not_allowed)
			(vias allowed)
			(pads allowed)
			(copperpour not_allowed)
			(footprints allowed)
		)
		(placement
			(enabled no)
			(sheetname "")
		)
		(fill
			(thermal_gap 0.5)
			(thermal_bridge_width 0.5)
			(island_removal_mode 0)
		)
		(polygon
			(pts
				(xy 434.250846 -214.925148) (xy 435.749446 -214.925148) (xy 435.749446 -215.445086) (xy 434.250846 -215.445086)
			)
		)
	)
	(zone
		(layer "In2.Cu")
		(hatch none 0.5)
		(connect_pads
			(clearance 0)
		)
		(min_thickness 0.25)
		(keepout
			(tracks not_allowed)
			(vias allowed)
			(pads allowed)
			(copperpour not_allowed)
			(footprints allowed)
		)
		(placement
			(enabled no)
			(sheetname "")
		)
		(fill
			(thermal_gap 0.5)
			(thermal_bridge_width 0.5)
			(island_removal_mode 0)
		)
		(polygon
			(pts
				(xy 441.7949 -306.72532) (xy 443.2935 -306.72532) (xy 443.2935 -307.245258) (xy 441.7949 -307.245258)
			)
		)
	)
	(zone
		(layer "In2.Cu")
		(hatch none 0.5)
		(connect_pads
			(clearance 0)
		)
		(min_thickness 0.25)
		(keepout
			(tracks not_allowed)
			(vias allowed)
			(pads allowed)
			(copperpour not_allowed)
			(footprints allowed)
		)
		(placement
			(enabled no)
			(sheetname "")
		)
		(fill
			(thermal_gap 0.5)
			(thermal_bridge_width 0.5)
			(island_removal_mode 0)
		)
		(polygon
			(pts
				(xy 163.678616 -286.32531) (xy 165.177216 -286.32531) (xy 165.177216 -286.845248) (xy 163.678616 -286.845248)
			)
		)
	)
	(zone
		(layer "In2.Cu")
		(hatch none 0.5)
		(connect_pads
			(clearance 0)
		)
		(min_thickness 0.25)
		(keepout
			(tracks not_allowed)
			(vias allowed)
			(pads allowed)
			(copperpour not_allowed)
			(footprints allowed)
		)
		(placement
			(enabled no)
			(sheetname "")
		)
		(fill
			(thermal_gap 0.5)
			(thermal_bridge_width 0.5)
			(island_removal_mode 0)
		)
		(polygon
			(pts
				(xy 419.162738 -249.775218) (xy 420.661338 -249.775218) (xy 420.661338 -250.295156) (xy 419.162738 -250.295156)
			)
		)
	)
	(zone
		(layer "In2.Cu")
		(hatch none 0.5)
		(connect_pads
			(clearance 0)
		)
		(min_thickness 0.25)
		(keepout
			(tracks not_allowed)
			(vias allowed)
			(pads allowed)
			(copperpour not_allowed)
			(footprints allowed)
		)
		(placement
			(enabled no)
			(sheetname "")
		)
		(fill
			(thermal_gap 0.5)
			(thermal_bridge_width 0.5)
			(island_removal_mode 0)
		)
		(polygon
			(pts
				(xy 201.398632 -313.525154) (xy 202.897232 -313.525154) (xy 202.897232 -314.045092) (xy 201.398632 -314.045092)
			)
		)
	)
	(zone
		(layer "In2.Cu")
		(hatch none 0.5)
		(connect_pads
			(clearance 0)
		)
		(min_thickness 0.25)
		(keepout
			(tracks not_allowed)
			(vias allowed)
			(pads allowed)
			(copperpour not_allowed)
			(footprints allowed)
		)
		(placement
			(enabled no)
			(sheetname "")
		)
		(fill
			(thermal_gap 0.5)
			(thermal_bridge_width 0.5)
			(island_removal_mode 0)
		)
		(polygon
			(pts
				(xy 415.718752 -279.525222) (xy 417.217352 -279.525222) (xy 417.217352 -280.04516) (xy 415.718752 -280.04516)
			)
		)
	)
	(zone
		(layer "In2.Cu")
		(hatch none 0.5)
		(connect_pads
			(clearance 0)
		)
		(min_thickness 0.25)
		(keepout
			(tracks not_allowed)
			(vias allowed)
			(pads allowed)
			(copperpour not_allowed)
			(footprints allowed)
		)
		(placement
			(enabled no)
			(sheetname "")
		)
		(fill
			(thermal_gap 0.5)
			(thermal_bridge_width 0.5)
			(island_removal_mode 0)
		)
		(polygon
			(pts
				(arc
					(start 354.434394 -379.360684)
					(mid 354.454318 -379.36992)
					(end 354.47605 -379.37313)
				)
				(arc
					(start 354.670614 -379.37313)
					(mid 354.724496 -379.350812)
					(end 354.746814 -379.29693)
				)
				(arc
					(start 354.746814 -378.61113)
					(mid 354.724496 -378.557248)
					(end 354.670614 -378.53493)
				)
				(arc
					(start 354.47605 -378.53493)
					(mid 354.454306 -378.538098)
					(end 354.434394 -378.547376)
				)
				(arc
					(start 354.13823 -378.740162)
					(mid 354.096546 -378.752384)
					(end 354.054918 -378.739908)
				)
				(arc
					(start 353.761294 -378.547376)
					(mid 353.74137 -378.53814)
					(end 353.719638 -378.53493)
				)
				(arc
					(start 353.525074 -378.53493)
					(mid 353.471192 -378.557248)
					(end 353.448874 -378.61113)
				)
				(arc
					(start 353.448874 -379.29693)
					(mid 353.471192 -379.350812)
					(end 353.525074 -379.37313)
				)
				(arc
					(start 353.720908 -379.37313)
					(mid 353.742652 -379.369962)
					(end 353.762564 -379.360684)
				)
				(arc
					(start 354.056188 -379.168152)
					(mid 354.097844 -379.15575)
					(end 354.1395 -379.168152)
				)
			)
		)
	)
	(zone
		(layer "In2.Cu")
		(hatch none 0.5)
		(connect_pads
			(clearance 0)
		)
		(min_thickness 0.25)
		(keepout
			(tracks not_allowed)
			(vias allowed)
			(pads allowed)
			(copperpour not_allowed)
			(footprints allowed)
		)
		(placement
			(enabled no)
			(sheetname "")
		)
		(fill
			(thermal_gap 0.5)
			(thermal_bridge_width 0.5)
			(island_removal_mode 0)
		)
		(polygon
			(pts
				(xy 58.678826 -310.975248) (xy 60.177426 -310.975248) (xy 60.177426 -311.495186) (xy 58.678826 -311.495186)
			)
		)
	)
	(zone
		(layer "In2.Cu")
		(hatch none 0.5)
		(connect_pads
			(clearance 0)
		)
		(min_thickness 0.25)
		(keepout
			(tracks allowed)
			(vias allowed)
			(pads allowed)
			(copperpour allowed)
			(footprints allowed)
		)
		(placement
			(enabled no)
			(sheetname "")
		)
		(fill
			(thermal_gap 0.5)
			(thermal_bridge_width 0.5)
			(island_removal_mode 0)
		)
		(polygon
			(pts
				(xy 408.255978 -163.959032) (xy 408.255978 -164.868352) (xy 407.986738 -164.868352) (xy 407.986738 -163.959032)
			)
		)
	)
	(zone
		(layer "In2.Cu")
		(hatch none 0.5)
		(connect_pads
			(clearance 0)
		)
		(min_thickness 0.25)
		(keepout
			(tracks not_allowed)
			(vias allowed)
			(pads allowed)
			(copperpour not_allowed)
			(footprints allowed)
		)
		(placement
			(enabled no)
			(sheetname "")
		)
		(fill
			(thermal_gap 0.5)
			(thermal_bridge_width 0.5)
			(island_removal_mode 0)
		)
		(polygon
			(pts
				(xy 36.046664 -229.375208) (xy 37.545264 -229.375208) (xy 37.545264 -229.895146) (xy 36.046664 -229.895146)
			)
		)
	)
	(zone
		(layer "In2.Cu")
		(hatch none 0.5)
		(connect_pads
			(clearance 0)
		)
		(min_thickness 0.25)
		(keepout
			(tracks not_allowed)
			(vias allowed)
			(pads allowed)
			(copperpour not_allowed)
			(footprints allowed)
		)
		(placement
			(enabled no)
			(sheetname "")
		)
		(fill
			(thermal_gap 0.5)
			(thermal_bridge_width 0.5)
			(island_removal_mode 0)
		)
		(polygon
			(pts
				(xy 24.402542 -295.675304) (xy 25.901142 -295.675304) (xy 25.901142 -296.195242) (xy 24.402542 -296.195242)
			)
		)
	)
	(zone
		(layer "In2.Cu")
		(hatch none 0.5)
		(connect_pads
			(clearance 0)
		)
		(min_thickness 0.25)
		(keepout
			(tracks not_allowed)
			(vias allowed)
			(pads allowed)
			(copperpour not_allowed)
			(footprints allowed)
		)
		(placement
			(enabled no)
			(sheetname "")
		)
		(fill
			(thermal_gap 0.5)
			(thermal_bridge_width 0.5)
			(island_removal_mode 0)
		)
		(polygon
			(pts
				(xy 434.250846 -207.275176) (xy 435.749446 -207.275176) (xy 435.749446 -207.795114) (xy 434.250846 -207.795114)
			)
		)
	)
	(zone
		(layer "In2.Cu")
		(hatch none 0.5)
		(connect_pads
			(clearance 0)
		)
		(min_thickness 0.25)
		(keepout
			(tracks not_allowed)
			(vias allowed)
			(pads allowed)
			(copperpour not_allowed)
			(footprints allowed)
		)
		(placement
			(enabled no)
			(sheetname "")
		)
		(fill
			(thermal_gap 0.5)
			(thermal_bridge_width 0.5)
			(island_removal_mode 0)
		)
		(polygon
			(pts
				(xy 430.80686 -296.525188) (xy 432.30546 -296.525188) (xy 432.30546 -297.045126) (xy 430.80686 -297.045126)
			)
		)
	)
	(zone
		(layer "In2.Cu")
		(hatch none 0.5)
		(connect_pads
			(clearance 0)
		)
		(min_thickness 0.25)
		(keepout
			(tracks not_allowed)
			(vias allowed)
			(pads allowed)
			(copperpour not_allowed)
			(footprints allowed)
		)
		(placement
			(enabled no)
			(sheetname "")
		)
		(fill
			(thermal_gap 0.5)
			(thermal_bridge_width 0.5)
			(island_removal_mode 0)
		)
		(polygon
			(pts
				(xy 430.80686 -236.175296) (xy 432.30546 -236.175296) (xy 432.30546 -236.695234) (xy 430.80686 -236.695234)
			)
		)
	)
	(zone
		(layer "In2.Cu")
		(hatch none 0.5)
		(connect_pads
			(clearance 0)
		)
		(min_thickness 0.25)
		(keepout
			(tracks not_allowed)
			(vias allowed)
			(pads allowed)
			(copperpour not_allowed)
			(footprints allowed)
		)
		(placement
			(enabled no)
			(sheetname "")
		)
		(fill
			(thermal_gap 0.5)
			(thermal_bridge_width 0.5)
			(island_removal_mode 0)
		)
		(polygon
			(pts
				(xy 449.3387 -199.625204) (xy 450.8373 -199.625204) (xy 450.8373 -200.145142) (xy 449.3387 -200.145142)
			)
		)
	)
	(zone
		(layer "In2.Cu")
		(hatch none 0.5)
		(connect_pads
			(clearance 0)
		)
		(min_thickness 0.25)
		(keepout
			(tracks not_allowed)
			(vias allowed)
			(pads allowed)
			(copperpour not_allowed)
			(footprints allowed)
		)
		(placement
			(enabled no)
			(sheetname "")
		)
		(fill
			(thermal_gap 0.5)
			(thermal_bridge_width 0.5)
			(island_removal_mode 0)
		)
		(polygon
			(pts
				(xy 36.046664 -262.525256) (xy 37.545264 -262.525256) (xy 37.545264 -263.045194) (xy 36.046664 -263.045194)
			)
		)
	)
	(zone
		(layer "In2.Cu")
		(hatch none 0.5)
		(connect_pads
			(clearance 0)
		)
		(min_thickness 0.25)
		(keepout
			(tracks not_allowed)
			(vias allowed)
			(pads allowed)
			(copperpour not_allowed)
			(footprints allowed)
		)
		(placement
			(enabled no)
			(sheetname "")
		)
		(fill
			(thermal_gap 0.5)
			(thermal_bridge_width 0.5)
			(island_removal_mode 0)
		)
		(polygon
			(pts
				(xy 16.858742 -304.17516) (xy 18.357342 -304.17516) (xy 18.357342 -304.695098) (xy 16.858742 -304.695098)
			)
		)
	)
	(zone
		(layer "In2.Cu")
		(hatch none 0.5)
		(connect_pads
			(clearance 0)
		)
		(min_thickness 0.25)
		(keepout
			(tracks not_allowed)
			(vias allowed)
			(pads allowed)
			(copperpour not_allowed)
			(footprints allowed)
		)
		(placement
			(enabled no)
			(sheetname "")
		)
		(fill
			(thermal_gap 0.5)
			(thermal_bridge_width 0.5)
			(island_removal_mode 0)
		)
		(polygon
			(pts
				(xy 47.034704 -197.925182) (xy 48.533304 -197.925182) (xy 48.533304 -198.44512) (xy 47.034704 -198.44512)
			)
		)
	)
	(zone
		(layer "In2.Cu")
		(hatch none 0.5)
		(connect_pads
			(clearance 0)
		)
		(min_thickness 0.25)
		(keepout
			(tracks not_allowed)
			(vias allowed)
			(pads allowed)
			(copperpour not_allowed)
			(footprints allowed)
		)
		(placement
			(enabled no)
			(sheetname "")
		)
		(fill
			(thermal_gap 0.5)
			(thermal_bridge_width 0.5)
			(island_removal_mode 0)
		)
		(polygon
			(pts
				(xy 306.618894 -228.525324) (xy 308.117494 -228.525324) (xy 308.117494 -229.045262) (xy 306.618894 -229.045262)
			)
		)
	)
	(zone
		(layer "In2.Cu")
		(hatch none 0.5)
		(connect_pads
			(clearance 0)
		)
		(min_thickness 0.25)
		(keepout
			(tracks not_allowed)
			(vias allowed)
			(pads allowed)
			(copperpour not_allowed)
			(footprints allowed)
		)
		(placement
			(enabled no)
			(sheetname "")
		)
		(fill
			(thermal_gap 0.5)
			(thermal_bridge_width 0.5)
			(island_removal_mode 0)
		)
		(polygon
			(pts
				(xy 430.80686 -231.07523) (xy 432.30546 -231.07523) (xy 432.30546 -231.595168) (xy 430.80686 -231.595168)
			)
		)
	)
	(zone
		(layer "In2.Cu")
		(hatch none 0.5)
		(connect_pads
			(clearance 0)
		)
		(min_thickness 0.25)
		(keepout
			(tracks not_allowed)
			(vias allowed)
			(pads allowed)
			(copperpour not_allowed)
			(footprints allowed)
		)
		(placement
			(enabled no)
			(sheetname "")
		)
		(fill
			(thermal_gap 0.5)
			(thermal_bridge_width 0.5)
			(island_removal_mode 0)
		)
		(polygon
			(pts
				(xy 411.618684 -211.525104) (xy 413.117284 -211.525104) (xy 413.117284 -212.045042) (xy 411.618684 -212.045042)
			)
		)
	)
	(zone
		(layer "In2.Cu")
		(hatch none 0.5)
		(connect_pads
			(clearance 0)
		)
		(min_thickness 0.25)
		(keepout
			(tracks not_allowed)
			(vias allowed)
			(pads allowed)
			(copperpour not_allowed)
			(footprints allowed)
		)
		(placement
			(enabled no)
			(sheetname "")
		)
		(fill
			(thermal_gap 0.5)
			(thermal_bridge_width 0.5)
			(island_removal_mode 0)
		)
		(polygon
			(pts
				(xy 438.350914 -206.425292) (xy 439.849514 -206.425292) (xy 439.849514 -206.94523) (xy 438.350914 -206.94523)
			)
		)
	)
	(zone
		(layer "In2.Cu")
		(hatch none 0.5)
		(connect_pads
			(clearance 0)
		)
		(min_thickness 0.25)
		(keepout
			(tracks not_allowed)
			(vias allowed)
			(pads allowed)
			(copperpour not_allowed)
			(footprints allowed)
		)
		(placement
			(enabled no)
			(sheetname "")
		)
		(fill
			(thermal_gap 0.5)
			(thermal_bridge_width 0.5)
			(island_removal_mode 0)
		)
		(polygon
			(pts
				(xy 441.7949 -311.825132) (xy 443.2935 -311.825132) (xy 443.2935 -312.34507) (xy 441.7949 -312.34507)
			)
		)
	)
	(zone
		(layer "In2.Cu")
		(hatch none 0.5)
		(connect_pads
			(clearance 0)
		)
		(min_thickness 0.25)
		(keepout
			(tracks not_allowed)
			(vias allowed)
			(pads allowed)
			(copperpour not_allowed)
			(footprints allowed)
		)
		(placement
			(enabled no)
			(sheetname "")
		)
		(fill
			(thermal_gap 0.5)
			(thermal_bridge_width 0.5)
			(island_removal_mode 0)
		)
		(polygon
			(pts
				(xy 268.898878 -273.575272) (xy 270.397478 -273.575272) (xy 270.397478 -274.09521) (xy 268.898878 -274.09521)
			)
		)
	)
	(zone
		(layer "In2.Cu")
		(hatch none 0.5)
		(connect_pads
			(clearance 0)
		)
		(min_thickness 0.25)
		(keepout
			(tracks not_allowed)
			(vias allowed)
			(pads allowed)
			(copperpour not_allowed)
			(footprints allowed)
		)
		(placement
			(enabled no)
			(sheetname "")
		)
		(fill
			(thermal_gap 0.5)
			(thermal_bridge_width 0.5)
			(island_removal_mode 0)
		)
		(polygon
			(pts
				(xy 20.95881 -215.775286) (xy 22.45741 -215.775286) (xy 22.45741 -216.295224) (xy 20.95881 -216.295224)
			)
		)
	)
	(zone
		(layer "In2.Cu")
		(hatch none 0.5)
		(connect_pads
			(clearance 0)
		)
		(min_thickness 0.25)
		(keepout
			(tracks not_allowed)
			(vias allowed)
			(pads allowed)
			(copperpour not_allowed)
			(footprints allowed)
		)
		(placement
			(enabled no)
			(sheetname "")
		)
		(fill
			(thermal_gap 0.5)
			(thermal_bridge_width 0.5)
			(island_removal_mode 0)
		)
		(polygon
			(pts
				(xy 190.410846 -250.625102) (xy 191.909446 -250.625102) (xy 191.909446 -251.14504) (xy 190.410846 -251.14504)
			)
		)
	)
	(zone
		(layer "In2.Cu")
		(hatch none 0.5)
		(connect_pads
			(clearance 0)
		)
		(min_thickness 0.25)
		(keepout
			(tracks not_allowed)
			(vias allowed)
			(pads allowed)
			(copperpour not_allowed)
			(footprints allowed)
		)
		(placement
			(enabled no)
			(sheetname "")
		)
		(fill
			(thermal_gap 0.5)
			(thermal_bridge_width 0.5)
			(island_removal_mode 0)
		)
		(polygon
			(pts
				(xy 299.07484 -269.325344) (xy 300.57344 -269.325344) (xy 300.57344 -269.845282) (xy 299.07484 -269.845282)
			)
		)
	)
	(zone
		(layer "In2.Cu")
		(hatch none 0.5)
		(connect_pads
			(clearance 0)
		)
		(min_thickness 0.25)
		(keepout
			(tracks not_allowed)
			(vias allowed)
			(pads allowed)
			(copperpour not_allowed)
			(footprints allowed)
		)
		(placement
			(enabled no)
			(sheetname "")
		)
		(fill
			(thermal_gap 0.5)
			(thermal_bridge_width 0.5)
			(island_removal_mode 0)
		)
		(polygon
			(pts
				(xy 47.034704 -305.025298) (xy 48.533304 -305.025298) (xy 48.533304 -305.545236) (xy 47.034704 -305.545236)
			)
		)
	)
	(zone
		(layer "In2.Cu")
		(hatch none 0.5)
		(connect_pads
			(clearance 0)
		)
		(min_thickness 0.25)
		(keepout
			(tracks not_allowed)
			(vias allowed)
			(pads allowed)
			(copperpour not_allowed)
			(footprints allowed)
		)
		(placement
			(enabled no)
			(sheetname "")
		)
		(fill
			(thermal_gap 0.5)
			(thermal_bridge_width 0.5)
			(island_removal_mode 0)
		)
		(polygon
			(pts
				(xy 430.80686 -206.425292) (xy 432.30546 -206.425292) (xy 432.30546 -206.94523) (xy 430.80686 -206.94523)
			)
		)
	)
	(zone
		(layer "In2.Cu")
		(hatch none 0.5)
		(connect_pads
			(clearance 0)
		)
		(min_thickness 0.25)
		(keepout
			(tracks not_allowed)
			(vias allowed)
			(pads allowed)
			(copperpour not_allowed)
			(footprints allowed)
		)
		(placement
			(enabled no)
			(sheetname "")
		)
		(fill
			(thermal_gap 0.5)
			(thermal_bridge_width 0.5)
			(island_removal_mode 0)
		)
		(polygon
			(pts
				(xy 419.162738 -265.075162) (xy 420.661338 -265.075162) (xy 420.661338 -265.5951) (xy 419.162738 -265.5951)
			)
		)
	)
	(zone
		(layer "In2.Cu")
		(hatch none 0.5)
		(connect_pads
			(clearance 0)
		)
		(min_thickness 0.25)
		(keepout
			(tracks not_allowed)
			(vias allowed)
			(pads allowed)
			(copperpour not_allowed)
			(footprints allowed)
		)
		(placement
			(enabled no)
			(sheetname "")
		)
		(fill
			(thermal_gap 0.5)
			(thermal_bridge_width 0.5)
			(island_removal_mode 0)
		)
		(polygon
			(pts
				(xy 201.398632 -203.875132) (xy 202.897232 -203.875132) (xy 202.897232 -204.39507) (xy 201.398632 -204.39507)
			)
		)
	)
	(zone
		(layer "In2.Cu")
		(hatch none 0.5)
		(connect_pads
			(clearance 0)
		)
		(min_thickness 0.25)
		(keepout
			(tracks not_allowed)
			(vias allowed)
			(pads allowed)
			(copperpour not_allowed)
			(footprints allowed)
		)
		(placement
			(enabled no)
			(sheetname "")
		)
		(fill
			(thermal_gap 0.5)
			(thermal_bridge_width 0.5)
			(island_removal_mode 0)
		)
		(polygon
			(pts
				(xy 16.858742 -286.32531) (xy 18.357342 -286.32531) (xy 18.357342 -286.845248) (xy 16.858742 -286.845248)
			)
		)
	)
	(zone
		(layer "In2.Cu")
		(hatch none 0.5)
		(connect_pads
			(clearance 0)
		)
		(min_thickness 0.25)
		(keepout
			(tracks not_allowed)
			(vias allowed)
			(pads allowed)
			(copperpour not_allowed)
			(footprints allowed)
		)
		(placement
			(enabled no)
			(sheetname "")
		)
		(fill
			(thermal_gap 0.5)
			(thermal_bridge_width 0.5)
			(island_removal_mode 0)
		)
		(polygon
			(pts
				(xy 51.134772 -267.625322) (xy 52.633372 -267.625322) (xy 52.633372 -268.14526) (xy 51.134772 -268.14526)
			)
		)
	)
	(zone
		(layer "In2.Cu")
		(hatch none 0.5)
		(connect_pads
			(clearance 0)
		)
		(min_thickness 0.25)
		(keepout
			(tracks not_allowed)
			(vias allowed)
			(pads allowed)
			(copperpour not_allowed)
			(footprints allowed)
		)
		(placement
			(enabled no)
			(sheetname "")
		)
		(fill
			(thermal_gap 0.5)
			(thermal_bridge_width 0.5)
			(island_removal_mode 0)
		)
		(polygon
			(pts
				(xy 426.706792 -306.72532) (xy 428.205392 -306.72532) (xy 428.205392 -307.245258) (xy 426.706792 -307.245258)
			)
		)
	)
	(zone
		(layer "In2.Cu")
		(hatch none 0.5)
		(connect_pads
			(clearance 0)
		)
		(min_thickness 0.25)
		(keepout
			(tracks allowed)
			(vias allowed)
			(pads allowed)
			(copperpour allowed)
			(footprints allowed)
		)
		(placement
			(enabled no)
			(sheetname "")
		)
		(fill
			(thermal_gap 0.5)
			(thermal_bridge_width 0.5)
			(island_removal_mode 0)
		)
		(polygon
			(pts
				(xy 118.13032 -169.32656) (xy 118.13032 -168.780206) (xy 118.68277 -168.780206) (xy 118.68277 -169.32656)
			)
		)
	)
	(zone
		(layer "In2.Cu")
		(hatch none 0.5)
		(connect_pads
			(clearance 0)
		)
		(min_thickness 0.25)
		(keepout
			(tracks not_allowed)
			(vias allowed)
			(pads allowed)
			(copperpour not_allowed)
			(footprints allowed)
		)
		(placement
			(enabled no)
			(sheetname "")
		)
		(fill
			(thermal_gap 0.5)
			(thermal_bridge_width 0.5)
			(island_removal_mode 0)
		)
		(polygon
			(pts
				(xy 283.986732 -228.525324) (xy 285.485332 -228.525324) (xy 285.485332 -229.045262) (xy 283.986732 -229.045262)
			)
		)
	)
	(zone
		(layer "In2.Cu")
		(hatch none 0.5)
		(connect_pads
			(clearance 0)
		)
		(min_thickness 0.25)
		(keepout
			(tracks not_allowed)
			(vias allowed)
			(pads allowed)
			(copperpour not_allowed)
			(footprints allowed)
		)
		(placement
			(enabled no)
			(sheetname "")
		)
		(fill
			(thermal_gap 0.5)
			(thermal_bridge_width 0.5)
			(island_removal_mode 0)
		)
		(polygon
			(pts
				(xy 287.430718 -235.325158) (xy 288.929318 -235.325158) (xy 288.929318 -235.845096) (xy 287.430718 -235.845096)
			)
		)
	)
	(zone
		(layer "In2.Cu")
		(hatch none 0.5)
		(connect_pads
			(clearance 0)
		)
		(min_thickness 0.25)
		(keepout
			(tracks not_allowed)
			(vias allowed)
			(pads allowed)
			(copperpour not_allowed)
			(footprints allowed)
		)
		(placement
			(enabled no)
			(sheetname "")
		)
		(fill
			(thermal_gap 0.5)
			(thermal_bridge_width 0.5)
			(island_removal_mode 0)
		)
		(polygon
			(pts
				(xy 175.322738 -262.525256) (xy 176.821338 -262.525256) (xy 176.821338 -263.045194) (xy 175.322738 -263.045194)
			)
		)
	)
	(zone
		(layer "In2.Cu")
		(hatch none 0.5)
		(connect_pads
			(clearance 0)
		)
		(min_thickness 0.25)
		(keepout
			(tracks not_allowed)
			(vias allowed)
			(pads allowed)
			(copperpour not_allowed)
			(footprints allowed)
		)
		(placement
			(enabled no)
			(sheetname "")
		)
		(fill
			(thermal_gap 0.5)
			(thermal_bridge_width 0.5)
			(island_removal_mode 0)
		)
		(polygon
			(pts
				(xy 36.046664 -198.77532) (xy 37.545264 -198.77532) (xy 37.545264 -199.295258) (xy 36.046664 -199.295258)
			)
		)
	)
	(zone
		(layer "In2.Cu")
		(hatch none 0.5)
		(connect_pads
			(clearance 0)
		)
		(min_thickness 0.25)
		(keepout
			(tracks not_allowed)
			(vias allowed)
			(pads allowed)
			(copperpour not_allowed)
			(footprints allowed)
		)
		(placement
			(enabled no)
			(sheetname "")
		)
		(fill
			(thermal_gap 0.5)
			(thermal_bridge_width 0.5)
			(island_removal_mode 0)
		)
		(polygon
			(pts
				(xy 28.50261 -276.125178) (xy 30.00121 -276.125178) (xy 30.00121 -276.645116) (xy 28.50261 -276.645116)
			)
		)
	)
	(zone
		(layer "In2.Cu")
		(hatch none 0.5)
		(connect_pads
			(clearance 0)
		)
		(min_thickness 0.25)
		(keepout
			(tracks not_allowed)
			(vias allowed)
			(pads allowed)
			(copperpour not_allowed)
			(footprints allowed)
		)
		(placement
			(enabled no)
			(sheetname "")
		)
		(fill
			(thermal_gap 0.5)
			(thermal_bridge_width 0.5)
			(island_removal_mode 0)
		)
		(polygon
			(pts
				(xy 58.678826 -243.825268) (xy 60.177426 -243.825268) (xy 60.177426 -244.345206) (xy 58.678826 -244.345206)
			)
		)
	)
	(zone
		(layer "In2.Cu")
		(hatch none 0.5)
		(connect_pads
			(clearance 0)
		)
		(min_thickness 0.25)
		(keepout
			(tracks not_allowed)
			(vias allowed)
			(pads allowed)
			(copperpour not_allowed)
			(footprints allowed)
		)
		(placement
			(enabled no)
			(sheetname "")
		)
		(fill
			(thermal_gap 0.5)
			(thermal_bridge_width 0.5)
			(island_removal_mode 0)
		)
		(polygon
			(pts
				(xy 197.954646 -281.225244) (xy 199.453246 -281.225244) (xy 199.453246 -281.745182) (xy 197.954646 -281.745182)
			)
		)
	)
	(zone
		(layer "In2.Cu")
		(hatch none 0.5)
		(connect_pads
			(clearance 0)
		)
		(min_thickness 0.25)
		(keepout
			(tracks not_allowed)
			(vias allowed)
			(pads allowed)
			(copperpour not_allowed)
			(footprints allowed)
		)
		(placement
			(enabled no)
			(sheetname "")
		)
		(fill
			(thermal_gap 0.5)
			(thermal_bridge_width 0.5)
			(island_removal_mode 0)
		)
		(polygon
			(pts
				(xy 171.22267 -305.025298) (xy 172.72127 -305.025298) (xy 172.72127 -305.545236) (xy 171.22267 -305.545236)
			)
		)
	)
	(zone
		(layer "In2.Cu")
		(hatch none 0.5)
		(connect_pads
			(clearance 0)
		)
		(min_thickness 0.25)
		(keepout
			(tracks not_allowed)
			(vias allowed)
			(pads allowed)
			(copperpour not_allowed)
			(footprints allowed)
		)
		(placement
			(enabled no)
			(sheetname "")
		)
		(fill
			(thermal_gap 0.5)
			(thermal_bridge_width 0.5)
			(island_removal_mode 0)
		)
		(polygon
			(pts
				(xy 445.894968 -223.425258) (xy 447.393568 -223.425258) (xy 447.393568 -223.945196) (xy 445.894968 -223.945196)
			)
		)
	)
	(zone
		(layer "In2.Cu")
		(hatch none 0.5)
		(connect_pads
			(clearance 0)
		)
		(min_thickness 0.25)
		(keepout
			(tracks not_allowed)
			(vias allowed)
			(pads allowed)
			(copperpour not_allowed)
			(footprints allowed)
		)
		(placement
			(enabled no)
			(sheetname "")
		)
		(fill
			(thermal_gap 0.5)
			(thermal_bridge_width 0.5)
			(island_removal_mode 0)
		)
		(polygon
			(pts
				(xy 175.322738 -310.975248) (xy 176.821338 -310.975248) (xy 176.821338 -311.495186) (xy 175.322738 -311.495186)
			)
		)
	)
	(zone
		(layer "In2.Cu")
		(hatch none 0.5)
		(connect_pads
			(clearance 0)
		)
		(min_thickness 0.25)
		(keepout
			(tracks not_allowed)
			(vias allowed)
			(pads allowed)
			(copperpour not_allowed)
			(footprints allowed)
		)
		(placement
			(enabled no)
			(sheetname "")
		)
		(fill
			(thermal_gap 0.5)
			(thermal_bridge_width 0.5)
			(island_removal_mode 0)
		)
		(polygon
			(pts
				(xy 51.134772 -292.27526) (xy 52.633372 -292.27526) (xy 52.633372 -292.795198) (xy 51.134772 -292.795198)
			)
		)
	)
	(zone
		(layer "In2.Cu")
		(hatch none 0.5)
		(connect_pads
			(clearance 0)
		)
		(min_thickness 0.25)
		(keepout
			(tracks not_allowed)
			(vias allowed)
			(pads allowed)
			(copperpour not_allowed)
			(footprints allowed)
		)
		(placement
			(enabled no)
			(sheetname "")
		)
		(fill
			(thermal_gap 0.5)
			(thermal_bridge_width 0.5)
			(island_removal_mode 0)
		)
		(polygon
			(pts
				(xy 268.898878 -217.475308) (xy 270.397478 -217.475308) (xy 270.397478 -217.995246) (xy 268.898878 -217.995246)
			)
		)
	)
	(zone
		(layer "In2.Cu")
		(hatch none 0.5)
		(connect_pads
			(clearance 0)
		)
		(min_thickness 0.25)
		(keepout
			(tracks not_allowed)
			(vias allowed)
			(pads allowed)
			(copperpour not_allowed)
			(footprints allowed)
		)
		(placement
			(enabled no)
			(sheetname "")
		)
		(fill
			(thermal_gap 0.5)
			(thermal_bridge_width 0.5)
			(island_removal_mode 0)
		)
		(polygon
			(pts
				(xy 58.678826 -231.07523) (xy 60.177426 -231.07523) (xy 60.177426 -231.595168) (xy 58.678826 -231.595168)
			)
		)
	)
	(zone
		(layer "In2.Cu")
		(hatch none 0.5)
		(connect_pads
			(clearance 0)
		)
		(min_thickness 0.25)
		(keepout
			(tracks not_allowed)
			(vias allowed)
			(pads allowed)
			(copperpour not_allowed)
			(footprints allowed)
		)
		(placement
			(enabled no)
			(sheetname "")
		)
		(fill
			(thermal_gap 0.5)
			(thermal_bridge_width 0.5)
			(island_removal_mode 0)
		)
		(polygon
			(pts
				(xy 268.898878 -206.425292) (xy 270.397478 -206.425292) (xy 270.397478 -206.94523) (xy 268.898878 -206.94523)
			)
		)
	)
	(zone
		(layer "In2.Cu")
		(hatch none 0.5)
		(connect_pads
			(clearance 0)
		)
		(min_thickness 0.25)
		(keepout
			(tracks allowed)
			(vias allowed)
			(pads allowed)
			(copperpour allowed)
			(footprints allowed)
		)
		(placement
			(enabled no)
			(sheetname "")
		)
		(fill
			(thermal_gap 0.5)
			(thermal_bridge_width 0.5)
			(island_removal_mode 0)
		)
		(polygon
			(pts
				(xy 277.96617 -350.590866) (xy 277.96617 -349.968566) (xy 278.51735 -349.968566) (xy 278.51735 -350.590866)
			)
		)
	)
	(zone
		(layer "In2.Cu")
		(hatch none 0.5)
		(connect_pads
			(clearance 0)
		)
		(min_thickness 0.25)
		(keepout
			(tracks not_allowed)
			(vias allowed)
			(pads allowed)
			(copperpour not_allowed)
			(footprints allowed)
		)
		(placement
			(enabled no)
			(sheetname "")
		)
		(fill
			(thermal_gap 0.5)
			(thermal_bridge_width 0.5)
			(island_removal_mode 0)
		)
		(polygon
			(pts
				(xy 291.530786 -296.525188) (xy 293.029386 -296.525188) (xy 293.029386 -297.045126) (xy 291.530786 -297.045126)
			)
		)
	)
	(zone
		(layer "In2.Cu")
		(hatch none 0.5)
		(connect_pads
			(clearance 0)
		)
		(min_thickness 0.25)
		(keepout
			(tracks not_allowed)
			(vias allowed)
			(pads allowed)
			(copperpour not_allowed)
			(footprints allowed)
		)
		(placement
			(enabled no)
			(sheetname "")
		)
		(fill
			(thermal_gap 0.5)
			(thermal_bridge_width 0.5)
			(island_removal_mode 0)
		)
		(polygon
			(pts
				(xy 31.946596 -295.675304) (xy 33.445196 -295.675304) (xy 33.445196 -296.195242) (xy 31.946596 -296.195242)
			)
		)
	)
	(zone
		(layer "In2.Cu")
		(hatch none 0.5)
		(connect_pads
			(clearance 0)
		)
		(min_thickness 0.25)
		(keepout
			(tracks not_allowed)
			(vias allowed)
			(pads allowed)
			(copperpour not_allowed)
			(footprints allowed)
		)
		(placement
			(enabled no)
			(sheetname "")
		)
		(fill
			(thermal_gap 0.5)
			(thermal_bridge_width 0.5)
			(island_removal_mode 0)
		)
		(polygon
			(pts
				(xy 171.22267 -300.775116) (xy 172.72127 -300.775116) (xy 172.72127 -301.295054) (xy 171.22267 -301.295054)
			)
		)
	)
	(zone
		(layer "In2.Cu")
		(hatch none 0.5)
		(connect_pads
			(clearance 0)
		)
		(min_thickness 0.25)
		(keepout
			(tracks not_allowed)
			(vias allowed)
			(pads allowed)
			(copperpour not_allowed)
			(footprints allowed)
		)
		(placement
			(enabled no)
			(sheetname "")
		)
		(fill
			(thermal_gap 0.5)
			(thermal_bridge_width 0.5)
			(island_removal_mode 0)
		)
		(polygon
			(pts
				(xy 453.438768 -304.17516) (xy 454.937368 -304.17516) (xy 454.937368 -304.695098) (xy 453.438768 -304.695098)
			)
		)
	)
	(zone
		(layer "In2.Cu")
		(hatch none 0.5)
		(connect_pads
			(clearance 0)
		)
		(min_thickness 0.25)
		(keepout
			(tracks not_allowed)
			(vias allowed)
			(pads allowed)
			(copperpour not_allowed)
			(footprints allowed)
		)
		(placement
			(enabled no)
			(sheetname "")
		)
		(fill
			(thermal_gap 0.5)
			(thermal_bridge_width 0.5)
			(island_removal_mode 0)
		)
		(polygon
			(pts
				(xy 434.250846 -293.125144) (xy 435.749446 -293.125144) (xy 435.749446 -293.645082) (xy 434.250846 -293.645082)
			)
		)
	)
	(zone
		(layer "In2.Cu")
		(hatch none 0.5)
		(connect_pads
			(clearance 0)
		)
		(min_thickness 0.25)
		(keepout
			(tracks not_allowed)
			(vias allowed)
			(pads allowed)
			(copperpour not_allowed)
			(footprints allowed)
		)
		(placement
			(enabled no)
			(sheetname "")
		)
		(fill
			(thermal_gap 0.5)
			(thermal_bridge_width 0.5)
			(island_removal_mode 0)
		)
		(polygon
			(pts
				(xy 279.886664 -231.925114) (xy 281.385264 -231.925114) (xy 281.385264 -232.445052) (xy 279.886664 -232.445052)
			)
		)
	)
	(zone
		(layer "In2.Cu")
		(hatch none 0.5)
		(connect_pads
			(clearance 0)
		)
		(min_thickness 0.25)
		(keepout
			(tracks not_allowed)
			(vias allowed)
			(pads allowed)
			(copperpour not_allowed)
			(footprints allowed)
		)
		(placement
			(enabled no)
			(sheetname "")
		)
		(fill
			(thermal_gap 0.5)
			(thermal_bridge_width 0.5)
			(island_removal_mode 0)
		)
		(polygon
			(pts
				(xy 449.3387 -222.57512) (xy 450.8373 -222.57512) (xy 450.8373 -223.095058) (xy 449.3387 -223.095058)
			)
		)
	)
	(zone
		(layer "In2.Cu")
		(hatch none 0.5)
		(connect_pads
			(clearance 0)
		)
		(min_thickness 0.25)
		(keepout
			(tracks not_allowed)
			(vias allowed)
			(pads allowed)
			(copperpour not_allowed)
			(footprints allowed)
		)
		(placement
			(enabled no)
			(sheetname "")
		)
		(fill
			(thermal_gap 0.5)
			(thermal_bridge_width 0.5)
			(island_removal_mode 0)
		)
		(polygon
			(pts
				(xy 283.986732 -234.475274) (xy 285.485332 -234.475274) (xy 285.485332 -234.995212) (xy 283.986732 -234.995212)
			)
		)
	)
	(zone
		(layer "In2.Cu")
		(hatch none 0.5)
		(connect_pads
			(clearance 0)
		)
		(min_thickness 0.25)
		(keepout
			(tracks not_allowed)
			(vias allowed)
			(pads allowed)
			(copperpour not_allowed)
			(footprints allowed)
		)
		(placement
			(enabled no)
			(sheetname "")
		)
		(fill
			(thermal_gap 0.5)
			(thermal_bridge_width 0.5)
			(island_removal_mode 0)
		)
		(polygon
			(pts
				(xy 201.398632 -208.975198) (xy 202.897232 -208.975198) (xy 202.897232 -209.495136) (xy 201.398632 -209.495136)
			)
		)
	)
	(zone
		(layer "In2.Cu")
		(hatch none 0.5)
		(connect_pads
			(clearance 0)
		)
		(min_thickness 0.25)
		(keepout
			(tracks not_allowed)
			(vias allowed)
			(pads allowed)
			(copperpour not_allowed)
			(footprints allowed)
		)
		(placement
			(enabled no)
			(sheetname "")
		)
		(fill
			(thermal_gap 0.5)
			(thermal_bridge_width 0.5)
			(island_removal_mode 0)
		)
		(polygon
			(pts
				(xy 453.438768 -206.425292) (xy 454.937368 -206.425292) (xy 454.937368 -206.94523) (xy 453.438768 -206.94523)
			)
		)
	)
	(zone
		(layer "In2.Cu")
		(hatch none 0.5)
		(connect_pads
			(clearance 0)
		)
		(min_thickness 0.25)
		(keepout
			(tracks not_allowed)
			(vias allowed)
			(pads allowed)
			(copperpour not_allowed)
			(footprints allowed)
		)
		(placement
			(enabled no)
			(sheetname "")
		)
		(fill
			(thermal_gap 0.5)
			(thermal_bridge_width 0.5)
			(island_removal_mode 0)
		)
		(polygon
			(pts
				(xy 438.350914 -242.125246) (xy 439.849514 -242.125246) (xy 439.849514 -242.645184) (xy 438.350914 -242.645184)
			)
		)
	)
	(zone
		(layer "In2.Cu")
		(hatch none 0.5)
		(connect_pads
			(clearance 0)
		)
		(min_thickness 0.25)
		(keepout
			(tracks not_allowed)
			(vias allowed)
			(pads allowed)
			(copperpour not_allowed)
			(footprints allowed)
		)
		(placement
			(enabled no)
			(sheetname "")
		)
		(fill
			(thermal_gap 0.5)
			(thermal_bridge_width 0.5)
			(island_removal_mode 0)
		)
		(polygon
			(pts
				(xy 445.894968 -281.225244) (xy 447.393568 -281.225244) (xy 447.393568 -281.745182) (xy 445.894968 -281.745182)
			)
		)
	)
	(zone
		(layer "In2.Cu")
		(hatch none 0.5)
		(connect_pads
			(clearance 0)
		)
		(min_thickness 0.25)
		(keepout
			(tracks not_allowed)
			(vias allowed)
			(pads allowed)
			(copperpour not_allowed)
			(footprints allowed)
		)
		(placement
			(enabled no)
			(sheetname "")
		)
		(fill
			(thermal_gap 0.5)
			(thermal_bridge_width 0.5)
			(island_removal_mode 0)
		)
		(polygon
			(pts
				(xy 24.402542 -289.725354) (xy 25.901142 -289.725354) (xy 25.901142 -290.245292) (xy 24.402542 -290.245292)
			)
		)
	)
	(zone
		(layer "In2.Cu")
		(hatch none 0.5)
		(connect_pads
			(clearance 0)
		)
		(min_thickness 0.25)
		(keepout
			(tracks not_allowed)
			(vias allowed)
			(pads allowed)
			(copperpour not_allowed)
			(footprints allowed)
		)
		(placement
			(enabled no)
			(sheetname "")
		)
		(fill
			(thermal_gap 0.5)
			(thermal_bridge_width 0.5)
			(island_removal_mode 0)
		)
		(polygon
			(pts
				(xy 411.618684 -218.325192) (xy 413.117284 -218.325192) (xy 413.117284 -218.84513) (xy 411.618684 -218.84513)
			)
		)
	)
	(zone
		(layer "In2.Cu")
		(hatch none 0.5)
		(connect_pads
			(clearance 0)
		)
		(min_thickness 0.25)
		(keepout
			(tracks not_allowed)
			(vias allowed)
			(pads allowed)
			(copperpour not_allowed)
			(footprints allowed)
		)
		(placement
			(enabled no)
			(sheetname "")
		)
		(fill
			(thermal_gap 0.5)
			(thermal_bridge_width 0.5)
			(island_removal_mode 0)
		)
		(polygon
			(pts
				(xy 186.310778 -216.62517) (xy 187.809378 -216.62517) (xy 187.809378 -217.145108) (xy 186.310778 -217.145108)
			)
		)
	)
	(zone
		(layer "In2.Cu")
		(hatch none 0.5)
		(connect_pads
			(clearance 0)
		)
		(min_thickness 0.25)
		(keepout
			(tracks not_allowed)
			(vias allowed)
			(pads allowed)
			(copperpour not_allowed)
			(footprints allowed)
		)
		(placement
			(enabled no)
			(sheetname "")
		)
		(fill
			(thermal_gap 0.5)
			(thermal_bridge_width 0.5)
			(island_removal_mode 0)
		)
		(polygon
			(pts
				(xy 283.986732 -271.87525) (xy 285.485332 -271.87525) (xy 285.485332 -272.395188) (xy 283.986732 -272.395188)
			)
		)
	)
	(zone
		(layer "In2.Cu")
		(hatch none 0.5)
		(connect_pads
			(clearance 0)
		)
		(min_thickness 0.25)
		(keepout
			(tracks not_allowed)
			(vias allowed)
			(pads allowed)
			(copperpour not_allowed)
			(footprints allowed)
		)
		(placement
			(enabled no)
			(sheetname "")
		)
		(fill
			(thermal_gap 0.5)
			(thermal_bridge_width 0.5)
			(island_removal_mode 0)
		)
		(polygon
			(pts
				(xy 31.946596 -205.575154) (xy 33.445196 -205.575154) (xy 33.445196 -206.095092) (xy 31.946596 -206.095092)
			)
		)
	)
	(zone
		(layer "In2.Cu")
		(hatch none 0.5)
		(connect_pads
			(clearance 0)
		)
		(min_thickness 0.25)
		(keepout
			(tracks not_allowed)
			(vias allowed)
			(pads allowed)
			(copperpour not_allowed)
			(footprints allowed)
		)
		(placement
			(enabled no)
			(sheetname "")
		)
		(fill
			(thermal_gap 0.5)
			(thermal_bridge_width 0.5)
			(island_removal_mode 0)
		)
		(polygon
			(pts
				(xy 51.134772 -238.725202) (xy 52.633372 -238.725202) (xy 52.633372 -239.24514) (xy 51.134772 -239.24514)
			)
		)
	)
	(zone
		(layer "In2.Cu")
		(hatch none 0.5)
		(connect_pads
			(clearance 0)
		)
		(min_thickness 0.25)
		(keepout
			(tracks not_allowed)
			(vias allowed)
			(pads allowed)
			(copperpour not_allowed)
			(footprints allowed)
		)
		(placement
			(enabled no)
			(sheetname "")
		)
		(fill
			(thermal_gap 0.5)
			(thermal_bridge_width 0.5)
			(island_removal_mode 0)
		)
		(polygon
			(pts
				(xy 276.442932 -236.175296) (xy 277.941532 -236.175296) (xy 277.941532 -236.695234) (xy 276.442932 -236.695234)
			)
		)
	)
	(zone
		(layer "In2.Cu")
		(hatch none 0.5)
		(connect_pads
			(clearance 0)
		)
		(min_thickness 0.25)
		(keepout
			(tracks not_allowed)
			(vias allowed)
			(pads allowed)
			(copperpour not_allowed)
			(footprints allowed)
		)
		(placement
			(enabled no)
			(sheetname "")
		)
		(fill
			(thermal_gap 0.5)
			(thermal_bridge_width 0.5)
			(island_removal_mode 0)
		)
		(polygon
			(pts
				(xy 294.974772 -308.425342) (xy 296.473372 -308.425342) (xy 296.473372 -308.94528) (xy 294.974772 -308.94528)
			)
		)
	)
	(zone
		(layer "In2.Cu")
		(hatch none 0.5)
		(connect_pads
			(clearance 0)
		)
		(min_thickness 0.25)
		(keepout
			(tracks not_allowed)
			(vias allowed)
			(pads allowed)
			(copperpour not_allowed)
			(footprints allowed)
		)
		(placement
			(enabled no)
			(sheetname "")
		)
		(fill
			(thermal_gap 0.5)
			(thermal_bridge_width 0.5)
			(island_removal_mode 0)
		)
		(polygon
			(pts
				(xy 434.250846 -305.025298) (xy 435.749446 -305.025298) (xy 435.749446 -305.545236) (xy 434.250846 -305.545236)
			)
		)
	)
	(zone
		(layer "In2.Cu")
		(hatch none 0.5)
		(connect_pads
			(clearance 0)
		)
		(min_thickness 0.25)
		(keepout
			(tracks not_allowed)
			(vias allowed)
			(pads allowed)
			(copperpour not_allowed)
			(footprints allowed)
		)
		(placement
			(enabled no)
			(sheetname "")
		)
		(fill
			(thermal_gap 0.5)
			(thermal_bridge_width 0.5)
			(island_removal_mode 0)
		)
		(polygon
			(pts
				(xy 58.678826 -209.825336) (xy 60.177426 -209.825336) (xy 60.177426 -210.345274) (xy 58.678826 -210.345274)
			)
		)
	)
	(zone
		(layer "In2.Cu")
		(hatch none 0.5)
		(connect_pads
			(clearance 0)
		)
		(min_thickness 0.25)
		(keepout
			(tracks not_allowed)
			(vias allowed)
			(pads allowed)
			(copperpour not_allowed)
			(footprints allowed)
		)
		(placement
			(enabled no)
			(sheetname "")
		)
		(fill
			(thermal_gap 0.5)
			(thermal_bridge_width 0.5)
			(island_removal_mode 0)
		)
		(polygon
			(pts
				(xy 167.778684 -293.975282) (xy 169.277284 -293.975282) (xy 169.277284 -294.49522) (xy 167.778684 -294.49522)
			)
		)
	)
	(zone
		(layer "In2.Cu")
		(hatch none 0.5)
		(connect_pads
			(clearance 0)
		)
		(min_thickness 0.25)
		(keepout
			(tracks not_allowed)
			(vias allowed)
			(pads allowed)
			(copperpour not_allowed)
			(footprints allowed)
		)
		(placement
			(enabled no)
			(sheetname "")
		)
		(fill
			(thermal_gap 0.5)
			(thermal_bridge_width 0.5)
			(island_removal_mode 0)
		)
		(polygon
			(pts
				(xy 167.778684 -215.775286) (xy 169.277284 -215.775286) (xy 169.277284 -216.295224) (xy 167.778684 -216.295224)
			)
		)
	)
	(zone
		(layer "In2.Cu")
		(hatch none 0.5)
		(connect_pads
			(clearance 0)
		)
		(min_thickness 0.25)
		(keepout
			(tracks not_allowed)
			(vias allowed)
			(pads allowed)
			(copperpour not_allowed)
			(footprints allowed)
		)
		(placement
			(enabled no)
			(sheetname "")
		)
		(fill
			(thermal_gap 0.5)
			(thermal_bridge_width 0.5)
			(island_removal_mode 0)
		)
		(polygon
			(pts
				(xy 201.398632 -274.425156) (xy 202.897232 -274.425156) (xy 202.897232 -274.945094) (xy 201.398632 -274.945094)
			)
		)
	)
	(zone
		(layer "In2.Cu")
		(hatch none 0.5)
		(connect_pads
			(clearance 0)
		)
		(min_thickness 0.25)
		(keepout
			(tracks not_allowed)
			(vias allowed)
			(pads allowed)
			(copperpour not_allowed)
			(footprints allowed)
		)
		(placement
			(enabled no)
			(sheetname "")
		)
		(fill
			(thermal_gap 0.5)
			(thermal_bridge_width 0.5)
			(island_removal_mode 0)
		)
		(polygon
			(pts
				(xy 276.442932 -215.775286) (xy 277.941532 -215.775286) (xy 277.941532 -216.295224) (xy 276.442932 -216.295224)
			)
		)
	)
	(zone
		(layer "In2.Cu")
		(hatch none 0.5)
		(connect_pads
			(clearance 0)
		)
		(min_thickness 0.25)
		(keepout
			(tracks not_allowed)
			(vias allowed)
			(pads allowed)
			(copperpour not_allowed)
			(footprints allowed)
		)
		(placement
			(enabled no)
			(sheetname "")
		)
		(fill
			(thermal_gap 0.5)
			(thermal_bridge_width 0.5)
			(island_removal_mode 0)
		)
		(polygon
			(pts
				(xy 291.530786 -232.775252) (xy 293.029386 -232.775252) (xy 293.029386 -233.29519) (xy 291.530786 -233.29519)
			)
		)
	)
	(zone
		(layer "In2.Cu")
		(hatch none 0.5)
		(connect_pads
			(clearance 0)
		)
		(min_thickness 0.25)
		(keepout
			(tracks not_allowed)
			(vias allowed)
			(pads allowed)
			(copperpour not_allowed)
			(footprints allowed)
		)
		(placement
			(enabled no)
			(sheetname "")
		)
		(fill
			(thermal_gap 0.5)
			(thermal_bridge_width 0.5)
			(island_removal_mode 0)
		)
		(polygon
			(pts
				(xy 445.894968 -293.975282) (xy 447.393568 -293.975282) (xy 447.393568 -294.49522) (xy 445.894968 -294.49522)
			)
		)
	)
	(zone
		(layer "In2.Cu")
		(hatch none 0.5)
		(connect_pads
			(clearance 0)
		)
		(min_thickness 0.25)
		(keepout
			(tracks not_allowed)
			(vias allowed)
			(pads allowed)
			(copperpour not_allowed)
			(footprints allowed)
		)
		(placement
			(enabled no)
			(sheetname "")
		)
		(fill
			(thermal_gap 0.5)
			(thermal_bridge_width 0.5)
			(island_removal_mode 0)
		)
		(polygon
			(pts
				(xy 276.442932 -242.125246) (xy 277.941532 -242.125246) (xy 277.941532 -242.645184) (xy 276.442932 -242.645184)
			)
		)
	)
	(zone
		(layer "In2.Cu")
		(hatch none 0.5)
		(connect_pads
			(clearance 0)
		)
		(min_thickness 0.25)
		(keepout
			(tracks not_allowed)
			(vias allowed)
			(pads allowed)
			(copperpour not_allowed)
			(footprints allowed)
		)
		(placement
			(enabled no)
			(sheetname "")
		)
		(fill
			(thermal_gap 0.5)
			(thermal_bridge_width 0.5)
			(island_removal_mode 0)
		)
		(polygon
			(pts
				(xy 306.618894 -226.825302) (xy 308.117494 -226.825302) (xy 308.117494 -227.34524) (xy 306.618894 -227.34524)
			)
		)
	)
	(zone
		(layer "In2.Cu")
		(hatch none 0.5)
		(connect_pads
			(clearance 0)
		)
		(min_thickness 0.25)
		(keepout
			(tracks not_allowed)
			(vias allowed)
			(pads allowed)
			(copperpour not_allowed)
			(footprints allowed)
		)
		(placement
			(enabled no)
			(sheetname "")
		)
		(fill
			(thermal_gap 0.5)
			(thermal_bridge_width 0.5)
			(island_removal_mode 0)
		)
		(polygon
			(pts
				(xy 197.954646 -221.725236) (xy 199.453246 -221.725236) (xy 199.453246 -222.245174) (xy 197.954646 -222.245174)
			)
		)
	)
	(zone
		(layer "In2.Cu")
		(hatch none 0.5)
		(connect_pads
			(clearance 0)
		)
		(min_thickness 0.25)
		(keepout
			(tracks not_allowed)
			(vias allowed)
			(pads allowed)
			(copperpour not_allowed)
			(footprints allowed)
		)
		(placement
			(enabled no)
			(sheetname "")
		)
		(fill
			(thermal_gap 0.5)
			(thermal_bridge_width 0.5)
			(island_removal_mode 0)
		)
		(polygon
			(pts
				(xy 430.80686 -316.925198) (xy 432.30546 -316.925198) (xy 432.30546 -317.445136) (xy 430.80686 -317.445136)
			)
		)
	)
	(zone
		(layer "In2.Cu")
		(hatch none 0.5)
		(connect_pads
			(clearance 0)
		)
		(min_thickness 0.25)
		(keepout
			(tracks not_allowed)
			(vias allowed)
			(pads allowed)
			(copperpour not_allowed)
			(footprints allowed)
		)
		(placement
			(enabled no)
			(sheetname "")
		)
		(fill
			(thermal_gap 0.5)
			(thermal_bridge_width 0.5)
			(island_removal_mode 0)
		)
		(polygon
			(pts
				(xy 434.250846 -295.675304) (xy 435.749446 -295.675304) (xy 435.749446 -296.195242) (xy 434.250846 -296.195242)
			)
		)
	)
	(zone
		(layer "In2.Cu")
		(hatch none 0.5)
		(connect_pads
			(clearance 0)
		)
		(min_thickness 0.25)
		(keepout
			(tracks not_allowed)
			(vias allowed)
			(pads allowed)
			(copperpour not_allowed)
			(footprints allowed)
		)
		(placement
			(enabled no)
			(sheetname "")
		)
		(fill
			(thermal_gap 0.5)
			(thermal_bridge_width 0.5)
			(island_removal_mode 0)
		)
		(polygon
			(pts
				(xy 426.706792 -225.975164) (xy 428.205392 -225.975164) (xy 428.205392 -226.495102) (xy 426.706792 -226.495102)
			)
		)
	)
	(zone
		(layer "In2.Cu")
		(hatch none 0.5)
		(connect_pads
			(clearance 0)
		)
		(min_thickness 0.25)
		(keepout
			(tracks not_allowed)
			(vias allowed)
			(pads allowed)
			(copperpour not_allowed)
			(footprints allowed)
		)
		(placement
			(enabled no)
			(sheetname "")
		)
		(fill
			(thermal_gap 0.5)
			(thermal_bridge_width 0.5)
			(island_removal_mode 0)
		)
		(polygon
			(pts
				(xy 445.894968 -285.475172) (xy 447.393568 -285.475172) (xy 447.393568 -285.99511) (xy 445.894968 -285.99511)
			)
		)
	)
	(zone
		(layer "In2.Cu")
		(hatch none 0.5)
		(connect_pads
			(clearance 0)
		)
		(min_thickness 0.25)
		(keepout
			(tracks not_allowed)
			(vias allowed)
			(pads allowed)
			(copperpour not_allowed)
			(footprints allowed)
		)
		(placement
			(enabled no)
			(sheetname "")
		)
		(fill
			(thermal_gap 0.5)
			(thermal_bridge_width 0.5)
			(island_removal_mode 0)
		)
		(polygon
			(pts
				(xy 449.3387 -213.225126) (xy 450.8373 -213.225126) (xy 450.8373 -213.745064) (xy 449.3387 -213.745064)
			)
		)
	)
	(zone
		(layer "In2.Cu")
		(hatch none 0.5)
		(connect_pads
			(clearance 0)
		)
		(min_thickness 0.25)
		(keepout
			(tracks not_allowed)
			(vias allowed)
			(pads allowed)
			(copperpour not_allowed)
			(footprints allowed)
		)
		(placement
			(enabled no)
			(sheetname "")
		)
		(fill
			(thermal_gap 0.5)
			(thermal_bridge_width 0.5)
			(island_removal_mode 0)
		)
		(polygon
			(pts
				(xy 430.80686 -217.475308) (xy 432.30546 -217.475308) (xy 432.30546 -217.995246) (xy 430.80686 -217.995246)
			)
		)
	)
	(zone
		(layer "In2.Cu")
		(hatch none 0.5)
		(connect_pads
			(clearance 0)
		)
		(min_thickness 0.25)
		(keepout
			(tracks not_allowed)
			(vias allowed)
			(pads allowed)
			(copperpour not_allowed)
			(footprints allowed)
		)
		(placement
			(enabled no)
			(sheetname "")
		)
		(fill
			(thermal_gap 0.5)
			(thermal_bridge_width 0.5)
			(island_removal_mode 0)
		)
		(polygon
			(pts
				(xy 294.974772 -299.075348) (xy 296.473372 -299.075348) (xy 296.473372 -299.595286) (xy 294.974772 -299.595286)
			)
		)
	)
	(zone
		(layer "In2.Cu")
		(hatch none 0.5)
		(connect_pads
			(clearance 0)
		)
		(min_thickness 0.25)
		(keepout
			(tracks not_allowed)
			(vias allowed)
			(pads allowed)
			(copperpour not_allowed)
			(footprints allowed)
		)
		(placement
			(enabled no)
			(sheetname "")
		)
		(fill
			(thermal_gap 0.5)
			(thermal_bridge_width 0.5)
			(island_removal_mode 0)
		)
		(polygon
			(pts
				(xy 197.954646 -214.075264) (xy 199.453246 -214.075264) (xy 199.453246 -214.595202) (xy 197.954646 -214.595202)
			)
		)
	)
	(zone
		(layer "In2.Cu")
		(hatch none 0.5)
		(connect_pads
			(clearance 0)
		)
		(min_thickness 0.25)
		(keepout
			(tracks not_allowed)
			(vias allowed)
			(pads allowed)
			(copperpour not_allowed)
			(footprints allowed)
		)
		(placement
			(enabled no)
			(sheetname "")
		)
		(fill
			(thermal_gap 0.5)
			(thermal_bridge_width 0.5)
			(island_removal_mode 0)
		)
		(polygon
			(pts
				(xy 186.310778 -197.925182) (xy 187.809378 -197.925182) (xy 187.809378 -198.44512) (xy 186.310778 -198.44512)
			)
		)
	)
	(zone
		(layer "In2.Cu")
		(hatch none 0.5)
		(connect_pads
			(clearance 0)
		)
		(min_thickness 0.25)
		(keepout
			(tracks not_allowed)
			(vias allowed)
			(pads allowed)
			(copperpour not_allowed)
			(footprints allowed)
		)
		(placement
			(enabled no)
			(sheetname "")
		)
		(fill
			(thermal_gap 0.5)
			(thermal_bridge_width 0.5)
			(island_removal_mode 0)
		)
		(polygon
			(pts
				(xy 434.250846 -308.425342) (xy 435.749446 -308.425342) (xy 435.749446 -308.94528) (xy 434.250846 -308.94528)
			)
		)
	)
	(zone
		(layer "In2.Cu")
		(hatch none 0.5)
		(connect_pads
			(clearance 0)
		)
		(min_thickness 0.25)
		(keepout
			(tracks not_allowed)
			(vias allowed)
			(pads allowed)
			(copperpour not_allowed)
			(footprints allowed)
		)
		(placement
			(enabled no)
			(sheetname "")
		)
		(fill
			(thermal_gap 0.5)
			(thermal_bridge_width 0.5)
			(island_removal_mode 0)
		)
		(polygon
			(pts
				(xy 291.530786 -240.425224) (xy 293.029386 -240.425224) (xy 293.029386 -240.945162) (xy 291.530786 -240.945162)
			)
		)
	)
	(zone
		(layer "In2.Cu")
		(hatch none 0.5)
		(connect_pads
			(clearance 0)
		)
		(min_thickness 0.25)
		(keepout
			(tracks not_allowed)
			(vias allowed)
			(pads allowed)
			(copperpour not_allowed)
			(footprints allowed)
		)
		(placement
			(enabled no)
			(sheetname "")
		)
		(fill
			(thermal_gap 0.5)
			(thermal_bridge_width 0.5)
			(island_removal_mode 0)
		)
		(polygon
			(pts
				(xy 299.07484 -310.975248) (xy 300.57344 -310.975248) (xy 300.57344 -311.495186) (xy 299.07484 -311.495186)
			)
		)
	)
	(zone
		(layer "In2.Cu")
		(hatch none 0.5)
		(connect_pads
			(clearance 0)
		)
		(min_thickness 0.25)
		(keepout
			(tracks not_allowed)
			(vias allowed)
			(pads allowed)
			(copperpour not_allowed)
			(footprints allowed)
		)
		(placement
			(enabled no)
			(sheetname "")
		)
		(fill
			(thermal_gap 0.5)
			(thermal_bridge_width 0.5)
			(island_removal_mode 0)
		)
		(polygon
			(pts
				(xy 291.530786 -307.575204) (xy 293.029386 -307.575204) (xy 293.029386 -308.095142) (xy 291.530786 -308.095142)
			)
		)
	)
	(zone
		(layer "In2.Cu")
		(hatch none 0.5)
		(connect_pads
			(clearance 0)
		)
		(min_thickness 0.25)
		(keepout
			(tracks not_allowed)
			(vias allowed)
			(pads allowed)
			(copperpour not_allowed)
			(footprints allowed)
		)
		(placement
			(enabled no)
			(sheetname "")
		)
		(fill
			(thermal_gap 0.5)
			(thermal_bridge_width 0.5)
			(island_removal_mode 0)
		)
		(polygon
			(pts
				(xy 131.405376 -32.363156) (xy 131.983226 -32.363156) (xy 131.983226 -33.683956) (xy 131.405376 -33.683956)
			)
		)
	)
	(zone
		(layer "In2.Cu")
		(hatch none 0.5)
		(connect_pads
			(clearance 0)
		)
		(min_thickness 0.25)
		(keepout
			(tracks not_allowed)
			(vias allowed)
			(pads allowed)
			(copperpour not_allowed)
			(footprints allowed)
		)
		(placement
			(enabled no)
			(sheetname "")
		)
		(fill
			(thermal_gap 0.5)
			(thermal_bridge_width 0.5)
			(island_removal_mode 0)
		)
		(polygon
			(pts
				(xy 201.398632 -282.075128) (xy 202.897232 -282.075128) (xy 202.897232 -282.595066) (xy 201.398632 -282.595066)
			)
		)
	)
	(zone
		(layer "In2.Cu")
		(hatch none 0.5)
		(connect_pads
			(clearance 0)
		)
		(min_thickness 0.25)
		(keepout
			(tracks not_allowed)
			(vias allowed)
			(pads allowed)
			(copperpour not_allowed)
			(footprints allowed)
		)
		(placement
			(enabled no)
			(sheetname "")
		)
		(fill
			(thermal_gap 0.5)
			(thermal_bridge_width 0.5)
			(island_removal_mode 0)
		)
		(polygon
			(pts
				(xy 24.402542 -246.375174) (xy 25.901142 -246.375174) (xy 25.901142 -246.895112) (xy 24.402542 -246.895112)
			)
		)
	)
	(zone
		(layer "In2.Cu")
		(hatch none 0.5)
		(connect_pads
			(clearance 0)
		)
		(min_thickness 0.25)
		(keepout
			(tracks not_allowed)
			(vias allowed)
			(pads allowed)
			(copperpour not_allowed)
			(footprints allowed)
		)
		(placement
			(enabled no)
			(sheetname "")
		)
		(fill
			(thermal_gap 0.5)
			(thermal_bridge_width 0.5)
			(island_removal_mode 0)
		)
		(polygon
			(pts
				(xy 58.678826 -260.825234) (xy 60.177426 -260.825234) (xy 60.177426 -261.345172) (xy 58.678826 -261.345172)
			)
		)
	)
	(zone
		(layer "In2.Cu")
		(hatch none 0.5)
		(connect_pads
			(clearance 0)
		)
		(min_thickness 0.25)
		(keepout
			(tracks not_allowed)
			(vias allowed)
			(pads allowed)
			(copperpour not_allowed)
			(footprints allowed)
		)
		(placement
			(enabled no)
			(sheetname "")
		)
		(fill
			(thermal_gap 0.5)
			(thermal_bridge_width 0.5)
			(island_removal_mode 0)
		)
		(polygon
			(pts
				(xy 201.398632 -246.375174) (xy 202.897232 -246.375174) (xy 202.897232 -246.895112) (xy 201.398632 -246.895112)
			)
		)
	)
	(zone
		(layer "In2.Cu")
		(hatch none 0.5)
		(connect_pads
			(clearance 0)
		)
		(min_thickness 0.25)
		(keepout
			(tracks not_allowed)
			(vias allowed)
			(pads allowed)
			(copperpour not_allowed)
			(footprints allowed)
		)
		(placement
			(enabled no)
			(sheetname "")
		)
		(fill
			(thermal_gap 0.5)
			(thermal_bridge_width 0.5)
			(island_removal_mode 0)
		)
		(polygon
			(pts
				(xy 423.262806 -223.425258) (xy 424.761406 -223.425258) (xy 424.761406 -223.945196) (xy 423.262806 -223.945196)
			)
		)
	)
	(zone
		(layer "In2.Cu")
		(hatch none 0.5)
		(connect_pads
			(clearance 0)
		)
		(min_thickness 0.25)
		(keepout
			(tracks not_allowed)
			(vias allowed)
			(pads allowed)
			(copperpour not_allowed)
			(footprints allowed)
		)
		(placement
			(enabled no)
			(sheetname "")
		)
		(fill
			(thermal_gap 0.5)
			(thermal_bridge_width 0.5)
			(island_removal_mode 0)
		)
		(polygon
			(pts
				(xy 163.678616 -308.425342) (xy 165.177216 -308.425342) (xy 165.177216 -308.94528) (xy 163.678616 -308.94528)
			)
		)
	)
	(zone
		(layer "In2.Cu")
		(hatch none 0.5)
		(connect_pads
			(clearance 0)
		)
		(min_thickness 0.25)
		(keepout
			(tracks not_allowed)
			(vias allowed)
			(pads allowed)
			(copperpour not_allowed)
			(footprints allowed)
		)
		(placement
			(enabled no)
			(sheetname "")
		)
		(fill
			(thermal_gap 0.5)
			(thermal_bridge_width 0.5)
			(island_removal_mode 0)
		)
		(polygon
			(pts
				(xy 193.854578 -295.675304) (xy 195.353178 -295.675304) (xy 195.353178 -296.195242) (xy 193.854578 -296.195242)
			)
		)
	)
	(zone
		(layer "In2.Cu")
		(hatch none 0.5)
		(connect_pads
			(clearance 0)
		)
		(min_thickness 0.25)
		(keepout
			(tracks not_allowed)
			(vias allowed)
			(pads allowed)
			(copperpour not_allowed)
			(footprints allowed)
		)
		(placement
			(enabled no)
			(sheetname "")
		)
		(fill
			(thermal_gap 0.5)
			(thermal_bridge_width 0.5)
			(island_removal_mode 0)
		)
		(polygon
			(pts
				(xy 279.886664 -251.47524) (xy 281.385264 -251.47524) (xy 281.385264 -251.995178) (xy 279.886664 -251.995178)
			)
		)
	)
	(zone
		(layer "In2.Cu")
		(hatch none 0.5)
		(connect_pads
			(clearance 0)
		)
		(min_thickness 0.25)
		(keepout
			(tracks not_allowed)
			(vias allowed)
			(pads allowed)
			(copperpour not_allowed)
			(footprints allowed)
		)
		(placement
			(enabled no)
			(sheetname "")
		)
		(fill
			(thermal_gap 0.5)
			(thermal_bridge_width 0.5)
			(island_removal_mode 0)
		)
		(polygon
			(pts
				(xy 294.974772 -239.57534) (xy 296.473372 -239.57534) (xy 296.473372 -240.095278) (xy 294.974772 -240.095278)
			)
		)
	)
	(zone
		(layer "In2.Cu")
		(hatch none 0.5)
		(connect_pads
			(clearance 0)
		)
		(min_thickness 0.25)
		(keepout
			(tracks not_allowed)
			(vias allowed)
			(pads allowed)
			(copperpour not_allowed)
			(footprints allowed)
		)
		(placement
			(enabled no)
			(sheetname "")
		)
		(fill
			(thermal_gap 0.5)
			(thermal_bridge_width 0.5)
			(island_removal_mode 0)
		)
		(polygon
			(pts
				(xy 272.342864 -203.875132) (xy 273.841464 -203.875132) (xy 273.841464 -204.39507) (xy 272.342864 -204.39507)
			)
		)
	)
	(zone
		(layer "In2.Cu")
		(hatch none 0.5)
		(connect_pads
			(clearance 0)
		)
		(min_thickness 0.25)
		(keepout
			(tracks not_allowed)
			(vias allowed)
			(pads allowed)
			(copperpour not_allowed)
			(footprints allowed)
		)
		(placement
			(enabled no)
			(sheetname "")
		)
		(fill
			(thermal_gap 0.5)
			(thermal_bridge_width 0.5)
			(island_removal_mode 0)
		)
		(polygon
			(pts
				(xy 163.678616 -220.025214) (xy 165.177216 -220.025214) (xy 165.177216 -220.545152) (xy 163.678616 -220.545152)
			)
		)
	)
	(zone
		(layer "In2.Cu")
		(hatch none 0.5)
		(connect_pads
			(clearance 0)
		)
		(min_thickness 0.25)
		(keepout
			(tracks not_allowed)
			(vias allowed)
			(pads allowed)
			(copperpour not_allowed)
			(footprints allowed)
		)
		(placement
			(enabled no)
			(sheetname "")
		)
		(fill
			(thermal_gap 0.5)
			(thermal_bridge_width 0.5)
			(island_removal_mode 0)
		)
		(polygon
			(pts
				(xy 283.986732 -288.875216) (xy 285.485332 -288.875216) (xy 285.485332 -289.395154) (xy 283.986732 -289.395154)
			)
		)
	)
	(zone
		(layer "In2.Cu")
		(hatch none 0.5)
		(connect_pads
			(clearance 0)
		)
		(min_thickness 0.25)
		(keepout
			(tracks not_allowed)
			(vias allowed)
			(pads allowed)
			(copperpour not_allowed)
			(footprints allowed)
		)
		(placement
			(enabled no)
			(sheetname "")
		)
		(fill
			(thermal_gap 0.5)
			(thermal_bridge_width 0.5)
			(island_removal_mode 0)
		)
		(polygon
			(pts
				(xy 272.342864 -202.17511) (xy 273.841464 -202.17511) (xy 273.841464 -202.695048) (xy 272.342864 -202.695048)
			)
		)
	)
	(zone
		(layer "In2.Cu")
		(hatch none 0.5)
		(connect_pads
			(clearance 0)
		)
		(min_thickness 0.25)
		(keepout
			(tracks not_allowed)
			(vias allowed)
			(pads allowed)
			(copperpour not_allowed)
			(footprints allowed)
		)
		(placement
			(enabled no)
			(sheetname "")
		)
		(fill
			(thermal_gap 0.5)
			(thermal_bridge_width 0.5)
			(island_removal_mode 0)
		)
		(polygon
			(pts
				(xy 438.350914 -267.625322) (xy 439.849514 -267.625322) (xy 439.849514 -268.14526) (xy 438.350914 -268.14526)
			)
		)
	)
	(zone
		(layer "In2.Cu")
		(hatch none 0.5)
		(connect_pads
			(clearance 0)
		)
		(min_thickness 0.25)
		(keepout
			(tracks not_allowed)
			(vias allowed)
			(pads allowed)
			(copperpour not_allowed)
			(footprints allowed)
		)
		(placement
			(enabled no)
			(sheetname "")
		)
		(fill
			(thermal_gap 0.5)
			(thermal_bridge_width 0.5)
			(island_removal_mode 0)
		)
		(polygon
			(pts
				(xy 171.22267 -311.825132) (xy 172.72127 -311.825132) (xy 172.72127 -312.34507) (xy 171.22267 -312.34507)
			)
		)
	)
	(zone
		(layer "In2.Cu")
		(hatch none 0.5)
		(connect_pads
			(clearance 0)
		)
		(min_thickness 0.25)
		(keepout
			(tracks not_allowed)
			(vias allowed)
			(pads allowed)
			(copperpour not_allowed)
			(footprints allowed)
		)
		(placement
			(enabled no)
			(sheetname "")
		)
		(fill
			(thermal_gap 0.5)
			(thermal_bridge_width 0.5)
			(island_removal_mode 0)
		)
		(polygon
			(pts
				(xy 167.778684 -277.8252) (xy 169.277284 -277.8252) (xy 169.277284 -278.345138) (xy 167.778684 -278.345138)
			)
		)
	)
	(zone
		(layer "In2.Cu")
		(hatch none 0.5)
		(connect_pads
			(clearance 0)
		)
		(min_thickness 0.25)
		(keepout
			(tracks not_allowed)
			(vias allowed)
			(pads allowed)
			(copperpour not_allowed)
			(footprints allowed)
		)
		(placement
			(enabled no)
			(sheetname "")
		)
		(fill
			(thermal_gap 0.5)
			(thermal_bridge_width 0.5)
			(island_removal_mode 0)
		)
		(polygon
			(pts
				(xy 294.974772 -227.675186) (xy 296.473372 -227.675186) (xy 296.473372 -228.195124) (xy 294.974772 -228.195124)
			)
		)
	)
	(zone
		(layer "In2.Cu")
		(hatch none 0.5)
		(connect_pads
			(clearance 0)
		)
		(min_thickness 0.25)
		(keepout
			(tracks not_allowed)
			(vias allowed)
			(pads allowed)
			(copperpour not_allowed)
			(footprints allowed)
		)
		(placement
			(enabled no)
			(sheetname "")
		)
		(fill
			(thermal_gap 0.5)
			(thermal_bridge_width 0.5)
			(island_removal_mode 0)
		)
		(polygon
			(pts
				(xy 445.894968 -237.875318) (xy 447.393568 -237.875318) (xy 447.393568 -238.395256) (xy 445.894968 -238.395256)
			)
		)
	)
	(zone
		(layer "In2.Cu")
		(hatch none 0.5)
		(connect_pads
			(clearance 0)
		)
		(min_thickness 0.25)
		(keepout
			(tracks not_allowed)
			(vias allowed)
			(pads allowed)
			(copperpour not_allowed)
			(footprints allowed)
		)
		(placement
			(enabled no)
			(sheetname "")
		)
		(fill
			(thermal_gap 0.5)
			(thermal_bridge_width 0.5)
			(island_removal_mode 0)
		)
		(polygon
			(pts
				(xy 453.438768 -225.12528) (xy 454.937368 -225.12528) (xy 454.937368 -225.645218) (xy 453.438768 -225.645218)
			)
		)
	)
	(zone
		(layer "In2.Cu")
		(hatch none 0.5)
		(connect_pads
			(clearance 0)
		)
		(min_thickness 0.25)
		(keepout
			(tracks not_allowed)
			(vias allowed)
			(pads allowed)
			(copperpour not_allowed)
			(footprints allowed)
		)
		(placement
			(enabled no)
			(sheetname "")
		)
		(fill
			(thermal_gap 0.5)
			(thermal_bridge_width 0.5)
			(island_removal_mode 0)
		)
		(polygon
			(pts
				(xy 167.778684 -262.525256) (xy 169.277284 -262.525256) (xy 169.277284 -263.045194) (xy 167.778684 -263.045194)
			)
		)
	)
	(zone
		(layer "In2.Cu")
		(hatch none 0.5)
		(connect_pads
			(clearance 0)
		)
		(min_thickness 0.25)
		(keepout
			(tracks not_allowed)
			(vias allowed)
			(pads allowed)
			(copperpour not_allowed)
			(footprints allowed)
		)
		(placement
			(enabled no)
			(sheetname "")
		)
		(fill
			(thermal_gap 0.5)
			(thermal_bridge_width 0.5)
			(island_removal_mode 0)
		)
		(polygon
			(pts
				(xy 20.95881 -269.325344) (xy 22.45741 -269.325344) (xy 22.45741 -269.845282) (xy 20.95881 -269.845282)
			)
		)
	)
	(zone
		(layer "In2.Cu")
		(hatch none 0.5)
		(connect_pads
			(clearance 0)
		)
		(min_thickness 0.25)
		(keepout
			(tracks not_allowed)
			(vias allowed)
			(pads allowed)
			(copperpour not_allowed)
			(footprints allowed)
		)
		(placement
			(enabled no)
			(sheetname "")
		)
		(fill
			(thermal_gap 0.5)
			(thermal_bridge_width 0.5)
			(island_removal_mode 0)
		)
		(polygon
			(pts
				(arc
					(start 42.362374 -7.672324)
					(mid 42.384692 -7.618442)
					(end 42.438574 -7.596124)
				)
				(arc
					(start 43.475148 -7.596124)
					(mid 43.52903 -7.618442)
					(end 43.551348 -7.672324)
				)
				(arc
					(start 43.551348 -9.071864)
					(mid 43.52903 -9.125746)
					(end 43.475148 -9.148064)
				)
				(arc
					(start 42.438574 -9.148064)
					(mid 42.384692 -9.125746)
					(end 42.362374 -9.071864)
				)
			)
		)
	)
	(zone
		(layer "In2.Cu")
		(hatch none 0.5)
		(connect_pads
			(clearance 0)
		)
		(min_thickness 0.25)
		(keepout
			(tracks not_allowed)
			(vias allowed)
			(pads allowed)
			(copperpour not_allowed)
			(footprints allowed)
		)
		(placement
			(enabled no)
			(sheetname "")
		)
		(fill
			(thermal_gap 0.5)
			(thermal_bridge_width 0.5)
			(island_removal_mode 0)
		)
		(polygon
			(pts
				(xy 453.438768 -267.625322) (xy 454.937368 -267.625322) (xy 454.937368 -268.14526) (xy 453.438768 -268.14526)
			)
		)
	)
	(zone
		(layer "In2.Cu")
		(hatch none 0.5)
		(connect_pads
			(clearance 0)
		)
		(min_thickness 0.25)
		(keepout
			(tracks not_allowed)
			(vias allowed)
			(pads allowed)
			(copperpour not_allowed)
			(footprints allowed)
		)
		(placement
			(enabled no)
			(sheetname "")
		)
		(fill
			(thermal_gap 0.5)
			(thermal_bridge_width 0.5)
			(island_removal_mode 0)
		)
		(polygon
			(pts
				(xy 58.678826 -242.125246) (xy 60.177426 -242.125246) (xy 60.177426 -242.645184) (xy 58.678826 -242.645184)
			)
		)
	)
	(zone
		(layer "In2.Cu")
		(hatch none 0.5)
		(connect_pads
			(clearance 0)
		)
		(min_thickness 0.25)
		(keepout
			(tracks not_allowed)
			(vias allowed)
			(pads allowed)
			(copperpour not_allowed)
			(footprints allowed)
		)
		(placement
			(enabled no)
			(sheetname "")
		)
		(fill
			(thermal_gap 0.5)
			(thermal_bridge_width 0.5)
			(island_removal_mode 0)
		)
		(polygon
			(pts
				(xy 197.954646 -294.825166) (xy 199.453246 -294.825166) (xy 199.453246 -295.345104) (xy 197.954646 -295.345104)
			)
		)
	)
	(zone
		(layer "In2.Cu")
		(hatch none 0.5)
		(connect_pads
			(clearance 0)
		)
		(min_thickness 0.25)
		(keepout
			(tracks not_allowed)
			(vias allowed)
			(pads allowed)
			(copperpour not_allowed)
			(footprints allowed)
		)
		(placement
			(enabled no)
			(sheetname "")
		)
		(fill
			(thermal_gap 0.5)
			(thermal_bridge_width 0.5)
			(island_removal_mode 0)
		)
		(polygon
			(pts
				(xy 47.034704 -203.875132) (xy 48.533304 -203.875132) (xy 48.533304 -204.39507) (xy 47.034704 -204.39507)
			)
		)
	)
	(zone
		(layer "In2.Cu")
		(hatch none 0.5)
		(connect_pads
			(clearance 0)
		)
		(min_thickness 0.25)
		(keepout
			(tracks not_allowed)
			(vias allowed)
			(pads allowed)
			(copperpour not_allowed)
			(footprints allowed)
		)
		(placement
			(enabled no)
			(sheetname "")
		)
		(fill
			(thermal_gap 0.5)
			(thermal_bridge_width 0.5)
			(island_removal_mode 0)
		)
		(polygon
			(pts
				(xy 171.22267 -263.37514) (xy 172.72127 -263.37514) (xy 172.72127 -263.895078) (xy 171.22267 -263.895078)
			)
		)
	)
	(zone
		(layer "In2.Cu")
		(hatch none 0.5)
		(connect_pads
			(clearance 0)
		)
		(min_thickness 0.25)
		(keepout
			(tracks not_allowed)
			(vias allowed)
			(pads allowed)
			(copperpour not_allowed)
			(footprints allowed)
		)
		(placement
			(enabled no)
			(sheetname "")
		)
		(fill
			(thermal_gap 0.5)
			(thermal_bridge_width 0.5)
			(island_removal_mode 0)
		)
		(polygon
			(pts
				(xy 434.250846 -238.725202) (xy 435.749446 -238.725202) (xy 435.749446 -239.24514) (xy 434.250846 -239.24514)
			)
		)
	)
	(zone
		(layer "In2.Cu")
		(hatch none 0.5)
		(connect_pads
			(clearance 0)
		)
		(min_thickness 0.25)
		(keepout
			(tracks not_allowed)
			(vias allowed)
			(pads allowed)
			(copperpour not_allowed)
			(footprints allowed)
		)
		(placement
			(enabled no)
			(sheetname "")
		)
		(fill
			(thermal_gap 0.5)
			(thermal_bridge_width 0.5)
			(island_removal_mode 0)
		)
		(polygon
			(pts
				(xy 16.858742 -241.275108) (xy 18.357342 -241.275108) (xy 18.357342 -241.795046) (xy 16.858742 -241.795046)
			)
		)
	)
	(zone
		(layer "In2.Cu")
		(hatch none 0.5)
		(connect_pads
			(clearance 0)
		)
		(min_thickness 0.25)
		(keepout
			(tracks not_allowed)
			(vias allowed)
			(pads allowed)
			(copperpour not_allowed)
			(footprints allowed)
		)
		(placement
			(enabled no)
			(sheetname "")
		)
		(fill
			(thermal_gap 0.5)
			(thermal_bridge_width 0.5)
			(island_removal_mode 0)
		)
		(polygon
			(pts
				(xy 306.618894 -242.125246) (xy 308.117494 -242.125246) (xy 308.117494 -242.645184) (xy 306.618894 -242.645184)
			)
		)
	)
	(zone
		(layer "In2.Cu")
		(hatch none 0.5)
		(connect_pads
			(clearance 0)
		)
		(min_thickness 0.25)
		(keepout
			(tracks not_allowed)
			(vias allowed)
			(pads allowed)
			(copperpour not_allowed)
			(footprints allowed)
		)
		(placement
			(enabled no)
			(sheetname "")
		)
		(fill
			(thermal_gap 0.5)
			(thermal_bridge_width 0.5)
			(island_removal_mode 0)
		)
		(polygon
			(pts
				(xy 449.3387 -310.12511) (xy 450.8373 -310.12511) (xy 450.8373 -310.645048) (xy 449.3387 -310.645048)
			)
		)
	)
	(zone
		(layer "In2.Cu")
		(hatch none 0.5)
		(connect_pads
			(clearance 0)
		)
		(min_thickness 0.25)
		(keepout
			(tracks not_allowed)
			(vias allowed)
			(pads allowed)
			(copperpour not_allowed)
			(footprints allowed)
		)
		(placement
			(enabled no)
			(sheetname "")
		)
		(fill
			(thermal_gap 0.5)
			(thermal_bridge_width 0.5)
			(island_removal_mode 0)
		)
		(polygon
			(pts
				(xy 20.95881 -214.075264) (xy 22.45741 -214.075264) (xy 22.45741 -214.595202) (xy 20.95881 -214.595202)
			)
		)
	)
	(zone
		(layer "In2.Cu")
		(hatch none 0.5)
		(connect_pads
			(clearance 0)
		)
		(min_thickness 0.25)
		(keepout
			(tracks not_allowed)
			(vias allowed)
			(pads allowed)
			(copperpour not_allowed)
			(footprints allowed)
		)
		(placement
			(enabled no)
			(sheetname "")
		)
		(fill
			(thermal_gap 0.5)
			(thermal_bridge_width 0.5)
			(island_removal_mode 0)
		)
		(polygon
			(pts
				(xy 58.678826 -315.225176) (xy 60.177426 -315.225176) (xy 60.177426 -315.745114) (xy 58.678826 -315.745114)
			)
		)
	)
	(zone
		(layer "In2.Cu")
		(hatch none 0.5)
		(connect_pads
			(clearance 0)
		)
		(min_thickness 0.25)
		(keepout
			(tracks not_allowed)
			(vias allowed)
			(pads allowed)
			(copperpour not_allowed)
			(footprints allowed)
		)
		(placement
			(enabled no)
			(sheetname "")
		)
		(fill
			(thermal_gap 0.5)
			(thermal_bridge_width 0.5)
			(island_removal_mode 0)
		)
		(polygon
			(pts
				(xy 31.946596 -216.62517) (xy 33.445196 -216.62517) (xy 33.445196 -217.145108) (xy 31.946596 -217.145108)
			)
		)
	)
	(zone
		(layer "In2.Cu")
		(hatch none 0.5)
		(connect_pads
			(clearance 0)
		)
		(min_thickness 0.25)
		(keepout
			(tracks not_allowed)
			(vias allowed)
			(pads allowed)
			(copperpour not_allowed)
			(footprints allowed)
		)
		(placement
			(enabled no)
			(sheetname "")
		)
		(fill
			(thermal_gap 0.5)
			(thermal_bridge_width 0.5)
			(island_removal_mode 0)
		)
		(polygon
			(pts
				(xy 31.946596 -249.775218) (xy 33.445196 -249.775218) (xy 33.445196 -250.295156) (xy 31.946596 -250.295156)
			)
		)
	)
	(zone
		(layer "In2.Cu")
		(hatch none 0.5)
		(connect_pads
			(clearance 0)
		)
		(min_thickness 0.25)
		(keepout
			(tracks not_allowed)
			(vias allowed)
			(pads allowed)
			(copperpour not_allowed)
			(footprints allowed)
		)
		(placement
			(enabled no)
			(sheetname "")
		)
		(fill
			(thermal_gap 0.5)
			(thermal_bridge_width 0.5)
			(island_removal_mode 0)
		)
		(polygon
			(pts
				(xy 193.854578 -316.075314) (xy 195.353178 -316.075314) (xy 195.353178 -316.595252) (xy 193.854578 -316.595252)
			)
		)
	)
	(zone
		(layer "In2.Cu")
		(hatch none 0.5)
		(connect_pads
			(clearance 0)
		)
		(min_thickness 0.25)
		(keepout
			(tracks not_allowed)
			(vias allowed)
			(pads allowed)
			(copperpour not_allowed)
			(footprints allowed)
		)
		(placement
			(enabled no)
			(sheetname "")
		)
		(fill
			(thermal_gap 0.5)
			(thermal_bridge_width 0.5)
			(island_removal_mode 0)
		)
		(polygon
			(pts
				(xy 163.678616 -302.475138) (xy 165.177216 -302.475138) (xy 165.177216 -302.995076) (xy 163.678616 -302.995076)
			)
		)
	)
	(zone
		(layer "In2.Cu")
		(hatch none 0.5)
		(connect_pads
			(clearance 0)
		)
		(min_thickness 0.25)
		(keepout
			(tracks not_allowed)
			(vias allowed)
			(pads allowed)
			(copperpour not_allowed)
			(footprints allowed)
		)
		(placement
			(enabled no)
			(sheetname "")
		)
		(fill
			(thermal_gap 0.5)
			(thermal_bridge_width 0.5)
			(island_removal_mode 0)
		)
		(polygon
			(pts
				(xy 171.22267 -291.425122) (xy 172.72127 -291.425122) (xy 172.72127 -291.94506) (xy 171.22267 -291.94506)
			)
		)
	)
	(zone
		(layer "In2.Cu")
		(hatch none 0.5)
		(connect_pads
			(clearance 0)
		)
		(min_thickness 0.25)
		(keepout
			(tracks not_allowed)
			(vias allowed)
			(pads allowed)
			(copperpour not_allowed)
			(footprints allowed)
		)
		(placement
			(enabled no)
			(sheetname "")
		)
		(fill
			(thermal_gap 0.5)
			(thermal_bridge_width 0.5)
			(island_removal_mode 0)
		)
		(polygon
			(pts
				(xy 287.430718 -229.375208) (xy 288.929318 -229.375208) (xy 288.929318 -229.895146) (xy 287.430718 -229.895146)
			)
		)
	)
	(zone
		(layer "In2.Cu")
		(hatch none 0.5)
		(connect_pads
			(clearance 0)
		)
		(min_thickness 0.25)
		(keepout
			(tracks not_allowed)
			(vias allowed)
			(pads allowed)
			(copperpour not_allowed)
			(footprints allowed)
		)
		(placement
			(enabled no)
			(sheetname "")
		)
		(fill
			(thermal_gap 0.5)
			(thermal_bridge_width 0.5)
			(island_removal_mode 0)
		)
		(polygon
			(pts
				(xy 453.438768 -212.375242) (xy 454.937368 -212.375242) (xy 454.937368 -212.89518) (xy 453.438768 -212.89518)
			)
		)
	)
	(zone
		(layer "In2.Cu")
		(hatch none 0.5)
		(connect_pads
			(clearance 0)
		)
		(min_thickness 0.25)
		(keepout
			(tracks not_allowed)
			(vias allowed)
			(pads allowed)
			(copperpour not_allowed)
			(footprints allowed)
		)
		(placement
			(enabled no)
			(sheetname "")
		)
		(fill
			(thermal_gap 0.5)
			(thermal_bridge_width 0.5)
			(island_removal_mode 0)
		)
		(polygon
			(pts
				(xy 453.438768 -217.475308) (xy 454.937368 -217.475308) (xy 454.937368 -217.995246) (xy 453.438768 -217.995246)
			)
		)
	)
	(zone
		(layer "In2.Cu")
		(hatch none 0.5)
		(connect_pads
			(clearance 0)
		)
		(min_thickness 0.25)
		(keepout
			(tracks not_allowed)
			(vias allowed)
			(pads allowed)
			(copperpour not_allowed)
			(footprints allowed)
		)
		(placement
			(enabled no)
			(sheetname "")
		)
		(fill
			(thermal_gap 0.5)
			(thermal_bridge_width 0.5)
			(island_removal_mode 0)
		)
		(polygon
			(pts
				(xy 426.706792 -278.675338) (xy 428.205392 -278.675338) (xy 428.205392 -279.195276) (xy 426.706792 -279.195276)
			)
		)
	)
	(zone
		(layer "In2.Cu")
		(hatch none 0.5)
		(connect_pads
			(clearance 0)
		)
		(min_thickness 0.25)
		(keepout
			(tracks not_allowed)
			(vias allowed)
			(pads allowed)
			(copperpour not_allowed)
			(footprints allowed)
		)
		(placement
			(enabled no)
			(sheetname "")
		)
		(fill
			(thermal_gap 0.5)
			(thermal_bridge_width 0.5)
			(island_removal_mode 0)
		)
		(polygon
			(pts
				(xy 54.578758 -216.62517) (xy 56.077358 -216.62517) (xy 56.077358 -217.145108) (xy 54.578758 -217.145108)
			)
		)
	)
	(zone
		(layer "In2.Cu")
		(hatch none 0.5)
		(connect_pads
			(clearance 0)
		)
		(min_thickness 0.25)
		(keepout
			(tracks not_allowed)
			(vias allowed)
			(pads allowed)
			(copperpour not_allowed)
			(footprints allowed)
		)
		(placement
			(enabled no)
			(sheetname "")
		)
		(fill
			(thermal_gap 0.5)
			(thermal_bridge_width 0.5)
			(island_removal_mode 0)
		)
		(polygon
			(pts
				(xy 411.618684 -220.875098) (xy 413.117284 -220.875098) (xy 413.117284 -221.395036) (xy 411.618684 -221.395036)
			)
		)
	)
	(zone
		(layer "In2.Cu")
		(hatch none 0.5)
		(connect_pads
			(clearance 0)
		)
		(min_thickness 0.25)
		(keepout
			(tracks not_allowed)
			(vias allowed)
			(pads allowed)
			(copperpour not_allowed)
			(footprints allowed)
		)
		(placement
			(enabled no)
			(sheetname "")
		)
		(fill
			(thermal_gap 0.5)
			(thermal_bridge_width 0.5)
			(island_removal_mode 0)
		)
		(polygon
			(pts
				(xy 306.618894 -281.225244) (xy 308.117494 -281.225244) (xy 308.117494 -281.745182) (xy 306.618894 -281.745182)
			)
		)
	)
	(zone
		(layer "In2.Cu")
		(hatch none 0.5)
		(connect_pads
			(clearance 0)
		)
		(min_thickness 0.25)
		(keepout
			(tracks not_allowed)
			(vias allowed)
			(pads allowed)
			(copperpour not_allowed)
			(footprints allowed)
		)
		(placement
			(enabled no)
			(sheetname "")
		)
		(fill
			(thermal_gap 0.5)
			(thermal_bridge_width 0.5)
			(island_removal_mode 0)
		)
		(polygon
			(pts
				(xy 58.678826 -198.77532) (xy 60.177426 -198.77532) (xy 60.177426 -199.295258) (xy 58.678826 -199.295258)
			)
		)
	)
	(zone
		(layer "In2.Cu")
		(hatch none 0.5)
		(connect_pads
			(clearance 0)
		)
		(min_thickness 0.25)
		(keepout
			(tracks not_allowed)
			(vias allowed)
			(pads allowed)
			(copperpour not_allowed)
			(footprints allowed)
		)
		(placement
			(enabled no)
			(sheetname "")
		)
		(fill
			(thermal_gap 0.5)
			(thermal_bridge_width 0.5)
			(island_removal_mode 0)
		)
		(polygon
			(pts
				(xy 441.7949 -291.425122) (xy 443.2935 -291.425122) (xy 443.2935 -291.94506) (xy 441.7949 -291.94506)
			)
		)
	)
	(zone
		(layer "In2.Cu")
		(hatch none 0.5)
		(connect_pads
			(clearance 0)
		)
		(min_thickness 0.25)
		(keepout
			(tracks not_allowed)
			(vias allowed)
			(pads allowed)
			(copperpour not_allowed)
			(footprints allowed)
		)
		(placement
			(enabled no)
			(sheetname "")
		)
		(fill
			(thermal_gap 0.5)
			(thermal_bridge_width 0.5)
			(island_removal_mode 0)
		)
		(polygon
			(pts
				(xy 419.162738 -278.675338) (xy 420.661338 -278.675338) (xy 420.661338 -279.195276) (xy 419.162738 -279.195276)
			)
		)
	)
	(zone
		(layer "In2.Cu")
		(hatch none 0.5)
		(connect_pads
			(clearance 0)
		)
		(min_thickness 0.25)
		(keepout
			(tracks not_allowed)
			(vias allowed)
			(pads allowed)
			(copperpour not_allowed)
			(footprints allowed)
		)
		(placement
			(enabled no)
			(sheetname "")
		)
		(fill
			(thermal_gap 0.5)
			(thermal_bridge_width 0.5)
			(island_removal_mode 0)
		)
		(polygon
			(pts
				(xy 453.438768 -234.475274) (xy 454.937368 -234.475274) (xy 454.937368 -234.995212) (xy 453.438768 -234.995212)
			)
		)
	)
	(zone
		(layer "In2.Cu")
		(hatch none 0.5)
		(connect_pads
			(clearance 0)
		)
		(min_thickness 0.25)
		(keepout
			(tracks allowed)
			(vias allowed)
			(pads allowed)
			(copperpour allowed)
			(footprints allowed)
		)
		(placement
			(enabled no)
			(sheetname "")
		)
		(fill
			(thermal_gap 0.5)
			(thermal_bridge_width 0.5)
			(island_removal_mode 0)
		)
		(polygon
			(pts
				(xy 286.24657 -349.854266) (xy 286.24657 -349.231966) (xy 286.79775 -349.231966) (xy 286.79775 -349.854266)
			)
		)
	)
	(zone
		(layer "In2.Cu")
		(hatch none 0.5)
		(connect_pads
			(clearance 0)
		)
		(min_thickness 0.25)
		(keepout
			(tracks not_allowed)
			(vias allowed)
			(pads allowed)
			(copperpour not_allowed)
			(footprints allowed)
		)
		(placement
			(enabled no)
			(sheetname "")
		)
		(fill
			(thermal_gap 0.5)
			(thermal_bridge_width 0.5)
			(island_removal_mode 0)
		)
		(polygon
			(pts
				(xy 445.894968 -294.825166) (xy 447.393568 -294.825166) (xy 447.393568 -295.345104) (xy 445.894968 -295.345104)
			)
		)
	)
	(zone
		(layer "In2.Cu")
		(hatch none 0.5)
		(connect_pads
			(clearance 0)
		)
		(min_thickness 0.25)
		(keepout
			(tracks not_allowed)
			(vias allowed)
			(pads allowed)
			(copperpour not_allowed)
			(footprints allowed)
		)
		(placement
			(enabled no)
			(sheetname "")
		)
		(fill
			(thermal_gap 0.5)
			(thermal_bridge_width 0.5)
			(island_removal_mode 0)
		)
		(polygon
			(pts
				(xy 453.438768 -243.825268) (xy 454.937368 -243.825268) (xy 454.937368 -244.345206) (xy 453.438768 -244.345206)
			)
		)
	)
	(zone
		(layer "In2.Cu")
		(hatch none 0.5)
		(connect_pads
			(clearance 0)
		)
		(min_thickness 0.25)
		(keepout
			(tracks not_allowed)
			(vias allowed)
			(pads allowed)
			(copperpour not_allowed)
			(footprints allowed)
		)
		(placement
			(enabled no)
			(sheetname "")
		)
		(fill
			(thermal_gap 0.5)
			(thermal_bridge_width 0.5)
			(island_removal_mode 0)
		)
		(polygon
			(pts
				(xy 449.3387 -278.675338) (xy 450.8373 -278.675338) (xy 450.8373 -279.195276) (xy 449.3387 -279.195276)
			)
		)
	)
	(zone
		(layer "In2.Cu")
		(hatch none 0.5)
		(connect_pads
			(clearance 0)
		)
		(min_thickness 0.25)
		(keepout
			(tracks allowed)
			(vias allowed)
			(pads allowed)
			(copperpour allowed)
			(footprints allowed)
		)
		(placement
			(enabled no)
			(sheetname "")
		)
		(fill
			(thermal_gap 0.5)
			(thermal_bridge_width 0.5)
			(island_removal_mode 0)
		)
		(polygon
			(pts
				(xy 52.446174 -419.905688) (xy 51.919886 -419.905688) (xy 51.919886 -418.561012) (xy 52.446174 -418.561012)
			)
		)
	)
	(zone
		(layer "In2.Cu")
		(hatch none 0.5)
		(connect_pads
			(clearance 0)
		)
		(min_thickness 0.25)
		(keepout
			(tracks not_allowed)
			(vias allowed)
			(pads allowed)
			(copperpour not_allowed)
			(footprints allowed)
		)
		(placement
			(enabled no)
			(sheetname "")
		)
		(fill
			(thermal_gap 0.5)
			(thermal_bridge_width 0.5)
			(island_removal_mode 0)
		)
		(polygon
			(pts
				(xy 423.262806 -298.22521) (xy 424.761406 -298.22521) (xy 424.761406 -298.745148) (xy 423.262806 -298.745148)
			)
		)
	)
	(zone
		(layer "In2.Cu")
		(hatch none 0.5)
		(connect_pads
			(clearance 0)
		)
		(min_thickness 0.25)
		(keepout
			(tracks not_allowed)
			(vias allowed)
			(pads allowed)
			(copperpour not_allowed)
			(footprints allowed)
		)
		(placement
			(enabled no)
			(sheetname "")
		)
		(fill
			(thermal_gap 0.5)
			(thermal_bridge_width 0.5)
			(island_removal_mode 0)
		)
		(polygon
			(pts
				(xy 287.430718 -242.97513) (xy 288.929318 -242.97513) (xy 288.929318 -243.495068) (xy 287.430718 -243.495068)
			)
		)
	)
	(zone
		(layer "In2.Cu")
		(hatch none 0.5)
		(connect_pads
			(clearance 0)
		)
		(min_thickness 0.25)
		(keepout
			(tracks not_allowed)
			(vias allowed)
			(pads allowed)
			(copperpour not_allowed)
			(footprints allowed)
		)
		(placement
			(enabled no)
			(sheetname "")
		)
		(fill
			(thermal_gap 0.5)
			(thermal_bridge_width 0.5)
			(island_removal_mode 0)
		)
		(polygon
			(pts
				(arc
					(start 20.652486 -7.672324)
					(mid 20.674804 -7.618442)
					(end 20.728686 -7.596124)
				)
				(arc
					(start 21.76526 -7.596124)
					(mid 21.819142 -7.618442)
					(end 21.84146 -7.672324)
				)
				(arc
					(start 21.84146 -9.071864)
					(mid 21.819142 -9.125746)
					(end 21.76526 -9.148064)
				)
				(arc
					(start 20.728686 -9.148064)
					(mid 20.674804 -9.125746)
					(end 20.652486 -9.071864)
				)
			)
		)
	)
	(zone
		(layer "In2.Cu")
		(hatch none 0.5)
		(connect_pads
			(clearance 0)
		)
		(min_thickness 0.25)
		(keepout
			(tracks not_allowed)
			(vias allowed)
			(pads allowed)
			(copperpour not_allowed)
			(footprints allowed)
		)
		(placement
			(enabled no)
			(sheetname "")
		)
		(fill
			(thermal_gap 0.5)
			(thermal_bridge_width 0.5)
			(island_removal_mode 0)
		)
		(polygon
			(pts
				(xy 163.678616 -291.425122) (xy 165.177216 -291.425122) (xy 165.177216 -291.94506) (xy 163.678616 -291.94506)
			)
		)
	)
	(zone
		(layer "In2.Cu")
		(hatch none 0.5)
		(connect_pads
			(clearance 0)
		)
		(min_thickness 0.25)
		(keepout
			(tracks not_allowed)
			(vias allowed)
			(pads allowed)
			(copperpour not_allowed)
			(footprints allowed)
		)
		(placement
			(enabled no)
			(sheetname "")
		)
		(fill
			(thermal_gap 0.5)
			(thermal_bridge_width 0.5)
			(island_removal_mode 0)
		)
		(polygon
			(pts
				(xy 28.50261 -271.87525) (xy 30.00121 -271.87525) (xy 30.00121 -272.395188) (xy 28.50261 -272.395188)
			)
		)
	)
	(zone
		(layer "In2.Cu")
		(hatch none 0.5)
		(connect_pads
			(clearance 0)
		)
		(min_thickness 0.25)
		(keepout
			(tracks not_allowed)
			(vias allowed)
			(pads allowed)
			(copperpour not_allowed)
			(footprints allowed)
		)
		(placement
			(enabled no)
			(sheetname "")
		)
		(fill
			(thermal_gap 0.5)
			(thermal_bridge_width 0.5)
			(island_removal_mode 0)
		)
		(polygon
			(pts
				(xy 283.986732 -245.52529) (xy 285.485332 -245.52529) (xy 285.485332 -246.045228) (xy 283.986732 -246.045228)
			)
		)
	)
	(zone
		(layer "In2.Cu")
		(hatch none 0.5)
		(connect_pads
			(clearance 0)
		)
		(min_thickness 0.25)
		(keepout
			(tracks not_allowed)
			(vias allowed)
			(pads allowed)
			(copperpour not_allowed)
			(footprints allowed)
		)
		(placement
			(enabled no)
			(sheetname "")
		)
		(fill
			(thermal_gap 0.5)
			(thermal_bridge_width 0.5)
			(island_removal_mode 0)
		)
		(polygon
			(pts
				(xy 28.50261 -219.17533) (xy 30.00121 -219.17533) (xy 30.00121 -219.695268) (xy 28.50261 -219.695268)
			)
		)
	)
	(zone
		(layer "In2.Cu")
		(hatch none 0.5)
		(connect_pads
			(clearance 0)
		)
		(min_thickness 0.25)
		(keepout
			(tracks not_allowed)
			(vias allowed)
			(pads allowed)
			(copperpour not_allowed)
			(footprints allowed)
		)
		(placement
			(enabled no)
			(sheetname "")
		)
		(fill
			(thermal_gap 0.5)
			(thermal_bridge_width 0.5)
			(island_removal_mode 0)
		)
		(polygon
			(pts
				(xy 449.3387 -300.775116) (xy 450.8373 -300.775116) (xy 450.8373 -301.295054) (xy 449.3387 -301.295054)
			)
		)
	)
	(zone
		(layer "In2.Cu")
		(hatch none 0.5)
		(connect_pads
			(clearance 0)
		)
		(min_thickness 0.25)
		(keepout
			(tracks allowed)
			(vias allowed)
			(pads allowed)
			(copperpour allowed)
			(footprints allowed)
		)
		(placement
			(enabled no)
			(sheetname "")
		)
		(fill
			(thermal_gap 0.5)
			(thermal_bridge_width 0.5)
			(island_removal_mode 0)
		)
		(polygon
			(pts
				(xy 25.00503 -347.628972) (xy 25.00503 -348.512892) (xy 24.80183 -348.512892) (xy 24.80183 -347.628972)
			)
		)
	)
	(zone
		(layer "In2.Cu")
		(hatch none 0.5)
		(connect_pads
			(clearance 0)
		)
		(min_thickness 0.25)
		(keepout
			(tracks not_allowed)
			(vias allowed)
			(pads allowed)
			(copperpour not_allowed)
			(footprints allowed)
		)
		(placement
			(enabled no)
			(sheetname "")
		)
		(fill
			(thermal_gap 0.5)
			(thermal_bridge_width 0.5)
			(island_removal_mode 0)
		)
		(polygon
			(pts
				(xy 283.986732 -236.175296) (xy 285.485332 -236.175296) (xy 285.485332 -236.695234) (xy 283.986732 -236.695234)
			)
		)
	)
	(zone
		(layer "In2.Cu")
		(hatch none 0.5)
		(connect_pads
			(clearance 0)
		)
		(min_thickness 0.25)
		(keepout
			(tracks not_allowed)
			(vias allowed)
			(pads allowed)
			(copperpour not_allowed)
			(footprints allowed)
		)
		(placement
			(enabled no)
			(sheetname "")
		)
		(fill
			(thermal_gap 0.5)
			(thermal_bridge_width 0.5)
			(island_removal_mode 0)
		)
		(polygon
			(pts
				(xy 302.518826 -310.12511) (xy 304.017426 -310.12511) (xy 304.017426 -310.645048) (xy 302.518826 -310.645048)
			)
		)
	)
	(zone
		(layer "In2.Cu")
		(hatch none 0.5)
		(connect_pads
			(clearance 0)
		)
		(min_thickness 0.25)
		(keepout
			(tracks not_allowed)
			(vias allowed)
			(pads allowed)
			(copperpour not_allowed)
			(footprints allowed)
		)
		(placement
			(enabled no)
			(sheetname "")
		)
		(fill
			(thermal_gap 0.5)
			(thermal_bridge_width 0.5)
			(island_removal_mode 0)
		)
		(polygon
			(pts
				(xy 268.898878 -200.475342) (xy 270.397478 -200.475342) (xy 270.397478 -200.99528) (xy 268.898878 -200.99528)
			)
		)
	)
	(zone
		(layer "In2.Cu")
		(hatch none 0.5)
		(connect_pads
			(clearance 0)
		)
		(min_thickness 0.25)
		(keepout
			(tracks not_allowed)
			(vias allowed)
			(pads allowed)
			(copperpour not_allowed)
			(footprints allowed)
		)
		(placement
			(enabled no)
			(sheetname "")
		)
		(fill
			(thermal_gap 0.5)
			(thermal_bridge_width 0.5)
			(island_removal_mode 0)
		)
		(polygon
			(pts
				(xy 279.886664 -276.975316) (xy 281.385264 -276.975316) (xy 281.385264 -277.495254) (xy 279.886664 -277.495254)
			)
		)
	)
	(zone
		(layer "In2.Cu")
		(hatch none 0.5)
		(connect_pads
			(clearance 0)
		)
		(min_thickness 0.25)
		(keepout
			(tracks not_allowed)
			(vias allowed)
			(pads allowed)
			(copperpour not_allowed)
			(footprints allowed)
		)
		(placement
			(enabled no)
			(sheetname "")
		)
		(fill
			(thermal_gap 0.5)
			(thermal_bridge_width 0.5)
			(island_removal_mode 0)
		)
		(polygon
			(pts
				(xy 430.80686 -221.725236) (xy 432.30546 -221.725236) (xy 432.30546 -222.245174) (xy 430.80686 -222.245174)
			)
		)
	)
	(zone
		(layer "In2.Cu")
		(hatch none 0.5)
		(connect_pads
			(clearance 0)
		)
		(min_thickness 0.25)
		(keepout
			(tracks not_allowed)
			(vias allowed)
			(pads allowed)
			(copperpour not_allowed)
			(footprints allowed)
		)
		(placement
			(enabled no)
			(sheetname "")
		)
		(fill
			(thermal_gap 0.5)
			(thermal_bridge_width 0.5)
			(island_removal_mode 0)
		)
		(polygon
			(pts
				(xy 283.986732 -250.625102) (xy 285.485332 -250.625102) (xy 285.485332 -251.14504) (xy 283.986732 -251.14504)
			)
		)
	)
	(zone
		(layer "In2.Cu")
		(hatch none 0.5)
		(connect_pads
			(clearance 0)
		)
		(min_thickness 0.25)
		(keepout
			(tracks allowed)
			(vias allowed)
			(pads allowed)
			(copperpour allowed)
			(footprints allowed)
		)
		(placement
			(enabled no)
			(sheetname "")
		)
		(fill
			(thermal_gap 0.5)
			(thermal_bridge_width 0.5)
			(island_removal_mode 0)
		)
		(polygon
			(pts
				(xy 75.15479 -335.891632) (xy 75.15479 -336.762852) (xy 74.90333 -336.762852) (xy 74.90333 -335.891632)
			)
		)
	)
	(zone
		(layer "In2.Cu")
		(hatch none 0.5)
		(connect_pads
			(clearance 0)
		)
		(min_thickness 0.25)
		(keepout
			(tracks not_allowed)
			(vias allowed)
			(pads allowed)
			(copperpour not_allowed)
			(footprints allowed)
		)
		(placement
			(enabled no)
			(sheetname "")
		)
		(fill
			(thermal_gap 0.5)
			(thermal_bridge_width 0.5)
			(island_removal_mode 0)
		)
		(polygon
			(pts
				(xy 389.165592 -23.50389) (xy 389.165592 -22.077172) (xy 389.826246 -22.077172) (xy 389.826246 -23.50389)
			)
		)
	)
	(zone
		(layer "In2.Cu")
		(hatch none 0.5)
		(connect_pads
			(clearance 0)
		)
		(min_thickness 0.25)
		(keepout
			(tracks not_allowed)
			(vias allowed)
			(pads allowed)
			(copperpour not_allowed)
			(footprints allowed)
		)
		(placement
			(enabled no)
			(sheetname "")
		)
		(fill
			(thermal_gap 0.5)
			(thermal_bridge_width 0.5)
			(island_removal_mode 0)
		)
		(polygon
			(pts
				(xy 415.718752 -284.625288) (xy 417.217352 -284.625288) (xy 417.217352 -285.145226) (xy 415.718752 -285.145226)
			)
		)
	)
	(zone
		(layer "In2.Cu")
		(hatch none 0.5)
		(connect_pads
			(clearance 0)
		)
		(min_thickness 0.25)
		(keepout
			(tracks allowed)
			(vias allowed)
			(pads allowed)
			(copperpour allowed)
			(footprints allowed)
		)
		(placement
			(enabled no)
			(sheetname "")
		)
		(fill
			(thermal_gap 0.5)
			(thermal_bridge_width 0.5)
			(island_removal_mode 0)
		)
		(polygon
			(pts
				(xy 366.758728 -175.174402) (xy 366.758728 -174.628048) (xy 367.311178 -174.628048) (xy 367.311178 -175.174402)
			)
		)
	)
	(zone
		(layer "In2.Cu")
		(hatch none 0.5)
		(connect_pads
			(clearance 0)
		)
		(min_thickness 0.25)
		(keepout
			(tracks not_allowed)
			(vias allowed)
			(pads allowed)
			(copperpour not_allowed)
			(footprints allowed)
		)
		(placement
			(enabled no)
			(sheetname "")
		)
		(fill
			(thermal_gap 0.5)
			(thermal_bridge_width 0.5)
			(island_removal_mode 0)
		)
		(polygon
			(pts
				(xy 190.410846 -209.825336) (xy 191.909446 -209.825336) (xy 191.909446 -210.345274) (xy 190.410846 -210.345274)
			)
		)
	)
	(zone
		(layer "In2.Cu")
		(hatch none 0.5)
		(connect_pads
			(clearance 0)
		)
		(min_thickness 0.25)
		(keepout
			(tracks allowed)
			(vias allowed)
			(pads allowed)
			(copperpour allowed)
			(footprints allowed)
		)
		(placement
			(enabled no)
			(sheetname "")
		)
		(fill
			(thermal_gap 0.5)
			(thermal_bridge_width 0.5)
			(island_removal_mode 0)
		)
		(polygon
			(pts
				(xy 95.083122 -180.180234) (xy 95.083122 -179.63388) (xy 95.635572 -179.63388) (xy 95.635572 -180.180234)
			)
		)
	)
	(zone
		(layer "In2.Cu")
		(hatch none 0.5)
		(connect_pads
			(clearance 0)
		)
		(min_thickness 0.25)
		(keepout
			(tracks not_allowed)
			(vias allowed)
			(pads allowed)
			(copperpour not_allowed)
			(footprints allowed)
		)
		(placement
			(enabled no)
			(sheetname "")
		)
		(fill
			(thermal_gap 0.5)
			(thermal_bridge_width 0.5)
			(island_removal_mode 0)
		)
		(polygon
			(pts
				(xy 441.7949 -251.47524) (xy 443.2935 -251.47524) (xy 443.2935 -251.995178) (xy 441.7949 -251.995178)
			)
		)
	)
	(zone
		(layer "In2.Cu")
		(hatch none 0.5)
		(connect_pads
			(clearance 0)
		)
		(min_thickness 0.25)
		(keepout
			(tracks not_allowed)
			(vias allowed)
			(pads allowed)
			(copperpour not_allowed)
			(footprints allowed)
		)
		(placement
			(enabled no)
			(sheetname "")
		)
		(fill
			(thermal_gap 0.5)
			(thermal_bridge_width 0.5)
			(island_removal_mode 0)
		)
		(polygon
			(pts
				(xy 445.894968 -221.725236) (xy 447.393568 -221.725236) (xy 447.393568 -222.245174) (xy 445.894968 -222.245174)
			)
		)
	)
	(zone
		(layer "In2.Cu")
		(hatch none 0.5)
		(connect_pads
			(clearance 0)
		)
		(min_thickness 0.25)
		(keepout
			(tracks not_allowed)
			(vias allowed)
			(pads allowed)
			(copperpour not_allowed)
			(footprints allowed)
		)
		(placement
			(enabled no)
			(sheetname "")
		)
		(fill
			(thermal_gap 0.5)
			(thermal_bridge_width 0.5)
			(island_removal_mode 0)
		)
		(polygon
			(pts
				(xy 419.162738 -317.775336) (xy 420.661338 -317.775336) (xy 420.661338 -318.295274) (xy 419.162738 -318.295274)
			)
		)
	)
	(zone
		(layer "In2.Cu")
		(hatch none 0.5)
		(connect_pads
			(clearance 0)
		)
		(min_thickness 0.25)
		(keepout
			(tracks not_allowed)
			(vias allowed)
			(pads allowed)
			(copperpour not_allowed)
			(footprints allowed)
		)
		(placement
			(enabled no)
			(sheetname "")
		)
		(fill
			(thermal_gap 0.5)
			(thermal_bridge_width 0.5)
			(island_removal_mode 0)
		)
		(polygon
			(pts
				(arc
					(start 325.334122 -388.647178)
					(mid 325.324886 -388.667102)
					(end 325.321676 -388.688834)
				)
				(arc
					(start 325.321676 -388.883398)
					(mid 325.343994 -388.93728)
					(end 325.397876 -388.959598)
				)
				(arc
					(start 326.083676 -388.959598)
					(mid 326.137558 -388.93728)
					(end 326.159876 -388.883398)
				)
				(arc
					(start 326.159876 -388.688834)
					(mid 326.156708 -388.66709)
					(end 326.14743 -388.647178)
				)
				(arc
					(start 325.954644 -388.351014)
					(mid 325.942422 -388.30933)
					(end 325.954898 -388.267702)
				)
				(arc
					(start 326.14743 -387.974078)
					(mid 326.156666 -387.954154)
					(end 326.159876 -387.932422)
				)
				(arc
					(start 326.159876 -387.737858)
					(mid 326.137558 -387.683976)
					(end 326.083676 -387.661658)
				)
				(arc
					(start 325.397876 -387.661658)
					(mid 325.343994 -387.683976)
					(end 325.321676 -387.737858)
				)
				(arc
					(start 325.321676 -387.933692)
					(mid 325.324844 -387.955436)
					(end 325.334122 -387.975348)
				)
				(arc
					(start 325.526654 -388.268972)
					(mid 325.539056 -388.310628)
					(end 325.526654 -388.352284)
				)
			)
		)
	)
	(zone
		(layer "In2.Cu")
		(hatch none 0.5)
		(connect_pads
			(clearance 0)
		)
		(min_thickness 0.25)
		(keepout
			(tracks not_allowed)
			(vias allowed)
			(pads allowed)
			(copperpour not_allowed)
			(footprints allowed)
		)
		(placement
			(enabled no)
			(sheetname "")
		)
		(fill
			(thermal_gap 0.5)
			(thermal_bridge_width 0.5)
			(island_removal_mode 0)
		)
		(polygon
			(pts
				(xy 279.886664 -210.67522) (xy 281.385264 -210.67522) (xy 281.385264 -211.195158) (xy 279.886664 -211.195158)
			)
		)
	)
	(zone
		(layer "In2.Cu")
		(hatch none 0.5)
		(connect_pads
			(clearance 0)
		)
		(min_thickness 0.25)
		(keepout
			(tracks not_allowed)
			(vias allowed)
			(pads allowed)
			(copperpour not_allowed)
			(footprints allowed)
		)
		(placement
			(enabled no)
			(sheetname "")
		)
		(fill
			(thermal_gap 0.5)
			(thermal_bridge_width 0.5)
			(island_removal_mode 0)
		)
		(polygon
			(pts
				(xy 423.262806 -237.875318) (xy 424.761406 -237.875318) (xy 424.761406 -238.395256) (xy 423.262806 -238.395256)
			)
		)
	)
	(zone
		(layer "In2.Cu")
		(hatch none 0.5)
		(connect_pads
			(clearance 0)
		)
		(min_thickness 0.25)
		(keepout
			(tracks not_allowed)
			(vias allowed)
			(pads allowed)
			(copperpour not_allowed)
			(footprints allowed)
		)
		(placement
			(enabled no)
			(sheetname "")
		)
		(fill
			(thermal_gap 0.5)
			(thermal_bridge_width 0.5)
			(island_removal_mode 0)
		)
		(polygon
			(pts
				(xy 197.954646 -220.025214) (xy 199.453246 -220.025214) (xy 199.453246 -220.545152) (xy 197.954646 -220.545152)
			)
		)
	)
	(zone
		(layer "In2.Cu")
		(hatch none 0.5)
		(connect_pads
			(clearance 0)
		)
		(min_thickness 0.25)
		(keepout
			(tracks not_allowed)
			(vias allowed)
			(pads allowed)
			(copperpour not_allowed)
			(footprints allowed)
		)
		(placement
			(enabled no)
			(sheetname "")
		)
		(fill
			(thermal_gap 0.5)
			(thermal_bridge_width 0.5)
			(island_removal_mode 0)
		)
		(polygon
			(pts
				(xy 299.07484 -208.125314) (xy 300.57344 -208.125314) (xy 300.57344 -208.645252) (xy 299.07484 -208.645252)
			)
		)
	)
	(zone
		(layer "In2.Cu")
		(hatch none 0.5)
		(connect_pads
			(clearance 0)
		)
		(min_thickness 0.25)
		(keepout
			(tracks not_allowed)
			(vias allowed)
			(pads allowed)
			(copperpour not_allowed)
			(footprints allowed)
		)
		(placement
			(enabled no)
			(sheetname "")
		)
		(fill
			(thermal_gap 0.5)
			(thermal_bridge_width 0.5)
			(island_removal_mode 0)
		)
		(polygon
			(pts
				(xy 47.034704 -218.325192) (xy 48.533304 -218.325192) (xy 48.533304 -218.84513) (xy 47.034704 -218.84513)
			)
		)
	)
	(zone
		(layer "In2.Cu")
		(hatch none 0.5)
		(connect_pads
			(clearance 0)
		)
		(min_thickness 0.25)
		(keepout
			(tracks not_allowed)
			(vias allowed)
			(pads allowed)
			(copperpour not_allowed)
			(footprints allowed)
		)
		(placement
			(enabled no)
			(sheetname "")
		)
		(fill
			(thermal_gap 0.5)
			(thermal_bridge_width 0.5)
			(island_removal_mode 0)
		)
		(polygon
			(pts
				(arc
					(start 51.97856 -17.966436)
					(mid 52.000878 -18.020318)
					(end 52.05476 -18.042636)
				)
				(arc
					(start 52.25034 -18.042636)
					(mid 52.272216 -18.039504)
					(end 52.29225 -18.03019)
				)
				(arc
					(start 52.585874 -17.837658)
					(mid 52.62753 -17.825256)
					(end 52.669186 -17.837658)
				)
				(arc
					(start 52.96408 -18.03019)
					(mid 52.984004 -18.039426)
					(end 53.005736 -18.042636)
				)
				(arc
					(start 53.2003 -18.042636)
					(mid 53.254182 -18.020318)
					(end 53.2765 -17.966436)
				)
				(arc
					(start 53.2765 -17.280636)
					(mid 53.254182 -17.226754)
					(end 53.2003 -17.204436)
				)
				(arc
					(start 53.005736 -17.204436)
					(mid 52.983992 -17.207604)
					(end 52.96408 -17.216882)
				)
				(arc
					(start 52.667916 -17.409668)
					(mid 52.626232 -17.42189)
					(end 52.584604 -17.409414)
				)
				(arc
					(start 52.29098 -17.216882)
					(mid 52.271056 -17.207646)
					(end 52.249324 -17.204436)
				)
				(arc
					(start 52.05476 -17.204436)
					(mid 52.000878 -17.226754)
					(end 51.97856 -17.280636)
				)
			)
		)
	)
	(zone
		(layer "In2.Cu")
		(hatch none 0.5)
		(connect_pads
			(clearance 0)
		)
		(min_thickness 0.25)
		(keepout
			(tracks not_allowed)
			(vias allowed)
			(pads allowed)
			(copperpour not_allowed)
			(footprints allowed)
		)
		(placement
			(enabled no)
			(sheetname "")
		)
		(fill
			(thermal_gap 0.5)
			(thermal_bridge_width 0.5)
			(island_removal_mode 0)
		)
		(polygon
			(pts
				(xy 36.046664 -204.72527) (xy 37.545264 -204.72527) (xy 37.545264 -205.245208) (xy 36.046664 -205.245208)
			)
		)
	)
	(zone
		(layer "In2.Cu")
		(hatch none 0.5)
		(connect_pads
			(clearance 0)
		)
		(min_thickness 0.25)
		(keepout
			(tracks not_allowed)
			(vias allowed)
			(pads allowed)
			(copperpour not_allowed)
			(footprints allowed)
		)
		(placement
			(enabled no)
			(sheetname "")
		)
		(fill
			(thermal_gap 0.5)
			(thermal_bridge_width 0.5)
			(island_removal_mode 0)
		)
		(polygon
			(pts
				(xy 411.618684 -197.925182) (xy 413.117284 -197.925182) (xy 413.117284 -198.44512) (xy 411.618684 -198.44512)
			)
		)
	)
	(zone
		(layer "In2.Cu")
		(hatch none 0.5)
		(connect_pads
			(clearance 0)
		)
		(min_thickness 0.25)
		(keepout
			(tracks not_allowed)
			(vias allowed)
			(pads allowed)
			(copperpour not_allowed)
			(footprints allowed)
		)
		(placement
			(enabled no)
			(sheetname "")
		)
		(fill
			(thermal_gap 0.5)
			(thermal_bridge_width 0.5)
			(island_removal_mode 0)
		)
		(polygon
			(pts
				(xy 438.350914 -226.825302) (xy 439.849514 -226.825302) (xy 439.849514 -227.34524) (xy 438.350914 -227.34524)
			)
		)
	)
	(zone
		(layer "In2.Cu")
		(hatch none 0.5)
		(connect_pads
			(clearance 0)
		)
		(min_thickness 0.25)
		(keepout
			(tracks not_allowed)
			(vias allowed)
			(pads allowed)
			(copperpour not_allowed)
			(footprints allowed)
		)
		(placement
			(enabled no)
			(sheetname "")
		)
		(fill
			(thermal_gap 0.5)
			(thermal_bridge_width 0.5)
			(island_removal_mode 0)
		)
		(polygon
			(pts
				(xy 419.162738 -302.475138) (xy 420.661338 -302.475138) (xy 420.661338 -302.995076) (xy 419.162738 -302.995076)
			)
		)
	)
	(zone
		(layer "In2.Cu")
		(hatch none 0.5)
		(connect_pads
			(clearance 0)
		)
		(min_thickness 0.25)
		(keepout
			(tracks not_allowed)
			(vias allowed)
			(pads allowed)
			(copperpour not_allowed)
			(footprints allowed)
		)
		(placement
			(enabled no)
			(sheetname "")
		)
		(fill
			(thermal_gap 0.5)
			(thermal_bridge_width 0.5)
			(island_removal_mode 0)
		)
		(polygon
			(pts
				(xy 167.778684 -316.925198) (xy 169.277284 -316.925198) (xy 169.277284 -317.445136) (xy 167.778684 -317.445136)
			)
		)
	)
	(zone
		(layer "In2.Cu")
		(hatch none 0.5)
		(connect_pads
			(clearance 0)
		)
		(min_thickness 0.25)
		(keepout
			(tracks not_allowed)
			(vias allowed)
			(pads allowed)
			(copperpour not_allowed)
			(footprints allowed)
		)
		(placement
			(enabled no)
			(sheetname "")
		)
		(fill
			(thermal_gap 0.5)
			(thermal_bridge_width 0.5)
			(island_removal_mode 0)
		)
		(polygon
			(pts
				(xy 449.3387 -244.675152) (xy 450.8373 -244.675152) (xy 450.8373 -245.19509) (xy 449.3387 -245.19509)
			)
		)
	)
	(zone
		(layer "In2.Cu")
		(hatch none 0.5)
		(connect_pads
			(clearance 0)
		)
		(min_thickness 0.25)
		(keepout
			(tracks not_allowed)
			(vias allowed)
			(pads allowed)
			(copperpour not_allowed)
			(footprints allowed)
		)
		(placement
			(enabled no)
			(sheetname "")
		)
		(fill
			(thermal_gap 0.5)
			(thermal_bridge_width 0.5)
			(island_removal_mode 0)
		)
		(polygon
			(pts
				(xy 175.322738 -305.875182) (xy 176.821338 -305.875182) (xy 176.821338 -306.39512) (xy 175.322738 -306.39512)
			)
		)
	)
	(zone
		(layer "In2.Cu")
		(hatch none 0.5)
		(connect_pads
			(clearance 0)
		)
		(min_thickness 0.25)
		(keepout
			(tracks not_allowed)
			(vias allowed)
			(pads allowed)
			(copperpour not_allowed)
			(footprints allowed)
		)
		(placement
			(enabled no)
			(sheetname "")
		)
		(fill
			(thermal_gap 0.5)
			(thermal_bridge_width 0.5)
			(island_removal_mode 0)
		)
		(polygon
			(pts
				(xy 279.886664 -294.825166) (xy 281.385264 -294.825166) (xy 281.385264 -295.345104) (xy 279.886664 -295.345104)
			)
		)
	)
	(zone
		(layer "In2.Cu")
		(hatch none 0.5)
		(connect_pads
			(clearance 0)
		)
		(min_thickness 0.25)
		(keepout
			(tracks not_allowed)
			(vias allowed)
			(pads allowed)
			(copperpour not_allowed)
			(footprints allowed)
		)
		(placement
			(enabled no)
			(sheetname "")
		)
		(fill
			(thermal_gap 0.5)
			(thermal_bridge_width 0.5)
			(island_removal_mode 0)
		)
		(polygon
			(pts
				(xy 287.430718 -280.375106) (xy 288.929318 -280.375106) (xy 288.929318 -280.895044) (xy 287.430718 -280.895044)
			)
		)
	)
	(zone
		(layer "In2.Cu")
		(hatch none 0.5)
		(connect_pads
			(clearance 0)
		)
		(min_thickness 0.25)
		(keepout
			(tracks not_allowed)
			(vias allowed)
			(pads allowed)
			(copperpour not_allowed)
			(footprints allowed)
		)
		(placement
			(enabled no)
			(sheetname "")
		)
		(fill
			(thermal_gap 0.5)
			(thermal_bridge_width 0.5)
			(island_removal_mode 0)
		)
		(polygon
			(pts
				(xy 47.034704 -268.475206) (xy 48.533304 -268.475206) (xy 48.533304 -268.995144) (xy 47.034704 -268.995144)
			)
		)
	)
	(zone
		(layer "In2.Cu")
		(hatch none 0.5)
		(connect_pads
			(clearance 0)
		)
		(min_thickness 0.25)
		(keepout
			(tracks not_allowed)
			(vias allowed)
			(pads allowed)
			(copperpour not_allowed)
			(footprints allowed)
		)
		(placement
			(enabled no)
			(sheetname "")
		)
		(fill
			(thermal_gap 0.5)
			(thermal_bridge_width 0.5)
			(island_removal_mode 0)
		)
		(polygon
			(pts
				(xy 186.310778 -235.325158) (xy 187.809378 -235.325158) (xy 187.809378 -235.845096) (xy 186.310778 -235.845096)
			)
		)
	)
	(zone
		(layer "In2.Cu")
		(hatch none 0.5)
		(connect_pads
			(clearance 0)
		)
		(min_thickness 0.25)
		(keepout
			(tracks not_allowed)
			(vias allowed)
			(pads allowed)
			(copperpour not_allowed)
			(footprints allowed)
		)
		(placement
			(enabled no)
			(sheetname "")
		)
		(fill
			(thermal_gap 0.5)
			(thermal_bridge_width 0.5)
			(island_removal_mode 0)
		)
		(polygon
			(pts
				(xy 47.034704 -276.975316) (xy 48.533304 -276.975316) (xy 48.533304 -277.495254) (xy 47.034704 -277.495254)
			)
		)
	)
	(zone
		(layer "In2.Cu")
		(hatch none 0.5)
		(connect_pads
			(clearance 0)
		)
		(min_thickness 0.25)
		(keepout
			(tracks not_allowed)
			(vias allowed)
			(pads allowed)
			(copperpour not_allowed)
			(footprints allowed)
		)
		(placement
			(enabled no)
			(sheetname "")
		)
		(fill
			(thermal_gap 0.5)
			(thermal_bridge_width 0.5)
			(island_removal_mode 0)
		)
		(polygon
			(pts
				(xy 306.618894 -307.575204) (xy 308.117494 -307.575204) (xy 308.117494 -308.095142) (xy 306.618894 -308.095142)
			)
		)
	)
	(zone
		(layer "In2.Cu")
		(hatch none 0.5)
		(connect_pads
			(clearance 0)
		)
		(min_thickness 0.25)
		(keepout
			(tracks not_allowed)
			(vias allowed)
			(pads allowed)
			(copperpour not_allowed)
			(footprints allowed)
		)
		(placement
			(enabled no)
			(sheetname "")
		)
		(fill
			(thermal_gap 0.5)
			(thermal_bridge_width 0.5)
			(island_removal_mode 0)
		)
		(polygon
			(pts
				(xy 411.618684 -216.62517) (xy 413.117284 -216.62517) (xy 413.117284 -217.145108) (xy 411.618684 -217.145108)
			)
		)
	)
	(zone
		(layer "In2.Cu")
		(hatch none 0.5)
		(connect_pads
			(clearance 0)
		)
		(min_thickness 0.25)
		(keepout
			(tracks not_allowed)
			(vias allowed)
			(pads allowed)
			(copperpour not_allowed)
			(footprints allowed)
		)
		(placement
			(enabled no)
			(sheetname "")
		)
		(fill
			(thermal_gap 0.5)
			(thermal_bridge_width 0.5)
			(island_removal_mode 0)
		)
		(polygon
			(pts
				(xy 279.886664 -278.675338) (xy 281.385264 -278.675338) (xy 281.385264 -279.195276) (xy 279.886664 -279.195276)
			)
		)
	)
	(zone
		(layer "In2.Cu")
		(hatch none 0.5)
		(connect_pads
			(clearance 0)
		)
		(min_thickness 0.25)
		(keepout
			(tracks not_allowed)
			(vias allowed)
			(pads allowed)
			(copperpour not_allowed)
			(footprints allowed)
		)
		(placement
			(enabled no)
			(sheetname "")
		)
		(fill
			(thermal_gap 0.5)
			(thermal_bridge_width 0.5)
			(island_removal_mode 0)
		)
		(polygon
			(pts
				(xy 193.854578 -220.875098) (xy 195.353178 -220.875098) (xy 195.353178 -221.395036) (xy 193.854578 -221.395036)
			)
		)
	)
	(zone
		(layer "In2.Cu")
		(hatch none 0.5)
		(connect_pads
			(clearance 0)
		)
		(min_thickness 0.25)
		(keepout
			(tracks not_allowed)
			(vias allowed)
			(pads allowed)
			(copperpour not_allowed)
			(footprints allowed)
		)
		(placement
			(enabled no)
			(sheetname "")
		)
		(fill
			(thermal_gap 0.5)
			(thermal_bridge_width 0.5)
			(island_removal_mode 0)
		)
		(polygon
			(pts
				(xy 190.410846 -221.725236) (xy 191.909446 -221.725236) (xy 191.909446 -222.245174) (xy 190.410846 -222.245174)
			)
		)
	)
	(zone
		(layer "In2.Cu")
		(hatch none 0.5)
		(connect_pads
			(clearance 0)
		)
		(min_thickness 0.25)
		(keepout
			(tracks not_allowed)
			(vias allowed)
			(pads allowed)
			(copperpour not_allowed)
			(footprints allowed)
		)
		(placement
			(enabled no)
			(sheetname "")
		)
		(fill
			(thermal_gap 0.5)
			(thermal_bridge_width 0.5)
			(island_removal_mode 0)
		)
		(polygon
			(pts
				(xy 51.134772 -212.375242) (xy 52.633372 -212.375242) (xy 52.633372 -212.89518) (xy 51.134772 -212.89518)
			)
		)
	)
	(zone
		(layer "In2.Cu")
		(hatch none 0.5)
		(connect_pads
			(clearance 0)
		)
		(min_thickness 0.25)
		(keepout
			(tracks not_allowed)
			(vias allowed)
			(pads allowed)
			(copperpour not_allowed)
			(footprints allowed)
		)
		(placement
			(enabled no)
			(sheetname "")
		)
		(fill
			(thermal_gap 0.5)
			(thermal_bridge_width 0.5)
			(island_removal_mode 0)
		)
		(polygon
			(pts
				(xy 426.706792 -304.17516) (xy 428.205392 -304.17516) (xy 428.205392 -304.695098) (xy 426.706792 -304.695098)
			)
		)
	)
	(zone
		(layer "In2.Cu")
		(hatch none 0.5)
		(connect_pads
			(clearance 0)
		)
		(min_thickness 0.25)
		(keepout
			(tracks not_allowed)
			(vias allowed)
			(pads allowed)
			(copperpour not_allowed)
			(footprints allowed)
		)
		(placement
			(enabled no)
			(sheetname "")
		)
		(fill
			(thermal_gap 0.5)
			(thermal_bridge_width 0.5)
			(island_removal_mode 0)
		)
		(polygon
			(pts
				(xy 20.95881 -208.125314) (xy 22.45741 -208.125314) (xy 22.45741 -208.645252) (xy 20.95881 -208.645252)
			)
		)
	)
	(zone
		(layer "In2.Cu")
		(hatch none 0.5)
		(connect_pads
			(clearance 0)
		)
		(min_thickness 0.25)
		(keepout
			(tracks not_allowed)
			(vias allowed)
			(pads allowed)
			(copperpour not_allowed)
			(footprints allowed)
		)
		(placement
			(enabled no)
			(sheetname "")
		)
		(fill
			(thermal_gap 0.5)
			(thermal_bridge_width 0.5)
			(island_removal_mode 0)
		)
		(polygon
			(pts
				(xy 175.322738 -220.025214) (xy 176.821338 -220.025214) (xy 176.821338 -220.545152) (xy 175.322738 -220.545152)
			)
		)
	)
	(zone
		(layer "In2.Cu")
		(hatch none 0.5)
		(connect_pads
			(clearance 0)
		)
		(min_thickness 0.25)
		(keepout
			(tracks not_allowed)
			(vias allowed)
			(pads allowed)
			(copperpour not_allowed)
			(footprints allowed)
		)
		(placement
			(enabled no)
			(sheetname "")
		)
		(fill
			(thermal_gap 0.5)
			(thermal_bridge_width 0.5)
			(island_removal_mode 0)
		)
		(polygon
			(pts
				(xy 294.974772 -203.875132) (xy 296.473372 -203.875132) (xy 296.473372 -204.39507) (xy 294.974772 -204.39507)
			)
		)
	)
	(zone
		(layer "In2.Cu")
		(hatch none 0.5)
		(connect_pads
			(clearance 0)
		)
		(min_thickness 0.25)
		(keepout
			(tracks not_allowed)
			(vias allowed)
			(pads allowed)
			(copperpour not_allowed)
			(footprints allowed)
		)
		(placement
			(enabled no)
			(sheetname "")
		)
		(fill
			(thermal_gap 0.5)
			(thermal_bridge_width 0.5)
			(island_removal_mode 0)
		)
		(polygon
			(pts
				(xy 276.442932 -277.8252) (xy 277.941532 -277.8252) (xy 277.941532 -278.345138) (xy 276.442932 -278.345138)
			)
		)
	)
	(zone
		(layer "In2.Cu")
		(hatch none 0.5)
		(connect_pads
			(clearance 0)
		)
		(min_thickness 0.25)
		(keepout
			(tracks not_allowed)
			(vias allowed)
			(pads allowed)
			(copperpour not_allowed)
			(footprints allowed)
		)
		(placement
			(enabled no)
			(sheetname "")
		)
		(fill
			(thermal_gap 0.5)
			(thermal_bridge_width 0.5)
			(island_removal_mode 0)
		)
		(polygon
			(pts
				(xy 163.678616 -201.325226) (xy 165.177216 -201.325226) (xy 165.177216 -201.845164) (xy 163.678616 -201.845164)
			)
		)
	)
	(zone
		(layer "In2.Cu")
		(hatch none 0.5)
		(connect_pads
			(clearance 0)
		)
		(min_thickness 0.25)
		(keepout
			(tracks not_allowed)
			(vias allowed)
			(pads allowed)
			(copperpour not_allowed)
			(footprints allowed)
		)
		(placement
			(enabled no)
			(sheetname "")
		)
		(fill
			(thermal_gap 0.5)
			(thermal_bridge_width 0.5)
			(island_removal_mode 0)
		)
		(polygon
			(pts
				(xy 58.678826 -267.625322) (xy 60.177426 -267.625322) (xy 60.177426 -268.14526) (xy 58.678826 -268.14526)
			)
		)
	)
	(zone
		(layer "In2.Cu")
		(hatch none 0.5)
		(connect_pads
			(clearance 0)
		)
		(min_thickness 0.25)
		(keepout
			(tracks not_allowed)
			(vias allowed)
			(pads allowed)
			(copperpour not_allowed)
			(footprints allowed)
		)
		(placement
			(enabled no)
			(sheetname "")
		)
		(fill
			(thermal_gap 0.5)
			(thermal_bridge_width 0.5)
			(island_removal_mode 0)
		)
		(polygon
			(pts
				(xy 51.134772 -262.525256) (xy 52.633372 -262.525256) (xy 52.633372 -263.045194) (xy 51.134772 -263.045194)
			)
		)
	)
	(zone
		(layer "In2.Cu")
		(hatch none 0.5)
		(connect_pads
			(clearance 0)
		)
		(min_thickness 0.25)
		(keepout
			(tracks not_allowed)
			(vias allowed)
			(pads allowed)
			(copperpour not_allowed)
			(footprints allowed)
		)
		(placement
			(enabled no)
			(sheetname "")
		)
		(fill
			(thermal_gap 0.5)
			(thermal_bridge_width 0.5)
			(island_removal_mode 0)
		)
		(polygon
			(pts
				(arc
					(start 55.372254 -7.672324)
					(mid 55.394572 -7.618442)
					(end 55.448454 -7.596124)
				)
				(arc
					(start 56.485028 -7.596124)
					(mid 56.53891 -7.618442)
					(end 56.561228 -7.672324)
				)
				(arc
					(start 56.561228 -9.071864)
					(mid 56.53891 -9.125746)
					(end 56.485028 -9.148064)
				)
				(arc
					(start 55.448454 -9.148064)
					(mid 55.394572 -9.125746)
					(end 55.372254 -9.071864)
				)
			)
		)
	)
	(zone
		(layer "In2.Cu")
		(hatch none 0.5)
		(connect_pads
			(clearance 0)
		)
		(min_thickness 0.25)
		(keepout
			(tracks not_allowed)
			(vias allowed)
			(pads allowed)
			(copperpour not_allowed)
			(footprints allowed)
		)
		(placement
			(enabled no)
			(sheetname "")
		)
		(fill
			(thermal_gap 0.5)
			(thermal_bridge_width 0.5)
			(island_removal_mode 0)
		)
		(polygon
			(pts
				(xy 291.530786 -315.225176) (xy 293.029386 -315.225176) (xy 293.029386 -315.745114) (xy 291.530786 -315.745114)
			)
		)
	)
	(zone
		(layer "In2.Cu")
		(hatch none 0.5)
		(connect_pads
			(clearance 0)
		)
		(min_thickness 0.25)
		(keepout
			(tracks not_allowed)
			(vias allowed)
			(pads allowed)
			(copperpour not_allowed)
			(footprints allowed)
		)
		(placement
			(enabled no)
			(sheetname "")
		)
		(fill
			(thermal_gap 0.5)
			(thermal_bridge_width 0.5)
			(island_removal_mode 0)
		)
		(polygon
			(pts
				(xy 434.250846 -241.275108) (xy 435.749446 -241.275108) (xy 435.749446 -241.795046) (xy 434.250846 -241.795046)
			)
		)
	)
	(zone
		(layer "In2.Cu")
		(hatch none 0.5)
		(connect_pads
			(clearance 0)
		)
		(min_thickness 0.25)
		(keepout
			(tracks not_allowed)
			(vias allowed)
			(pads allowed)
			(copperpour not_allowed)
			(footprints allowed)
		)
		(placement
			(enabled no)
			(sheetname "")
		)
		(fill
			(thermal_gap 0.5)
			(thermal_bridge_width 0.5)
			(island_removal_mode 0)
		)
		(polygon
			(pts
				(xy 193.854578 -202.17511) (xy 195.353178 -202.17511) (xy 195.353178 -202.695048) (xy 193.854578 -202.695048)
			)
		)
	)
	(zone
		(layer "In2.Cu")
		(hatch none 0.5)
		(connect_pads
			(clearance 0)
		)
		(min_thickness 0.25)
		(keepout
			(tracks not_allowed)
			(vias allowed)
			(pads allowed)
			(copperpour not_allowed)
			(footprints allowed)
		)
		(placement
			(enabled no)
			(sheetname "")
		)
		(fill
			(thermal_gap 0.5)
			(thermal_bridge_width 0.5)
			(island_removal_mode 0)
		)
		(polygon
			(pts
				(xy 453.438768 -279.525222) (xy 454.937368 -279.525222) (xy 454.937368 -280.04516) (xy 453.438768 -280.04516)
			)
		)
	)
	(zone
		(layer "In2.Cu")
		(hatch none 0.5)
		(connect_pads
			(clearance 0)
		)
		(min_thickness 0.25)
		(keepout
			(tracks not_allowed)
			(vias allowed)
			(pads allowed)
			(copperpour not_allowed)
			(footprints allowed)
		)
		(placement
			(enabled no)
			(sheetname "")
		)
		(fill
			(thermal_gap 0.5)
			(thermal_bridge_width 0.5)
			(island_removal_mode 0)
		)
		(polygon
			(pts
				(xy 163.678616 -317.775336) (xy 165.177216 -317.775336) (xy 165.177216 -318.295274) (xy 163.678616 -318.295274)
			)
		)
	)
	(zone
		(layer "In2.Cu")
		(hatch none 0.5)
		(connect_pads
			(clearance 0)
		)
		(min_thickness 0.25)
		(keepout
			(tracks not_allowed)
			(vias allowed)
			(pads allowed)
			(copperpour not_allowed)
			(footprints allowed)
		)
		(placement
			(enabled no)
			(sheetname "")
		)
		(fill
			(thermal_gap 0.5)
			(thermal_bridge_width 0.5)
			(island_removal_mode 0)
		)
		(polygon
			(pts
				(xy 58.678826 -250.625102) (xy 60.177426 -250.625102) (xy 60.177426 -251.14504) (xy 58.678826 -251.14504)
			)
		)
	)
	(zone
		(layer "In2.Cu")
		(hatch none 0.5)
		(connect_pads
			(clearance 0)
		)
		(min_thickness 0.25)
		(keepout
			(tracks not_allowed)
			(vias allowed)
			(pads allowed)
			(copperpour not_allowed)
			(footprints allowed)
		)
		(placement
			(enabled no)
			(sheetname "")
		)
		(fill
			(thermal_gap 0.5)
			(thermal_bridge_width 0.5)
			(island_removal_mode 0)
		)
		(polygon
			(pts
				(xy 31.946596 -208.975198) (xy 33.445196 -208.975198) (xy 33.445196 -209.495136) (xy 31.946596 -209.495136)
			)
		)
	)
	(zone
		(layer "In2.Cu")
		(hatch none 0.5)
		(connect_pads
			(clearance 0)
		)
		(min_thickness 0.25)
		(keepout
			(tracks not_allowed)
			(vias allowed)
			(pads allowed)
			(copperpour not_allowed)
			(footprints allowed)
		)
		(placement
			(enabled no)
			(sheetname "")
		)
		(fill
			(thermal_gap 0.5)
			(thermal_bridge_width 0.5)
			(island_removal_mode 0)
		)
		(polygon
			(pts
				(xy 175.322738 -299.925232) (xy 176.821338 -299.925232) (xy 176.821338 -300.44517) (xy 175.322738 -300.44517)
			)
		)
	)
	(zone
		(layer "In2.Cu")
		(hatch none 0.5)
		(connect_pads
			(clearance 0)
		)
		(min_thickness 0.25)
		(keepout
			(tracks not_allowed)
			(vias allowed)
			(pads allowed)
			(copperpour not_allowed)
			(footprints allowed)
		)
		(placement
			(enabled no)
			(sheetname "")
		)
		(fill
			(thermal_gap 0.5)
			(thermal_bridge_width 0.5)
			(island_removal_mode 0)
		)
		(polygon
			(pts
				(xy 58.678826 -279.525222) (xy 60.177426 -279.525222) (xy 60.177426 -280.04516) (xy 58.678826 -280.04516)
			)
		)
	)
	(zone
		(layer "In2.Cu")
		(hatch none 0.5)
		(connect_pads
			(clearance 0)
		)
		(min_thickness 0.25)
		(keepout
			(tracks not_allowed)
			(vias allowed)
			(pads allowed)
			(copperpour not_allowed)
			(footprints allowed)
		)
		(placement
			(enabled no)
			(sheetname "")
		)
		(fill
			(thermal_gap 0.5)
			(thermal_bridge_width 0.5)
			(island_removal_mode 0)
		)
		(polygon
			(pts
				(xy 47.034704 -227.675186) (xy 48.533304 -227.675186) (xy 48.533304 -228.195124) (xy 47.034704 -228.195124)
			)
		)
	)
	(zone
		(layer "In2.Cu")
		(hatch none 0.5)
		(connect_pads
			(clearance 0)
		)
		(min_thickness 0.25)
		(keepout
			(tracks not_allowed)
			(vias allowed)
			(pads allowed)
			(copperpour not_allowed)
			(footprints allowed)
		)
		(placement
			(enabled no)
			(sheetname "")
		)
		(fill
			(thermal_gap 0.5)
			(thermal_bridge_width 0.5)
			(island_removal_mode 0)
		)
		(polygon
			(pts
				(xy 276.442932 -243.825268) (xy 277.941532 -243.825268) (xy 277.941532 -244.345206) (xy 276.442932 -244.345206)
			)
		)
	)
	(zone
		(layer "In2.Cu")
		(hatch none 0.5)
		(connect_pads
			(clearance 0)
		)
		(min_thickness 0.25)
		(keepout
			(tracks not_allowed)
			(vias allowed)
			(pads allowed)
			(copperpour not_allowed)
			(footprints allowed)
		)
		(placement
			(enabled no)
			(sheetname "")
		)
		(fill
			(thermal_gap 0.5)
			(thermal_bridge_width 0.5)
			(island_removal_mode 0)
		)
		(polygon
			(pts
				(xy 299.07484 -248.925334) (xy 300.57344 -248.925334) (xy 300.57344 -249.445272) (xy 299.07484 -249.445272)
			)
		)
	)
	(zone
		(layer "In2.Cu")
		(hatch none 0.5)
		(connect_pads
			(clearance 0)
		)
		(min_thickness 0.25)
		(keepout
			(tracks not_allowed)
			(vias allowed)
			(pads allowed)
			(copperpour not_allowed)
			(footprints allowed)
		)
		(placement
			(enabled no)
			(sheetname "")
		)
		(fill
			(thermal_gap 0.5)
			(thermal_bridge_width 0.5)
			(island_removal_mode 0)
		)
		(polygon
			(pts
				(xy 190.410846 -219.17533) (xy 191.909446 -219.17533) (xy 191.909446 -219.695268) (xy 190.410846 -219.695268)
			)
		)
	)
	(zone
		(layer "In2.Cu")
		(hatch none 0.5)
		(connect_pads
			(clearance 0)
		)
		(min_thickness 0.25)
		(keepout
			(tracks not_allowed)
			(vias allowed)
			(pads allowed)
			(copperpour not_allowed)
			(footprints allowed)
		)
		(placement
			(enabled no)
			(sheetname "")
		)
		(fill
			(thermal_gap 0.5)
			(thermal_bridge_width 0.5)
			(island_removal_mode 0)
		)
		(polygon
			(pts
				(xy 276.442932 -210.67522) (xy 277.941532 -210.67522) (xy 277.941532 -211.195158) (xy 276.442932 -211.195158)
			)
		)
	)
	(zone
		(layer "In2.Cu")
		(hatch none 0.5)
		(connect_pads
			(clearance 0)
		)
		(min_thickness 0.25)
		(keepout
			(tracks not_allowed)
			(vias allowed)
			(pads allowed)
			(copperpour not_allowed)
			(footprints allowed)
		)
		(placement
			(enabled no)
			(sheetname "")
		)
		(fill
			(thermal_gap 0.5)
			(thermal_bridge_width 0.5)
			(island_removal_mode 0)
		)
		(polygon
			(pts
				(xy 299.07484 -252.325124) (xy 300.57344 -252.325124) (xy 300.57344 -252.845062) (xy 299.07484 -252.845062)
			)
		)
	)
	(zone
		(layer "In2.Cu")
		(hatch none 0.5)
		(connect_pads
			(clearance 0)
		)
		(min_thickness 0.25)
		(keepout
			(tracks not_allowed)
			(vias allowed)
			(pads allowed)
			(copperpour not_allowed)
			(footprints allowed)
		)
		(placement
			(enabled no)
			(sheetname "")
		)
		(fill
			(thermal_gap 0.5)
			(thermal_bridge_width 0.5)
			(island_removal_mode 0)
		)
		(polygon
			(pts
				(xy 306.618894 -212.375242) (xy 308.117494 -212.375242) (xy 308.117494 -212.89518) (xy 306.618894 -212.89518)
			)
		)
	)
	(zone
		(layer "In2.Cu")
		(hatch none 0.5)
		(connect_pads
			(clearance 0)
		)
		(min_thickness 0.25)
		(keepout
			(tracks not_allowed)
			(vias allowed)
			(pads allowed)
			(copperpour not_allowed)
			(footprints allowed)
		)
		(placement
			(enabled no)
			(sheetname "")
		)
		(fill
			(thermal_gap 0.5)
			(thermal_bridge_width 0.5)
			(island_removal_mode 0)
		)
		(polygon
			(pts
				(xy 186.310778 -278.675338) (xy 187.809378 -278.675338) (xy 187.809378 -279.195276) (xy 186.310778 -279.195276)
			)
		)
	)
	(zone
		(layer "In2.Cu")
		(hatch none 0.5)
		(connect_pads
			(clearance 0)
		)
		(min_thickness 0.25)
		(keepout
			(tracks not_allowed)
			(vias allowed)
			(pads allowed)
			(copperpour not_allowed)
			(footprints allowed)
		)
		(placement
			(enabled no)
			(sheetname "")
		)
		(fill
			(thermal_gap 0.5)
			(thermal_bridge_width 0.5)
			(island_removal_mode 0)
		)
		(polygon
			(pts
				(xy 411.618684 -310.12511) (xy 413.117284 -310.12511) (xy 413.117284 -310.645048) (xy 411.618684 -310.645048)
			)
		)
	)
	(zone
		(layer "In2.Cu")
		(hatch none 0.5)
		(connect_pads
			(clearance 0)
		)
		(min_thickness 0.25)
		(keepout
			(tracks not_allowed)
			(vias allowed)
			(pads allowed)
			(copperpour not_allowed)
			(footprints allowed)
		)
		(placement
			(enabled no)
			(sheetname "")
		)
		(fill
			(thermal_gap 0.5)
			(thermal_bridge_width 0.5)
			(island_removal_mode 0)
		)
		(polygon
			(pts
				(xy 24.402542 -316.075314) (xy 25.901142 -316.075314) (xy 25.901142 -316.595252) (xy 24.402542 -316.595252)
			)
		)
	)
	(zone
		(layer "In2.Cu")
		(hatch none 0.5)
		(connect_pads
			(clearance 0)
		)
		(min_thickness 0.25)
		(keepout
			(tracks not_allowed)
			(vias allowed)
			(pads allowed)
			(copperpour not_allowed)
			(footprints allowed)
		)
		(placement
			(enabled no)
			(sheetname "")
		)
		(fill
			(thermal_gap 0.5)
			(thermal_bridge_width 0.5)
			(island_removal_mode 0)
		)
		(polygon
			(pts
				(xy 423.262806 -229.375208) (xy 424.761406 -229.375208) (xy 424.761406 -229.895146) (xy 423.262806 -229.895146)
			)
		)
	)
	(zone
		(layer "In2.Cu")
		(hatch none 0.5)
		(connect_pads
			(clearance 0)
		)
		(min_thickness 0.25)
		(keepout
			(tracks not_allowed)
			(vias allowed)
			(pads allowed)
			(copperpour not_allowed)
			(footprints allowed)
		)
		(placement
			(enabled no)
			(sheetname "")
		)
		(fill
			(thermal_gap 0.5)
			(thermal_bridge_width 0.5)
			(island_removal_mode 0)
		)
		(polygon
			(pts
				(xy 272.342864 -248.075196) (xy 273.841464 -248.075196) (xy 273.841464 -248.595134) (xy 272.342864 -248.595134)
			)
		)
	)
	(zone
		(layer "In2.Cu")
		(hatch none 0.5)
		(connect_pads
			(clearance 0)
		)
		(min_thickness 0.25)
		(keepout
			(tracks not_allowed)
			(vias allowed)
			(pads allowed)
			(copperpour not_allowed)
			(footprints allowed)
		)
		(placement
			(enabled no)
			(sheetname "")
		)
		(fill
			(thermal_gap 0.5)
			(thermal_bridge_width 0.5)
			(island_removal_mode 0)
		)
		(polygon
			(pts
				(xy 306.618894 -265.9253) (xy 308.117494 -265.9253) (xy 308.117494 -266.445238) (xy 306.618894 -266.445238)
			)
		)
	)
	(zone
		(layer "In2.Cu")
		(hatch none 0.5)
		(connect_pads
			(clearance 0)
		)
		(min_thickness 0.25)
		(keepout
			(tracks not_allowed)
			(vias allowed)
			(pads allowed)
			(copperpour not_allowed)
			(footprints allowed)
		)
		(placement
			(enabled no)
			(sheetname "")
		)
		(fill
			(thermal_gap 0.5)
			(thermal_bridge_width 0.5)
			(island_removal_mode 0)
		)
		(polygon
			(pts
				(xy 47.034704 -306.72532) (xy 48.533304 -306.72532) (xy 48.533304 -307.245258) (xy 47.034704 -307.245258)
			)
		)
	)
	(zone
		(layer "In2.Cu")
		(hatch none 0.5)
		(connect_pads
			(clearance 0)
		)
		(min_thickness 0.25)
		(keepout
			(tracks not_allowed)
			(vias allowed)
			(pads allowed)
			(copperpour not_allowed)
			(footprints allowed)
		)
		(placement
			(enabled no)
			(sheetname "")
		)
		(fill
			(thermal_gap 0.5)
			(thermal_bridge_width 0.5)
			(island_removal_mode 0)
		)
		(polygon
			(pts
				(xy 193.854578 -244.675152) (xy 195.353178 -244.675152) (xy 195.353178 -245.19509) (xy 193.854578 -245.19509)
			)
		)
	)
	(zone
		(layer "In2.Cu")
		(hatch none 0.5)
		(connect_pads
			(clearance 0)
		)
		(min_thickness 0.25)
		(keepout
			(tracks not_allowed)
			(vias allowed)
			(pads allowed)
			(copperpour not_allowed)
			(footprints allowed)
		)
		(placement
			(enabled no)
			(sheetname "")
		)
		(fill
			(thermal_gap 0.5)
			(thermal_bridge_width 0.5)
			(island_removal_mode 0)
		)
		(polygon
			(pts
				(xy 163.678616 -311.825132) (xy 165.177216 -311.825132) (xy 165.177216 -312.34507) (xy 163.678616 -312.34507)
			)
		)
	)
	(zone
		(layer "In2.Cu")
		(hatch none 0.5)
		(connect_pads
			(clearance 0)
		)
		(min_thickness 0.25)
		(keepout
			(tracks not_allowed)
			(vias allowed)
			(pads allowed)
			(copperpour not_allowed)
			(footprints allowed)
		)
		(placement
			(enabled no)
			(sheetname "")
		)
		(fill
			(thermal_gap 0.5)
			(thermal_bridge_width 0.5)
			(island_removal_mode 0)
		)
		(polygon
			(pts
				(xy 415.718752 -209.825336) (xy 417.217352 -209.825336) (xy 417.217352 -210.345274) (xy 415.718752 -210.345274)
			)
		)
	)
	(zone
		(layer "In2.Cu")
		(hatch none 0.5)
		(connect_pads
			(clearance 0)
		)
		(min_thickness 0.25)
		(keepout
			(tracks not_allowed)
			(vias allowed)
			(pads allowed)
			(copperpour not_allowed)
			(footprints allowed)
		)
		(placement
			(enabled no)
			(sheetname "")
		)
		(fill
			(thermal_gap 0.5)
			(thermal_bridge_width 0.5)
			(island_removal_mode 0)
		)
		(polygon
			(pts
				(xy 167.778684 -198.77532) (xy 169.277284 -198.77532) (xy 169.277284 -199.295258) (xy 167.778684 -199.295258)
			)
		)
	)
	(zone
		(layer "In2.Cu")
		(hatch none 0.5)
		(connect_pads
			(clearance 0)
		)
		(min_thickness 0.25)
		(keepout
			(tracks not_allowed)
			(vias allowed)
			(pads allowed)
			(copperpour not_allowed)
			(footprints allowed)
		)
		(placement
			(enabled no)
			(sheetname "")
		)
		(fill
			(thermal_gap 0.5)
			(thermal_bridge_width 0.5)
			(island_removal_mode 0)
		)
		(polygon
			(pts
				(xy 163.678616 -316.075314) (xy 165.177216 -316.075314) (xy 165.177216 -316.595252) (xy 163.678616 -316.595252)
			)
		)
	)
	(zone
		(layer "In2.Cu")
		(hatch none 0.5)
		(connect_pads
			(clearance 0)
		)
		(min_thickness 0.25)
		(keepout
			(tracks not_allowed)
			(vias allowed)
			(pads allowed)
			(copperpour not_allowed)
			(footprints allowed)
		)
		(placement
			(enabled no)
			(sheetname "")
		)
		(fill
			(thermal_gap 0.5)
			(thermal_bridge_width 0.5)
			(island_removal_mode 0)
		)
		(polygon
			(pts
				(xy 299.07484 -301.625254) (xy 300.57344 -301.625254) (xy 300.57344 -302.145192) (xy 299.07484 -302.145192)
			)
		)
	)
	(zone
		(layer "In2.Cu")
		(hatch none 0.5)
		(connect_pads
			(clearance 0)
		)
		(min_thickness 0.25)
		(keepout
			(tracks not_allowed)
			(vias allowed)
			(pads allowed)
			(copperpour not_allowed)
			(footprints allowed)
		)
		(placement
			(enabled no)
			(sheetname "")
		)
		(fill
			(thermal_gap 0.5)
			(thermal_bridge_width 0.5)
			(island_removal_mode 0)
		)
		(polygon
			(pts
				(xy 163.678616 -213.225126) (xy 165.177216 -213.225126) (xy 165.177216 -213.745064) (xy 163.678616 -213.745064)
			)
		)
	)
	(zone
		(layer "In2.Cu")
		(hatch none 0.5)
		(connect_pads
			(clearance 0)
		)
		(min_thickness 0.25)
		(keepout
			(tracks not_allowed)
			(vias allowed)
			(pads allowed)
			(copperpour not_allowed)
			(footprints allowed)
		)
		(placement
			(enabled no)
			(sheetname "")
		)
		(fill
			(thermal_gap 0.5)
			(thermal_bridge_width 0.5)
			(island_removal_mode 0)
		)
		(polygon
			(pts
				(xy 438.350914 -264.225278) (xy 439.849514 -264.225278) (xy 439.849514 -264.745216) (xy 438.350914 -264.745216)
			)
		)
	)
	(zone
		(layer "In2.Cu")
		(hatch none 0.5)
		(connect_pads
			(clearance 0)
		)
		(min_thickness 0.25)
		(keepout
			(tracks not_allowed)
			(vias allowed)
			(pads allowed)
			(copperpour not_allowed)
			(footprints allowed)
		)
		(placement
			(enabled no)
			(sheetname "")
		)
		(fill
			(thermal_gap 0.5)
			(thermal_bridge_width 0.5)
			(island_removal_mode 0)
		)
		(polygon
			(pts
				(xy 426.706792 -314.375292) (xy 428.205392 -314.375292) (xy 428.205392 -314.89523) (xy 426.706792 -314.89523)
			)
		)
	)
	(zone
		(layer "In2.Cu")
		(hatch none 0.5)
		(connect_pads
			(clearance 0)
		)
		(min_thickness 0.25)
		(keepout
			(tracks not_allowed)
			(vias allowed)
			(pads allowed)
			(copperpour not_allowed)
			(footprints allowed)
		)
		(placement
			(enabled no)
			(sheetname "")
		)
		(fill
			(thermal_gap 0.5)
			(thermal_bridge_width 0.5)
			(island_removal_mode 0)
		)
		(polygon
			(pts
				(xy 279.886664 -235.325158) (xy 281.385264 -235.325158) (xy 281.385264 -235.845096) (xy 279.886664 -235.845096)
			)
		)
	)
	(zone
		(layer "In2.Cu")
		(hatch none 0.5)
		(connect_pads
			(clearance 0)
		)
		(min_thickness 0.25)
		(keepout
			(tracks not_allowed)
			(vias allowed)
			(pads allowed)
			(copperpour not_allowed)
			(footprints allowed)
		)
		(placement
			(enabled no)
			(sheetname "")
		)
		(fill
			(thermal_gap 0.5)
			(thermal_bridge_width 0.5)
			(island_removal_mode 0)
		)
		(polygon
			(pts
				(xy 47.034704 -222.57512) (xy 48.533304 -222.57512) (xy 48.533304 -223.095058) (xy 47.034704 -223.095058)
			)
		)
	)
	(zone
		(layer "In2.Cu")
		(hatch none 0.5)
		(connect_pads
			(clearance 0)
		)
		(min_thickness 0.25)
		(keepout
			(tracks not_allowed)
			(vias allowed)
			(pads allowed)
			(copperpour not_allowed)
			(footprints allowed)
		)
		(placement
			(enabled no)
			(sheetname "")
		)
		(fill
			(thermal_gap 0.5)
			(thermal_bridge_width 0.5)
			(island_removal_mode 0)
		)
		(polygon
			(pts
				(xy 291.530786 -260.825234) (xy 293.029386 -260.825234) (xy 293.029386 -261.345172) (xy 291.530786 -261.345172)
			)
		)
	)
	(zone
		(layer "In2.Cu")
		(hatch none 0.5)
		(connect_pads
			(clearance 0)
		)
		(min_thickness 0.25)
		(keepout
			(tracks not_allowed)
			(vias allowed)
			(pads allowed)
			(copperpour not_allowed)
			(footprints allowed)
		)
		(placement
			(enabled no)
			(sheetname "")
		)
		(fill
			(thermal_gap 0.5)
			(thermal_bridge_width 0.5)
			(island_removal_mode 0)
		)
		(polygon
			(pts
				(xy 197.954646 -238.725202) (xy 199.453246 -238.725202) (xy 199.453246 -239.24514) (xy 197.954646 -239.24514)
			)
		)
	)
	(zone
		(layer "In2.Cu")
		(hatch none 0.5)
		(connect_pads
			(clearance 0)
		)
		(min_thickness 0.25)
		(keepout
			(tracks not_allowed)
			(vias allowed)
			(pads allowed)
			(copperpour not_allowed)
			(footprints allowed)
		)
		(placement
			(enabled no)
			(sheetname "")
		)
		(fill
			(thermal_gap 0.5)
			(thermal_bridge_width 0.5)
			(island_removal_mode 0)
		)
		(polygon
			(pts
				(xy 299.07484 -247.225312) (xy 300.57344 -247.225312) (xy 300.57344 -247.74525) (xy 299.07484 -247.74525)
			)
		)
	)
	(zone
		(layer "In2.Cu")
		(hatch none 0.5)
		(connect_pads
			(clearance 0)
		)
		(min_thickness 0.25)
		(keepout
			(tracks not_allowed)
			(vias allowed)
			(pads allowed)
			(copperpour not_allowed)
			(footprints allowed)
		)
		(placement
			(enabled no)
			(sheetname "")
		)
		(fill
			(thermal_gap 0.5)
			(thermal_bridge_width 0.5)
			(island_removal_mode 0)
		)
		(polygon
			(pts
				(xy 287.430718 -220.875098) (xy 288.929318 -220.875098) (xy 288.929318 -221.395036) (xy 287.430718 -221.395036)
			)
		)
	)
	(zone
		(layer "In2.Cu")
		(hatch none 0.5)
		(connect_pads
			(clearance 0)
		)
		(min_thickness 0.25)
		(keepout
			(tracks not_allowed)
			(vias allowed)
			(pads allowed)
			(copperpour not_allowed)
			(footprints allowed)
		)
		(placement
			(enabled no)
			(sheetname "")
		)
		(fill
			(thermal_gap 0.5)
			(thermal_bridge_width 0.5)
			(island_removal_mode 0)
		)
		(polygon
			(pts
				(xy 426.706792 -230.225346) (xy 428.205392 -230.225346) (xy 428.205392 -230.745284) (xy 426.706792 -230.745284)
			)
		)
	)
	(zone
		(layer "In2.Cu")
		(hatch none 0.5)
		(connect_pads
			(clearance 0)
		)
		(min_thickness 0.25)
		(keepout
			(tracks not_allowed)
			(vias allowed)
			(pads allowed)
			(copperpour not_allowed)
			(footprints allowed)
		)
		(placement
			(enabled no)
			(sheetname "")
		)
		(fill
			(thermal_gap 0.5)
			(thermal_bridge_width 0.5)
			(island_removal_mode 0)
		)
		(polygon
			(pts
				(xy 28.50261 -232.775252) (xy 30.00121 -232.775252) (xy 30.00121 -233.29519) (xy 28.50261 -233.29519)
			)
		)
	)
	(zone
		(layer "In2.Cu")
		(hatch none 0.5)
		(connect_pads
			(clearance 0)
		)
		(min_thickness 0.25)
		(keepout
			(tracks not_allowed)
			(vias allowed)
			(pads allowed)
			(copperpour not_allowed)
			(footprints allowed)
		)
		(placement
			(enabled no)
			(sheetname "")
		)
		(fill
			(thermal_gap 0.5)
			(thermal_bridge_width 0.5)
			(island_removal_mode 0)
		)
		(polygon
			(pts
				(xy 28.50261 -208.125314) (xy 30.00121 -208.125314) (xy 30.00121 -208.645252) (xy 28.50261 -208.645252)
			)
		)
	)
	(zone
		(layer "In2.Cu")
		(hatch none 0.5)
		(connect_pads
			(clearance 0)
		)
		(min_thickness 0.25)
		(keepout
			(tracks allowed)
			(vias allowed)
			(pads allowed)
			(copperpour allowed)
			(footprints allowed)
		)
		(placement
			(enabled no)
			(sheetname "")
		)
		(fill
			(thermal_gap 0.5)
			(thermal_bridge_width 0.5)
			(island_removal_mode 0)
		)
		(polygon
			(pts
				(xy 428.967646 -354.362258) (xy 428.967646 -353.739958) (xy 429.518826 -353.739958) (xy 429.518826 -354.362258)
			)
		)
	)
	(zone
		(layer "In2.Cu")
		(hatch none 0.5)
		(connect_pads
			(clearance 0)
		)
		(min_thickness 0.25)
		(keepout
			(tracks not_allowed)
			(vias allowed)
			(pads allowed)
			(copperpour not_allowed)
			(footprints allowed)
		)
		(placement
			(enabled no)
			(sheetname "")
		)
		(fill
			(thermal_gap 0.5)
			(thermal_bridge_width 0.5)
			(island_removal_mode 0)
		)
		(polygon
			(pts
				(xy 190.410846 -279.525222) (xy 191.909446 -279.525222) (xy 191.909446 -280.04516) (xy 190.410846 -280.04516)
			)
		)
	)
	(zone
		(layer "In2.Cu")
		(hatch none 0.5)
		(connect_pads
			(clearance 0)
		)
		(min_thickness 0.25)
		(keepout
			(tracks not_allowed)
			(vias allowed)
			(pads allowed)
			(copperpour not_allowed)
			(footprints allowed)
		)
		(placement
			(enabled no)
			(sheetname "")
		)
		(fill
			(thermal_gap 0.5)
			(thermal_bridge_width 0.5)
			(island_removal_mode 0)
		)
		(polygon
			(pts
				(xy 411.618684 -304.17516) (xy 413.117284 -304.17516) (xy 413.117284 -304.695098) (xy 411.618684 -304.695098)
			)
		)
	)
	(zone
		(layer "In2.Cu")
		(hatch none 0.5)
		(connect_pads
			(clearance 0)
		)
		(min_thickness 0.25)
		(keepout
			(tracks not_allowed)
			(vias allowed)
			(pads allowed)
			(copperpour not_allowed)
			(footprints allowed)
		)
		(placement
			(enabled no)
			(sheetname "")
		)
		(fill
			(thermal_gap 0.5)
			(thermal_bridge_width 0.5)
			(island_removal_mode 0)
		)
		(polygon
			(pts
				(xy 47.034704 -313.525154) (xy 48.533304 -313.525154) (xy 48.533304 -314.045092) (xy 47.034704 -314.045092)
			)
		)
	)
	(zone
		(layer "In2.Cu")
		(hatch none 0.5)
		(connect_pads
			(clearance 0)
		)
		(min_thickness 0.25)
		(keepout
			(tracks not_allowed)
			(vias allowed)
			(pads allowed)
			(copperpour not_allowed)
			(footprints allowed)
		)
		(placement
			(enabled no)
			(sheetname "")
		)
		(fill
			(thermal_gap 0.5)
			(thermal_bridge_width 0.5)
			(island_removal_mode 0)
		)
		(polygon
			(pts
				(xy 426.706792 -213.225126) (xy 428.205392 -213.225126) (xy 428.205392 -213.745064) (xy 426.706792 -213.745064)
			)
		)
	)
	(zone
		(layer "In2.Cu")
		(hatch none 0.5)
		(connect_pads
			(clearance 0)
		)
		(min_thickness 0.25)
		(keepout
			(tracks not_allowed)
			(vias allowed)
			(pads allowed)
			(copperpour not_allowed)
			(footprints allowed)
		)
		(placement
			(enabled no)
			(sheetname "")
		)
		(fill
			(thermal_gap 0.5)
			(thermal_bridge_width 0.5)
			(island_removal_mode 0)
		)
		(polygon
			(pts
				(xy 54.578758 -266.775184) (xy 56.077358 -266.775184) (xy 56.077358 -267.295122) (xy 54.578758 -267.295122)
			)
		)
	)
	(zone
		(layer "In2.Cu")
		(hatch none 0.5)
		(connect_pads
			(clearance 0)
		)
		(min_thickness 0.25)
		(keepout
			(tracks not_allowed)
			(vias allowed)
			(pads allowed)
			(copperpour not_allowed)
			(footprints allowed)
		)
		(placement
			(enabled no)
			(sheetname "")
		)
		(fill
			(thermal_gap 0.5)
			(thermal_bridge_width 0.5)
			(island_removal_mode 0)
		)
		(polygon
			(pts
				(xy 423.262806 -219.17533) (xy 424.761406 -219.17533) (xy 424.761406 -219.695268) (xy 423.262806 -219.695268)
			)
		)
	)
	(zone
		(layer "In2.Cu")
		(hatch none 0.5)
		(connect_pads
			(clearance 0)
		)
		(min_thickness 0.25)
		(keepout
			(tracks not_allowed)
			(vias allowed)
			(pads allowed)
			(copperpour not_allowed)
			(footprints allowed)
		)
		(placement
			(enabled no)
			(sheetname "")
		)
		(fill
			(thermal_gap 0.5)
			(thermal_bridge_width 0.5)
			(island_removal_mode 0)
		)
		(polygon
			(pts
				(xy 423.262806 -288.875216) (xy 424.761406 -288.875216) (xy 424.761406 -289.395154) (xy 423.262806 -289.395154)
			)
		)
	)
	(zone
		(layer "In2.Cu")
		(hatch none 0.5)
		(connect_pads
			(clearance 0)
		)
		(min_thickness 0.25)
		(keepout
			(tracks not_allowed)
			(vias allowed)
			(pads allowed)
			(copperpour not_allowed)
			(footprints allowed)
		)
		(placement
			(enabled no)
			(sheetname "")
		)
		(fill
			(thermal_gap 0.5)
			(thermal_bridge_width 0.5)
			(island_removal_mode 0)
		)
		(polygon
			(pts
				(xy 28.50261 -201.325226) (xy 30.00121 -201.325226) (xy 30.00121 -201.845164) (xy 28.50261 -201.845164)
			)
		)
	)
	(zone
		(layer "In2.Cu")
		(hatch none 0.5)
		(connect_pads
			(clearance 0)
		)
		(min_thickness 0.25)
		(keepout
			(tracks not_allowed)
			(vias allowed)
			(pads allowed)
			(copperpour not_allowed)
			(footprints allowed)
		)
		(placement
			(enabled no)
			(sheetname "")
		)
		(fill
			(thermal_gap 0.5)
			(thermal_bridge_width 0.5)
			(island_removal_mode 0)
		)
		(polygon
			(pts
				(xy 20.95881 -236.175296) (xy 22.45741 -236.175296) (xy 22.45741 -236.695234) (xy 20.95881 -236.695234)
			)
		)
	)
	(zone
		(layer "In2.Cu")
		(hatch none 0.5)
		(connect_pads
			(clearance 0)
		)
		(min_thickness 0.25)
		(keepout
			(tracks not_allowed)
			(vias allowed)
			(pads allowed)
			(copperpour not_allowed)
			(footprints allowed)
		)
		(placement
			(enabled no)
			(sheetname "")
		)
		(fill
			(thermal_gap 0.5)
			(thermal_bridge_width 0.5)
			(island_removal_mode 0)
		)
		(polygon
			(pts
				(xy 276.442932 -220.025214) (xy 277.941532 -220.025214) (xy 277.941532 -220.545152) (xy 276.442932 -220.545152)
			)
		)
	)
	(zone
		(layer "In2.Cu")
		(hatch none 0.5)
		(connect_pads
			(clearance 0)
		)
		(min_thickness 0.25)
		(keepout
			(tracks not_allowed)
			(vias allowed)
			(pads allowed)
			(copperpour not_allowed)
			(footprints allowed)
		)
		(placement
			(enabled no)
			(sheetname "")
		)
		(fill
			(thermal_gap 0.5)
			(thermal_bridge_width 0.5)
			(island_removal_mode 0)
		)
		(polygon
			(pts
				(xy 31.946596 -199.625204) (xy 33.445196 -199.625204) (xy 33.445196 -200.145142) (xy 31.946596 -200.145142)
			)
		)
	)
	(zone
		(layer "In2.Cu")
		(hatch none 0.5)
		(connect_pads
			(clearance 0)
		)
		(min_thickness 0.25)
		(keepout
			(tracks allowed)
			(vias allowed)
			(pads allowed)
			(copperpour allowed)
			(footprints allowed)
		)
		(placement
			(enabled no)
			(sheetname "")
		)
		(fill
			(thermal_gap 0.5)
			(thermal_bridge_width 0.5)
			(island_removal_mode 0)
		)
		(polygon
			(pts
				(xy 109.90072 -175.57496) (xy 109.90072 -175.028606) (xy 110.45317 -175.028606) (xy 110.45317 -175.57496)
			)
		)
	)
	(zone
		(layer "In2.Cu")
		(hatch none 0.5)
		(connect_pads
			(clearance 0)
		)
		(min_thickness 0.25)
		(keepout
			(tracks not_allowed)
			(vias allowed)
			(pads allowed)
			(copperpour not_allowed)
			(footprints allowed)
		)
		(placement
			(enabled no)
			(sheetname "")
		)
		(fill
			(thermal_gap 0.5)
			(thermal_bridge_width 0.5)
			(island_removal_mode 0)
		)
		(polygon
			(pts
				(xy 283.986732 -247.225312) (xy 285.485332 -247.225312) (xy 285.485332 -247.74525) (xy 283.986732 -247.74525)
			)
		)
	)
	(zone
		(layer "In2.Cu")
		(hatch none 0.5)
		(connect_pads
			(clearance 0)
		)
		(min_thickness 0.25)
		(keepout
			(tracks not_allowed)
			(vias allowed)
			(pads allowed)
			(copperpour not_allowed)
			(footprints allowed)
		)
		(placement
			(enabled no)
			(sheetname "")
		)
		(fill
			(thermal_gap 0.5)
			(thermal_bridge_width 0.5)
			(island_removal_mode 0)
		)
		(polygon
			(pts
				(xy 294.974772 -253.175262) (xy 296.473372 -253.175262) (xy 296.473372 -253.6952) (xy 294.974772 -253.6952)
			)
		)
	)
	(zone
		(layer "In2.Cu")
		(hatch none 0.5)
		(connect_pads
			(clearance 0)
		)
		(min_thickness 0.25)
		(keepout
			(tracks not_allowed)
			(vias allowed)
			(pads allowed)
			(copperpour not_allowed)
			(footprints allowed)
		)
		(placement
			(enabled no)
			(sheetname "")
		)
		(fill
			(thermal_gap 0.5)
			(thermal_bridge_width 0.5)
			(island_removal_mode 0)
		)
		(polygon
			(pts
				(xy 58.678826 -281.225244) (xy 60.177426 -281.225244) (xy 60.177426 -281.745182) (xy 58.678826 -281.745182)
			)
		)
	)
	(zone
		(layer "In2.Cu")
		(hatch none 0.5)
		(connect_pads
			(clearance 0)
		)
		(min_thickness 0.25)
		(keepout
			(tracks not_allowed)
			(vias allowed)
			(pads allowed)
			(copperpour not_allowed)
			(footprints allowed)
		)
		(placement
			(enabled no)
			(sheetname "")
		)
		(fill
			(thermal_gap 0.5)
			(thermal_bridge_width 0.5)
			(island_removal_mode 0)
		)
		(polygon
			(pts
				(xy 287.430718 -224.275142) (xy 288.929318 -224.275142) (xy 288.929318 -224.79508) (xy 287.430718 -224.79508)
			)
		)
	)
	(zone
		(layer "In2.Cu")
		(hatch none 0.5)
		(connect_pads
			(clearance 0)
		)
		(min_thickness 0.25)
		(keepout
			(tracks not_allowed)
			(vias allowed)
			(pads allowed)
			(copperpour not_allowed)
			(footprints allowed)
		)
		(placement
			(enabled no)
			(sheetname "")
		)
		(fill
			(thermal_gap 0.5)
			(thermal_bridge_width 0.5)
			(island_removal_mode 0)
		)
		(polygon
			(pts
				(arc
					(start 306.590446 -381.824484)
					(mid 306.61037 -381.83372)
					(end 306.632102 -381.83693)
				)
				(arc
					(start 306.826666 -381.83693)
					(mid 306.880548 -381.814612)
					(end 306.902866 -381.76073)
				)
				(arc
					(start 306.902866 -381.07493)
					(mid 306.880548 -381.021048)
					(end 306.826666 -380.99873)
				)
				(arc
					(start 306.632102 -380.99873)
					(mid 306.610358 -381.001898)
					(end 306.590446 -381.011176)
				)
				(arc
					(start 306.294282 -381.203962)
					(mid 306.252598 -381.216184)
					(end 306.21097 -381.203708)
				)
				(arc
					(start 305.917346 -381.011176)
					(mid 305.897422 -381.00194)
					(end 305.87569 -380.99873)
				)
				(arc
					(start 305.681126 -380.99873)
					(mid 305.627244 -381.021048)
					(end 305.604926 -381.07493)
				)
				(arc
					(start 305.604926 -381.76073)
					(mid 305.627244 -381.814612)
					(end 305.681126 -381.83693)
				)
				(arc
					(start 305.87696 -381.83693)
					(mid 305.898704 -381.833762)
					(end 305.918616 -381.824484)
				)
				(arc
					(start 306.21224 -381.631952)
					(mid 306.253896 -381.61955)
					(end 306.295552 -381.631952)
				)
			)
		)
	)
	(zone
		(layer "In2.Cu")
		(hatch none 0.5)
		(connect_pads
			(clearance 0)
		)
		(min_thickness 0.25)
		(keepout
			(tracks not_allowed)
			(vias allowed)
			(pads allowed)
			(copperpour not_allowed)
			(footprints allowed)
		)
		(placement
			(enabled no)
			(sheetname "")
		)
		(fill
			(thermal_gap 0.5)
			(thermal_bridge_width 0.5)
			(island_removal_mode 0)
		)
		(polygon
			(pts
				(xy 438.350914 -229.375208) (xy 439.849514 -229.375208) (xy 439.849514 -229.895146) (xy 438.350914 -229.895146)
			)
		)
	)
	(zone
		(layer "In2.Cu")
		(hatch none 0.5)
		(connect_pads
			(clearance 0)
		)
		(min_thickness 0.25)
		(keepout
			(tracks not_allowed)
			(vias allowed)
			(pads allowed)
			(copperpour not_allowed)
			(footprints allowed)
		)
		(placement
			(enabled no)
			(sheetname "")
		)
		(fill
			(thermal_gap 0.5)
			(thermal_bridge_width 0.5)
			(island_removal_mode 0)
		)
		(polygon
			(pts
				(xy 279.886664 -314.375292) (xy 281.385264 -314.375292) (xy 281.385264 -314.89523) (xy 279.886664 -314.89523)
			)
		)
	)
	(zone
		(layer "In2.Cu")
		(hatch none 0.5)
		(connect_pads
			(clearance 0)
		)
		(min_thickness 0.25)
		(keepout
			(tracks not_allowed)
			(vias allowed)
			(pads allowed)
			(copperpour not_allowed)
			(footprints allowed)
		)
		(placement
			(enabled no)
			(sheetname "")
		)
		(fill
			(thermal_gap 0.5)
			(thermal_bridge_width 0.5)
			(island_removal_mode 0)
		)
		(polygon
			(pts
				(xy 272.342864 -294.825166) (xy 273.841464 -294.825166) (xy 273.841464 -295.345104) (xy 272.342864 -295.345104)
			)
		)
	)
	(zone
		(layer "In2.Cu")
		(hatch none 0.5)
		(connect_pads
			(clearance 0)
		)
		(min_thickness 0.25)
		(keepout
			(tracks not_allowed)
			(vias allowed)
			(pads allowed)
			(copperpour not_allowed)
			(footprints allowed)
		)
		(placement
			(enabled no)
			(sheetname "")
		)
		(fill
			(thermal_gap 0.5)
			(thermal_bridge_width 0.5)
			(island_removal_mode 0)
		)
		(polygon
			(pts
				(xy 47.034704 -253.175262) (xy 48.533304 -253.175262) (xy 48.533304 -253.6952) (xy 47.034704 -253.6952)
			)
		)
	)
	(zone
		(layer "In2.Cu")
		(hatch none 0.5)
		(connect_pads
			(clearance 0)
		)
		(min_thickness 0.25)
		(keepout
			(tracks not_allowed)
			(vias allowed)
			(pads allowed)
			(copperpour not_allowed)
			(footprints allowed)
		)
		(placement
			(enabled no)
			(sheetname "")
		)
		(fill
			(thermal_gap 0.5)
			(thermal_bridge_width 0.5)
			(island_removal_mode 0)
		)
		(polygon
			(pts
				(xy 294.974772 -265.075162) (xy 296.473372 -265.075162) (xy 296.473372 -265.5951) (xy 294.974772 -265.5951)
			)
		)
	)
	(zone
		(layer "In2.Cu")
		(hatch none 0.5)
		(connect_pads
			(clearance 0)
		)
		(min_thickness 0.25)
		(keepout
			(tracks not_allowed)
			(vias allowed)
			(pads allowed)
			(copperpour not_allowed)
			(footprints allowed)
		)
		(placement
			(enabled no)
			(sheetname "")
		)
		(fill
			(thermal_gap 0.5)
			(thermal_bridge_width 0.5)
			(island_removal_mode 0)
		)
		(polygon
			(pts
				(xy 197.954646 -296.525188) (xy 199.453246 -296.525188) (xy 199.453246 -297.045126) (xy 197.954646 -297.045126)
			)
		)
	)
	(zone
		(layer "In2.Cu")
		(hatch none 0.5)
		(connect_pads
			(clearance 0)
		)
		(min_thickness 0.25)
		(keepout
			(tracks not_allowed)
			(vias allowed)
			(pads allowed)
			(copperpour not_allowed)
			(footprints allowed)
		)
		(placement
			(enabled no)
			(sheetname "")
		)
		(fill
			(thermal_gap 0.5)
			(thermal_bridge_width 0.5)
			(island_removal_mode 0)
		)
		(polygon
			(pts
				(xy 302.518826 -222.57512) (xy 304.017426 -222.57512) (xy 304.017426 -223.095058) (xy 302.518826 -223.095058)
			)
		)
	)
	(zone
		(layer "In2.Cu")
		(hatch none 0.5)
		(connect_pads
			(clearance 0)
		)
		(min_thickness 0.25)
		(keepout
			(tracks not_allowed)
			(vias allowed)
			(pads allowed)
			(copperpour not_allowed)
			(footprints allowed)
		)
		(placement
			(enabled no)
			(sheetname "")
		)
		(fill
			(thermal_gap 0.5)
			(thermal_bridge_width 0.5)
			(island_removal_mode 0)
		)
		(polygon
			(pts
				(xy 54.578758 -294.825166) (xy 56.077358 -294.825166) (xy 56.077358 -295.345104) (xy 54.578758 -295.345104)
			)
		)
	)
	(zone
		(layer "In2.Cu")
		(hatch none 0.5)
		(connect_pads
			(clearance 0)
		)
		(min_thickness 0.25)
		(keepout
			(tracks not_allowed)
			(vias allowed)
			(pads allowed)
			(copperpour not_allowed)
			(footprints allowed)
		)
		(placement
			(enabled no)
			(sheetname "")
		)
		(fill
			(thermal_gap 0.5)
			(thermal_bridge_width 0.5)
			(island_removal_mode 0)
		)
		(polygon
			(pts
				(xy 167.778684 -290.575238) (xy 169.277284 -290.575238) (xy 169.277284 -291.095176) (xy 167.778684 -291.095176)
			)
		)
	)
	(zone
		(layer "In2.Cu")
		(hatch none 0.5)
		(connect_pads
			(clearance 0)
		)
		(min_thickness 0.25)
		(keepout
			(tracks not_allowed)
			(vias allowed)
			(pads allowed)
			(copperpour not_allowed)
			(footprints allowed)
		)
		(placement
			(enabled no)
			(sheetname "")
		)
		(fill
			(thermal_gap 0.5)
			(thermal_bridge_width 0.5)
			(island_removal_mode 0)
		)
		(polygon
			(pts
				(xy 58.678826 -203.025248) (xy 60.177426 -203.025248) (xy 60.177426 -203.545186) (xy 58.678826 -203.545186)
			)
		)
	)
	(zone
		(layer "In2.Cu")
		(hatch none 0.5)
		(connect_pads
			(clearance 0)
		)
		(min_thickness 0.25)
		(keepout
			(tracks not_allowed)
			(vias allowed)
			(pads allowed)
			(copperpour not_allowed)
			(footprints allowed)
		)
		(placement
			(enabled no)
			(sheetname "")
		)
		(fill
			(thermal_gap 0.5)
			(thermal_bridge_width 0.5)
			(island_removal_mode 0)
		)
		(polygon
			(pts
				(xy 291.530786 -290.575238) (xy 293.029386 -290.575238) (xy 293.029386 -291.095176) (xy 291.530786 -291.095176)
			)
		)
	)
	(zone
		(layer "In2.Cu")
		(hatch none 0.5)
		(connect_pads
			(clearance 0)
		)
		(min_thickness 0.25)
		(keepout
			(tracks not_allowed)
			(vias allowed)
			(pads allowed)
			(copperpour not_allowed)
			(footprints allowed)
		)
		(placement
			(enabled no)
			(sheetname "")
		)
		(fill
			(thermal_gap 0.5)
			(thermal_bridge_width 0.5)
			(island_removal_mode 0)
		)
		(polygon
			(pts
				(xy 276.442932 -282.925266) (xy 277.941532 -282.925266) (xy 277.941532 -283.445204) (xy 276.442932 -283.445204)
			)
		)
	)
	(zone
		(layer "In2.Cu")
		(hatch none 0.5)
		(connect_pads
			(clearance 0)
		)
		(min_thickness 0.25)
		(keepout
			(tracks not_allowed)
			(vias allowed)
			(pads allowed)
			(copperpour not_allowed)
			(footprints allowed)
		)
		(placement
			(enabled no)
			(sheetname "")
		)
		(fill
			(thermal_gap 0.5)
			(thermal_bridge_width 0.5)
			(island_removal_mode 0)
		)
		(polygon
			(pts
				(xy 426.706792 -222.57512) (xy 428.205392 -222.57512) (xy 428.205392 -223.095058) (xy 426.706792 -223.095058)
			)
		)
	)
	(zone
		(layer "In2.Cu")
		(hatch none 0.5)
		(connect_pads
			(clearance 0)
		)
		(min_thickness 0.25)
		(keepout
			(tracks not_allowed)
			(vias allowed)
			(pads allowed)
			(copperpour not_allowed)
			(footprints allowed)
		)
		(placement
			(enabled no)
			(sheetname "")
		)
		(fill
			(thermal_gap 0.5)
			(thermal_bridge_width 0.5)
			(island_removal_mode 0)
		)
		(polygon
			(pts
				(xy 171.22267 -216.62517) (xy 172.72127 -216.62517) (xy 172.72127 -217.145108) (xy 171.22267 -217.145108)
			)
		)
	)
	(zone
		(layer "In2.Cu")
		(hatch none 0.5)
		(connect_pads
			(clearance 0)
		)
		(min_thickness 0.25)
		(keepout
			(tracks not_allowed)
			(vias allowed)
			(pads allowed)
			(copperpour not_allowed)
			(footprints allowed)
		)
		(placement
			(enabled no)
			(sheetname "")
		)
		(fill
			(thermal_gap 0.5)
			(thermal_bridge_width 0.5)
			(island_removal_mode 0)
		)
		(polygon
			(pts
				(xy 36.046664 -287.175194) (xy 37.545264 -287.175194) (xy 37.545264 -287.695132) (xy 36.046664 -287.695132)
			)
		)
	)
	(zone
		(layer "In2.Cu")
		(hatch none 0.5)
		(connect_pads
			(clearance 0)
		)
		(min_thickness 0.25)
		(keepout
			(tracks not_allowed)
			(vias allowed)
			(pads allowed)
			(copperpour not_allowed)
			(footprints allowed)
		)
		(placement
			(enabled no)
			(sheetname "")
		)
		(fill
			(thermal_gap 0.5)
			(thermal_bridge_width 0.5)
			(island_removal_mode 0)
		)
		(polygon
			(pts
				(xy 411.618684 -241.275108) (xy 413.117284 -241.275108) (xy 413.117284 -241.795046) (xy 411.618684 -241.795046)
			)
		)
	)
	(zone
		(layer "In2.Cu")
		(hatch none 0.5)
		(connect_pads
			(clearance 0)
		)
		(min_thickness 0.25)
		(keepout
			(tracks not_allowed)
			(vias allowed)
			(pads allowed)
			(copperpour not_allowed)
			(footprints allowed)
		)
		(placement
			(enabled no)
			(sheetname "")
		)
		(fill
			(thermal_gap 0.5)
			(thermal_bridge_width 0.5)
			(island_removal_mode 0)
		)
		(polygon
			(pts
				(xy 419.162738 -233.625136) (xy 420.661338 -233.625136) (xy 420.661338 -234.145074) (xy 419.162738 -234.145074)
			)
		)
	)
	(zone
		(layer "In2.Cu")
		(hatch none 0.5)
		(connect_pads
			(clearance 0)
		)
		(min_thickness 0.25)
		(keepout
			(tracks not_allowed)
			(vias allowed)
			(pads allowed)
			(copperpour not_allowed)
			(footprints allowed)
		)
		(placement
			(enabled no)
			(sheetname "")
		)
		(fill
			(thermal_gap 0.5)
			(thermal_bridge_width 0.5)
			(island_removal_mode 0)
		)
		(polygon
			(pts
				(xy 445.894968 -203.025248) (xy 447.393568 -203.025248) (xy 447.393568 -203.545186) (xy 445.894968 -203.545186)
			)
		)
	)
	(zone
		(layer "In2.Cu")
		(hatch none 0.5)
		(connect_pads
			(clearance 0)
		)
		(min_thickness 0.25)
		(keepout
			(tracks not_allowed)
			(vias allowed)
			(pads allowed)
			(copperpour not_allowed)
			(footprints allowed)
		)
		(placement
			(enabled no)
			(sheetname "")
		)
		(fill
			(thermal_gap 0.5)
			(thermal_bridge_width 0.5)
			(island_removal_mode 0)
		)
		(polygon
			(pts
				(xy 28.50261 -231.07523) (xy 30.00121 -231.07523) (xy 30.00121 -231.595168) (xy 28.50261 -231.595168)
			)
		)
	)
	(zone
		(layer "In2.Cu")
		(hatch none 0.5)
		(connect_pads
			(clearance 0)
		)
		(min_thickness 0.25)
		(keepout
			(tracks not_allowed)
			(vias allowed)
			(pads allowed)
			(copperpour not_allowed)
			(footprints allowed)
		)
		(placement
			(enabled no)
			(sheetname "")
		)
		(fill
			(thermal_gap 0.5)
			(thermal_bridge_width 0.5)
			(island_removal_mode 0)
		)
		(polygon
			(pts
				(xy 302.518826 -316.075314) (xy 304.017426 -316.075314) (xy 304.017426 -316.595252) (xy 302.518826 -316.595252)
			)
		)
	)
	(zone
		(layer "In2.Cu")
		(hatch none 0.5)
		(connect_pads
			(clearance 0)
		)
		(min_thickness 0.25)
		(keepout
			(tracks not_allowed)
			(vias allowed)
			(pads allowed)
			(copperpour not_allowed)
			(footprints allowed)
		)
		(placement
			(enabled no)
			(sheetname "")
		)
		(fill
			(thermal_gap 0.5)
			(thermal_bridge_width 0.5)
			(island_removal_mode 0)
		)
		(polygon
			(pts
				(xy 287.430718 -272.725134) (xy 288.929318 -272.725134) (xy 288.929318 -273.245072) (xy 287.430718 -273.245072)
			)
		)
	)
	(zone
		(layer "In2.Cu")
		(hatch none 0.5)
		(connect_pads
			(clearance 0)
		)
		(min_thickness 0.25)
		(keepout
			(tracks not_allowed)
			(vias allowed)
			(pads allowed)
			(copperpour not_allowed)
			(footprints allowed)
		)
		(placement
			(enabled no)
			(sheetname "")
		)
		(fill
			(thermal_gap 0.5)
			(thermal_bridge_width 0.5)
			(island_removal_mode 0)
		)
		(polygon
			(pts
				(xy 20.95881 -301.625254) (xy 22.45741 -301.625254) (xy 22.45741 -302.145192) (xy 20.95881 -302.145192)
			)
		)
	)
	(zone
		(layer "In2.Cu")
		(hatch none 0.5)
		(connect_pads
			(clearance 0)
		)
		(min_thickness 0.25)
		(keepout
			(tracks not_allowed)
			(vias allowed)
			(pads allowed)
			(copperpour not_allowed)
			(footprints allowed)
		)
		(placement
			(enabled no)
			(sheetname "")
		)
		(fill
			(thermal_gap 0.5)
			(thermal_bridge_width 0.5)
			(island_removal_mode 0)
		)
		(polygon
			(pts
				(xy 306.618894 -316.925198) (xy 308.117494 -316.925198) (xy 308.117494 -317.445136) (xy 306.618894 -317.445136)
			)
		)
	)
	(zone
		(layer "In2.Cu")
		(hatch none 0.5)
		(connect_pads
			(clearance 0)
		)
		(min_thickness 0.25)
		(keepout
			(tracks allowed)
			(vias allowed)
			(pads allowed)
			(copperpour allowed)
			(footprints allowed)
		)
		(placement
			(enabled no)
			(sheetname "")
		)
		(fill
			(thermal_gap 0.5)
			(thermal_bridge_width 0.5)
			(island_removal_mode 0)
		)
		(polygon
			(pts
				(xy 50.540412 -349.943166) (xy 50.540412 -349.320866) (xy 51.091592 -349.320866) (xy 51.091592 -349.943166)
			)
		)
	)
	(zone
		(layer "In2.Cu")
		(hatch none 0.5)
		(connect_pads
			(clearance 0)
		)
		(min_thickness 0.25)
		(keepout
			(tracks not_allowed)
			(vias allowed)
			(pads allowed)
			(copperpour not_allowed)
			(footprints allowed)
		)
		(placement
			(enabled no)
			(sheetname "")
		)
		(fill
			(thermal_gap 0.5)
			(thermal_bridge_width 0.5)
			(island_removal_mode 0)
		)
		(polygon
			(pts
				(xy 28.50261 -221.725236) (xy 30.00121 -221.725236) (xy 30.00121 -222.245174) (xy 28.50261 -222.245174)
			)
		)
	)
	(zone
		(layer "In2.Cu")
		(hatch none 0.5)
		(connect_pads
			(clearance 0)
		)
		(min_thickness 0.25)
		(keepout
			(tracks not_allowed)
			(vias allowed)
			(pads allowed)
			(copperpour not_allowed)
			(footprints allowed)
		)
		(placement
			(enabled no)
			(sheetname "")
		)
		(fill
			(thermal_gap 0.5)
			(thermal_bridge_width 0.5)
			(island_removal_mode 0)
		)
		(polygon
			(pts
				(xy 175.322738 -275.275294) (xy 176.821338 -275.275294) (xy 176.821338 -275.795232) (xy 175.322738 -275.795232)
			)
		)
	)
	(zone
		(layer "In2.Cu")
		(hatch none 0.5)
		(connect_pads
			(clearance 0)
		)
		(min_thickness 0.25)
		(keepout
			(tracks not_allowed)
			(vias allowed)
			(pads allowed)
			(copperpour not_allowed)
			(footprints allowed)
		)
		(placement
			(enabled no)
			(sheetname "")
		)
		(fill
			(thermal_gap 0.5)
			(thermal_bridge_width 0.5)
			(island_removal_mode 0)
		)
		(polygon
			(pts
				(xy 434.250846 -202.17511) (xy 435.749446 -202.17511) (xy 435.749446 -202.695048) (xy 434.250846 -202.695048)
			)
		)
	)
	(zone
		(layer "In2.Cu")
		(hatch none 0.5)
		(connect_pads
			(clearance 0)
		)
		(min_thickness 0.25)
		(keepout
			(tracks not_allowed)
			(vias allowed)
			(pads allowed)
			(copperpour not_allowed)
			(footprints allowed)
		)
		(placement
			(enabled no)
			(sheetname "")
		)
		(fill
			(thermal_gap 0.5)
			(thermal_bridge_width 0.5)
			(island_removal_mode 0)
		)
		(polygon
			(pts
				(xy 419.162738 -276.125178) (xy 420.661338 -276.125178) (xy 420.661338 -276.645116) (xy 419.162738 -276.645116)
			)
		)
	)
	(zone
		(layer "In2.Cu")
		(hatch none 0.5)
		(connect_pads
			(clearance 0)
		)
		(min_thickness 0.25)
		(keepout
			(tracks not_allowed)
			(vias allowed)
			(pads allowed)
			(copperpour not_allowed)
			(footprints allowed)
		)
		(placement
			(enabled no)
			(sheetname "")
		)
		(fill
			(thermal_gap 0.5)
			(thermal_bridge_width 0.5)
			(island_removal_mode 0)
		)
		(polygon
			(pts
				(xy 190.410846 -290.575238) (xy 191.909446 -290.575238) (xy 191.909446 -291.095176) (xy 190.410846 -291.095176)
			)
		)
	)
	(zone
		(layer "In2.Cu")
		(hatch none 0.5)
		(connect_pads
			(clearance 0)
		)
		(min_thickness 0.25)
		(keepout
			(tracks not_allowed)
			(vias allowed)
			(pads allowed)
			(copperpour not_allowed)
			(footprints allowed)
		)
		(placement
			(enabled no)
			(sheetname "")
		)
		(fill
			(thermal_gap 0.5)
			(thermal_bridge_width 0.5)
			(island_removal_mode 0)
		)
		(polygon
			(pts
				(xy 16.858742 -220.025214) (xy 18.357342 -220.025214) (xy 18.357342 -220.545152) (xy 16.858742 -220.545152)
			)
		)
	)
	(zone
		(layer "In2.Cu")
		(hatch none 0.5)
		(connect_pads
			(clearance 0)
		)
		(min_thickness 0.25)
		(keepout
			(tracks not_allowed)
			(vias allowed)
			(pads allowed)
			(copperpour not_allowed)
			(footprints allowed)
		)
		(placement
			(enabled no)
			(sheetname "")
		)
		(fill
			(thermal_gap 0.5)
			(thermal_bridge_width 0.5)
			(island_removal_mode 0)
		)
		(polygon
			(pts
				(xy 24.402542 -291.425122) (xy 25.901142 -291.425122) (xy 25.901142 -291.94506) (xy 24.402542 -291.94506)
			)
		)
	)
	(zone
		(layer "In2.Cu")
		(hatch none 0.5)
		(connect_pads
			(clearance 0)
		)
		(min_thickness 0.25)
		(keepout
			(tracks not_allowed)
			(vias allowed)
			(pads allowed)
			(copperpour not_allowed)
			(footprints allowed)
		)
		(placement
			(enabled no)
			(sheetname "")
		)
		(fill
			(thermal_gap 0.5)
			(thermal_bridge_width 0.5)
			(island_removal_mode 0)
		)
		(polygon
			(pts
				(xy 31.946596 -272.725134) (xy 33.445196 -272.725134) (xy 33.445196 -273.245072) (xy 31.946596 -273.245072)
			)
		)
	)
	(zone
		(layer "In2.Cu")
		(hatch none 0.5)
		(connect_pads
			(clearance 0)
		)
		(min_thickness 0.25)
		(keepout
			(tracks not_allowed)
			(vias allowed)
			(pads allowed)
			(copperpour not_allowed)
			(footprints allowed)
		)
		(placement
			(enabled no)
			(sheetname "")
		)
		(fill
			(thermal_gap 0.5)
			(thermal_bridge_width 0.5)
			(island_removal_mode 0)
		)
		(polygon
			(pts
				(xy 438.350914 -219.17533) (xy 439.849514 -219.17533) (xy 439.849514 -219.695268) (xy 438.350914 -219.695268)
			)
		)
	)
	(zone
		(layer "In2.Cu")
		(hatch none 0.5)
		(connect_pads
			(clearance 0)
		)
		(min_thickness 0.25)
		(keepout
			(tracks not_allowed)
			(vias allowed)
			(pads allowed)
			(copperpour not_allowed)
			(footprints allowed)
		)
		(placement
			(enabled no)
			(sheetname "")
		)
		(fill
			(thermal_gap 0.5)
			(thermal_bridge_width 0.5)
			(island_removal_mode 0)
		)
		(polygon
			(pts
				(xy 415.718752 -301.625254) (xy 417.217352 -301.625254) (xy 417.217352 -302.145192) (xy 415.718752 -302.145192)
			)
		)
	)
	(zone
		(layer "In2.Cu")
		(hatch none 0.5)
		(connect_pads
			(clearance 0)
		)
		(min_thickness 0.25)
		(keepout
			(tracks not_allowed)
			(vias allowed)
			(pads allowed)
			(copperpour not_allowed)
			(footprints allowed)
		)
		(placement
			(enabled no)
			(sheetname "")
		)
		(fill
			(thermal_gap 0.5)
			(thermal_bridge_width 0.5)
			(island_removal_mode 0)
		)
		(polygon
			(pts
				(xy 306.618894 -288.875216) (xy 308.117494 -288.875216) (xy 308.117494 -289.395154) (xy 306.618894 -289.395154)
			)
		)
	)
	(zone
		(layer "In2.Cu")
		(hatch none 0.5)
		(connect_pads
			(clearance 0)
		)
		(min_thickness 0.25)
		(keepout
			(tracks not_allowed)
			(vias allowed)
			(pads allowed)
			(copperpour not_allowed)
			(footprints allowed)
		)
		(placement
			(enabled no)
			(sheetname "")
		)
		(fill
			(thermal_gap 0.5)
			(thermal_bridge_width 0.5)
			(island_removal_mode 0)
		)
		(polygon
			(pts
				(xy 294.974772 -231.925114) (xy 296.473372 -231.925114) (xy 296.473372 -232.445052) (xy 294.974772 -232.445052)
			)
		)
	)
	(zone
		(layer "In2.Cu")
		(hatch none 0.5)
		(connect_pads
			(clearance 0)
		)
		(min_thickness 0.25)
		(keepout
			(tracks not_allowed)
			(vias allowed)
			(pads allowed)
			(copperpour not_allowed)
			(footprints allowed)
		)
		(placement
			(enabled no)
			(sheetname "")
		)
		(fill
			(thermal_gap 0.5)
			(thermal_bridge_width 0.5)
			(island_removal_mode 0)
		)
		(polygon
			(pts
				(xy 268.898878 -303.325276) (xy 270.397478 -303.325276) (xy 270.397478 -303.845214) (xy 268.898878 -303.845214)
			)
		)
	)
	(zone
		(layer "In2.Cu")
		(hatch none 0.5)
		(connect_pads
			(clearance 0)
		)
		(min_thickness 0.25)
		(keepout
			(tracks not_allowed)
			(vias allowed)
			(pads allowed)
			(copperpour not_allowed)
			(footprints allowed)
		)
		(placement
			(enabled no)
			(sheetname "")
		)
		(fill
			(thermal_gap 0.5)
			(thermal_bridge_width 0.5)
			(island_removal_mode 0)
		)
		(polygon
			(pts
				(xy 175.322738 -293.975282) (xy 176.821338 -293.975282) (xy 176.821338 -294.49522) (xy 175.322738 -294.49522)
			)
		)
	)
	(zone
		(layer "In2.Cu")
		(hatch none 0.5)
		(connect_pads
			(clearance 0)
		)
		(min_thickness 0.25)
		(keepout
			(tracks not_allowed)
			(vias allowed)
			(pads allowed)
			(copperpour not_allowed)
			(footprints allowed)
		)
		(placement
			(enabled no)
			(sheetname "")
		)
		(fill
			(thermal_gap 0.5)
			(thermal_bridge_width 0.5)
			(island_removal_mode 0)
		)
		(polygon
			(pts
				(xy 272.342864 -297.375326) (xy 273.841464 -297.375326) (xy 273.841464 -297.895264) (xy 272.342864 -297.895264)
			)
		)
	)
	(zone
		(layer "In2.Cu")
		(hatch none 0.5)
		(connect_pads
			(clearance 0)
		)
		(min_thickness 0.25)
		(keepout
			(tracks not_allowed)
			(vias allowed)
			(pads allowed)
			(copperpour not_allowed)
			(footprints allowed)
		)
		(placement
			(enabled no)
			(sheetname "")
		)
		(fill
			(thermal_gap 0.5)
			(thermal_bridge_width 0.5)
			(island_removal_mode 0)
		)
		(polygon
			(pts
				(xy 276.442932 -279.525222) (xy 277.941532 -279.525222) (xy 277.941532 -280.04516) (xy 276.442932 -280.04516)
			)
		)
	)
	(zone
		(layer "In2.Cu")
		(hatch none 0.5)
		(connect_pads
			(clearance 0)
		)
		(min_thickness 0.25)
		(keepout
			(tracks not_allowed)
			(vias allowed)
			(pads allowed)
			(copperpour not_allowed)
			(footprints allowed)
		)
		(placement
			(enabled no)
			(sheetname "")
		)
		(fill
			(thermal_gap 0.5)
			(thermal_bridge_width 0.5)
			(island_removal_mode 0)
		)
		(polygon
			(pts
				(xy 438.350914 -254.025146) (xy 439.849514 -254.025146) (xy 439.849514 -254.545084) (xy 438.350914 -254.545084)
			)
		)
	)
	(zone
		(layer "In2.Cu")
		(hatch none 0.5)
		(connect_pads
			(clearance 0)
		)
		(min_thickness 0.25)
		(keepout
			(tracks not_allowed)
			(vias allowed)
			(pads allowed)
			(copperpour not_allowed)
			(footprints allowed)
		)
		(placement
			(enabled no)
			(sheetname "")
		)
		(fill
			(thermal_gap 0.5)
			(thermal_bridge_width 0.5)
			(island_removal_mode 0)
		)
		(polygon
			(pts
				(xy 171.22267 -202.17511) (xy 172.72127 -202.17511) (xy 172.72127 -202.695048) (xy 171.22267 -202.695048)
			)
		)
	)
	(zone
		(layer "In2.Cu")
		(hatch none 0.5)
		(connect_pads
			(clearance 0)
		)
		(min_thickness 0.25)
		(keepout
			(tracks not_allowed)
			(vias allowed)
			(pads allowed)
			(copperpour not_allowed)
			(footprints allowed)
		)
		(placement
			(enabled no)
			(sheetname "")
		)
		(fill
			(thermal_gap 0.5)
			(thermal_bridge_width 0.5)
			(island_removal_mode 0)
		)
		(polygon
			(pts
				(xy 283.986732 -270.175228) (xy 285.485332 -270.175228) (xy 285.485332 -270.695166) (xy 283.986732 -270.695166)
			)
		)
	)
	(zone
		(layer "In2.Cu")
		(hatch none 0.5)
		(connect_pads
			(clearance 0)
		)
		(min_thickness 0.25)
		(keepout
			(tracks allowed)
			(vias allowed)
			(pads allowed)
			(copperpour allowed)
			(footprints allowed)
		)
		(placement
			(enabled no)
			(sheetname "")
		)
		(fill
			(thermal_gap 0.5)
			(thermal_bridge_width 0.5)
			(island_removal_mode 0)
		)
		(polygon
			(pts
				(xy 73.84161 -338.874608) (xy 73.84161 -338.252308) (xy 74.39279 -338.252308) (xy 74.39279 -338.874608)
			)
		)
	)
	(zone
		(layer "In2.Cu")
		(hatch none 0.5)
		(connect_pads
			(clearance 0)
		)
		(min_thickness 0.25)
		(keepout
			(tracks not_allowed)
			(vias allowed)
			(pads allowed)
			(copperpour not_allowed)
			(footprints allowed)
		)
		(placement
			(enabled no)
			(sheetname "")
		)
		(fill
			(thermal_gap 0.5)
			(thermal_bridge_width 0.5)
			(island_removal_mode 0)
		)
		(polygon
			(pts
				(arc
					(start 344.223594 -384.288284)
					(mid 344.243518 -384.29752)
					(end 344.26525 -384.30073)
				)
				(arc
					(start 344.459814 -384.30073)
					(mid 344.513696 -384.278412)
					(end 344.536014 -384.22453)
				)
				(arc
					(start 344.536014 -383.53873)
					(mid 344.513696 -383.484848)
					(end 344.459814 -383.46253)
				)
				(arc
					(start 344.26525 -383.46253)
					(mid 344.243506 -383.465698)
					(end 344.223594 -383.474976)
				)
				(arc
					(start 343.92743 -383.667762)
					(mid 343.885746 -383.679984)
					(end 343.844118 -383.667508)
				)
				(arc
					(start 343.550494 -383.474976)
					(mid 343.53057 -383.46574)
					(end 343.508838 -383.46253)
				)
				(arc
					(start 343.314274 -383.46253)
					(mid 343.260392 -383.484848)
					(end 343.238074 -383.53873)
				)
				(arc
					(start 343.238074 -384.22453)
					(mid 343.260392 -384.278412)
					(end 343.314274 -384.30073)
				)
				(arc
					(start 343.510108 -384.30073)
					(mid 343.531852 -384.297562)
					(end 343.551764 -384.288284)
				)
				(arc
					(start 343.845388 -384.095752)
					(mid 343.887044 -384.08335)
					(end 343.9287 -384.095752)
				)
			)
		)
	)
	(zone
		(layer "In2.Cu")
		(hatch none 0.5)
		(connect_pads
			(clearance 0)
		)
		(min_thickness 0.25)
		(keepout
			(tracks not_allowed)
			(vias allowed)
			(pads allowed)
			(copperpour not_allowed)
			(footprints allowed)
		)
		(placement
			(enabled no)
			(sheetname "")
		)
		(fill
			(thermal_gap 0.5)
			(thermal_bridge_width 0.5)
			(island_removal_mode 0)
		)
		(polygon
			(pts
				(xy 287.430718 -291.425122) (xy 288.929318 -291.425122) (xy 288.929318 -291.94506) (xy 287.430718 -291.94506)
			)
		)
	)
	(zone
		(layer "In2.Cu")
		(hatch none 0.5)
		(connect_pads
			(clearance 0)
		)
		(min_thickness 0.25)
		(keepout
			(tracks not_allowed)
			(vias allowed)
			(pads allowed)
			(copperpour not_allowed)
			(footprints allowed)
		)
		(placement
			(enabled no)
			(sheetname "")
		)
		(fill
			(thermal_gap 0.5)
			(thermal_bridge_width 0.5)
			(island_removal_mode 0)
		)
		(polygon
			(pts
				(xy 28.50261 -223.425258) (xy 30.00121 -223.425258) (xy 30.00121 -223.945196) (xy 28.50261 -223.945196)
			)
		)
	)
	(zone
		(layer "In2.Cu")
		(hatch none 0.5)
		(connect_pads
			(clearance 0)
		)
		(min_thickness 0.25)
		(keepout
			(tracks not_allowed)
			(vias allowed)
			(pads allowed)
			(copperpour not_allowed)
			(footprints allowed)
		)
		(placement
			(enabled no)
			(sheetname "")
		)
		(fill
			(thermal_gap 0.5)
			(thermal_bridge_width 0.5)
			(island_removal_mode 0)
		)
		(polygon
			(pts
				(xy 272.342864 -282.075128) (xy 273.841464 -282.075128) (xy 273.841464 -282.595066) (xy 272.342864 -282.595066)
			)
		)
	)
	(zone
		(layer "In2.Cu")
		(hatch none 0.5)
		(connect_pads
			(clearance 0)
		)
		(min_thickness 0.25)
		(keepout
			(tracks not_allowed)
			(vias allowed)
			(pads allowed)
			(copperpour not_allowed)
			(footprints allowed)
		)
		(placement
			(enabled no)
			(sheetname "")
		)
		(fill
			(thermal_gap 0.5)
			(thermal_bridge_width 0.5)
			(island_removal_mode 0)
		)
		(polygon
			(pts
				(xy 190.410846 -293.975282) (xy 191.909446 -293.975282) (xy 191.909446 -294.49522) (xy 190.410846 -294.49522)
			)
		)
	)
	(zone
		(layer "In2.Cu")
		(hatch none 0.5)
		(connect_pads
			(clearance 0)
		)
		(min_thickness 0.25)
		(keepout
			(tracks not_allowed)
			(vias allowed)
			(pads allowed)
			(copperpour not_allowed)
			(footprints allowed)
		)
		(placement
			(enabled no)
			(sheetname "")
		)
		(fill
			(thermal_gap 0.5)
			(thermal_bridge_width 0.5)
			(island_removal_mode 0)
		)
		(polygon
			(pts
				(xy 193.854578 -294.825166) (xy 195.353178 -294.825166) (xy 195.353178 -295.345104) (xy 193.854578 -295.345104)
			)
		)
	)
	(zone
		(layer "In2.Cu")
		(hatch none 0.5)
		(connect_pads
			(clearance 0)
		)
		(min_thickness 0.25)
		(keepout
			(tracks not_allowed)
			(vias allowed)
			(pads allowed)
			(copperpour not_allowed)
			(footprints allowed)
		)
		(placement
			(enabled no)
			(sheetname "")
		)
		(fill
			(thermal_gap 0.5)
			(thermal_bridge_width 0.5)
			(island_removal_mode 0)
		)
		(polygon
			(pts
				(xy 47.034704 -251.47524) (xy 48.533304 -251.47524) (xy 48.533304 -251.995178) (xy 47.034704 -251.995178)
			)
		)
	)
	(zone
		(layer "In2.Cu")
		(hatch none 0.5)
		(connect_pads
			(clearance 0)
		)
		(min_thickness 0.25)
		(keepout
			(tracks not_allowed)
			(vias allowed)
			(pads allowed)
			(copperpour not_allowed)
			(footprints allowed)
		)
		(placement
			(enabled no)
			(sheetname "")
		)
		(fill
			(thermal_gap 0.5)
			(thermal_bridge_width 0.5)
			(island_removal_mode 0)
		)
		(polygon
			(pts
				(xy 430.80686 -220.025214) (xy 432.30546 -220.025214) (xy 432.30546 -220.545152) (xy 430.80686 -220.545152)
			)
		)
	)
	(zone
		(layer "In2.Cu")
		(hatch none 0.5)
		(connect_pads
			(clearance 0)
		)
		(min_thickness 0.25)
		(keepout
			(tracks not_allowed)
			(vias allowed)
			(pads allowed)
			(copperpour not_allowed)
			(footprints allowed)
		)
		(placement
			(enabled no)
			(sheetname "")
		)
		(fill
			(thermal_gap 0.5)
			(thermal_bridge_width 0.5)
			(island_removal_mode 0)
		)
		(polygon
			(pts
				(xy 163.678616 -299.075348) (xy 165.177216 -299.075348) (xy 165.177216 -299.595286) (xy 163.678616 -299.595286)
			)
		)
	)
	(zone
		(layer "In2.Cu")
		(hatch none 0.5)
		(connect_pads
			(clearance 0)
		)
		(min_thickness 0.25)
		(keepout
			(tracks allowed)
			(vias allowed)
			(pads allowed)
			(copperpour allowed)
			(footprints allowed)
		)
		(placement
			(enabled no)
			(sheetname "")
		)
		(fill
			(thermal_gap 0.5)
			(thermal_bridge_width 0.5)
			(island_removal_mode 0)
		)
		(polygon
			(pts
				(xy 286.24657 -350.590866) (xy 286.24657 -349.968566) (xy 286.79775 -349.968566) (xy 286.79775 -350.590866)
			)
		)
	)
	(zone
		(layer "In2.Cu")
		(hatch none 0.5)
		(connect_pads
			(clearance 0)
		)
		(min_thickness 0.25)
		(keepout
			(tracks not_allowed)
			(vias allowed)
			(pads allowed)
			(copperpour not_allowed)
			(footprints allowed)
		)
		(placement
			(enabled no)
			(sheetname "")
		)
		(fill
			(thermal_gap 0.5)
			(thermal_bridge_width 0.5)
			(island_removal_mode 0)
		)
		(polygon
			(pts
				(xy 430.80686 -292.27526) (xy 432.30546 -292.27526) (xy 432.30546 -292.795198) (xy 430.80686 -292.795198)
			)
		)
	)
	(zone
		(layer "In2.Cu")
		(hatch none 0.5)
		(connect_pads
			(clearance 0)
		)
		(min_thickness 0.25)
		(keepout
			(tracks not_allowed)
			(vias allowed)
			(pads allowed)
			(copperpour not_allowed)
			(footprints allowed)
		)
		(placement
			(enabled no)
			(sheetname "")
		)
		(fill
			(thermal_gap 0.5)
			(thermal_bridge_width 0.5)
			(island_removal_mode 0)
		)
		(polygon
			(pts
				(xy 186.310778 -313.525154) (xy 187.809378 -313.525154) (xy 187.809378 -314.045092) (xy 186.310778 -314.045092)
			)
		)
	)
	(zone
		(layer "In2.Cu")
		(hatch none 0.5)
		(connect_pads
			(clearance 0)
		)
		(min_thickness 0.25)
		(keepout
			(tracks not_allowed)
			(vias allowed)
			(pads allowed)
			(copperpour not_allowed)
			(footprints allowed)
		)
		(placement
			(enabled no)
			(sheetname "")
		)
		(fill
			(thermal_gap 0.5)
			(thermal_bridge_width 0.5)
			(island_removal_mode 0)
		)
		(polygon
			(pts
				(xy 175.322738 -277.8252) (xy 176.821338 -277.8252) (xy 176.821338 -278.345138) (xy 175.322738 -278.345138)
			)
		)
	)
	(zone
		(layer "In2.Cu")
		(hatch none 0.5)
		(connect_pads
			(clearance 0)
		)
		(min_thickness 0.25)
		(keepout
			(tracks not_allowed)
			(vias allowed)
			(pads allowed)
			(copperpour not_allowed)
			(footprints allowed)
		)
		(placement
			(enabled no)
			(sheetname "")
		)
		(fill
			(thermal_gap 0.5)
			(thermal_bridge_width 0.5)
			(island_removal_mode 0)
		)
		(polygon
			(pts
				(xy 28.50261 -304.17516) (xy 30.00121 -304.17516) (xy 30.00121 -304.695098) (xy 28.50261 -304.695098)
			)
		)
	)
	(zone
		(layer "In2.Cu")
		(hatch none 0.5)
		(connect_pads
			(clearance 0)
		)
		(min_thickness 0.25)
		(keepout
			(tracks not_allowed)
			(vias allowed)
			(pads allowed)
			(copperpour not_allowed)
			(footprints allowed)
		)
		(placement
			(enabled no)
			(sheetname "")
		)
		(fill
			(thermal_gap 0.5)
			(thermal_bridge_width 0.5)
			(island_removal_mode 0)
		)
		(polygon
			(pts
				(xy 415.718752 -265.9253) (xy 417.217352 -265.9253) (xy 417.217352 -266.445238) (xy 415.718752 -266.445238)
			)
		)
	)
	(zone
		(layer "In2.Cu")
		(hatch none 0.5)
		(connect_pads
			(clearance 0)
		)
		(min_thickness 0.25)
		(keepout
			(tracks not_allowed)
			(vias allowed)
			(pads allowed)
			(copperpour not_allowed)
			(footprints allowed)
		)
		(placement
			(enabled no)
			(sheetname "")
		)
		(fill
			(thermal_gap 0.5)
			(thermal_bridge_width 0.5)
			(island_removal_mode 0)
		)
		(polygon
			(pts
				(xy 287.430718 -268.475206) (xy 288.929318 -268.475206) (xy 288.929318 -268.995144) (xy 287.430718 -268.995144)
			)
		)
	)
	(zone
		(layer "In2.Cu")
		(hatch none 0.5)
		(connect_pads
			(clearance 0)
		)
		(min_thickness 0.25)
		(keepout
			(tracks not_allowed)
			(vias allowed)
			(pads allowed)
			(copperpour not_allowed)
			(footprints allowed)
		)
		(placement
			(enabled no)
			(sheetname "")
		)
		(fill
			(thermal_gap 0.5)
			(thermal_bridge_width 0.5)
			(island_removal_mode 0)
		)
		(polygon
			(pts
				(xy 171.22267 -210.67522) (xy 172.72127 -210.67522) (xy 172.72127 -211.195158) (xy 171.22267 -211.195158)
			)
		)
	)
	(zone
		(layer "In2.Cu")
		(hatch none 0.5)
		(connect_pads
			(clearance 0)
		)
		(min_thickness 0.25)
		(keepout
			(tracks not_allowed)
			(vias allowed)
			(pads allowed)
			(copperpour not_allowed)
			(footprints allowed)
		)
		(placement
			(enabled no)
			(sheetname "")
		)
		(fill
			(thermal_gap 0.5)
			(thermal_bridge_width 0.5)
			(island_removal_mode 0)
		)
		(polygon
			(pts
				(xy 36.046664 -225.12528) (xy 37.545264 -225.12528) (xy 37.545264 -225.645218) (xy 36.046664 -225.645218)
			)
		)
	)
	(zone
		(layer "In2.Cu")
		(hatch none 0.5)
		(connect_pads
			(clearance 0)
		)
		(min_thickness 0.25)
		(keepout
			(tracks not_allowed)
			(vias allowed)
			(pads allowed)
			(copperpour not_allowed)
			(footprints allowed)
		)
		(placement
			(enabled no)
			(sheetname "")
		)
		(fill
			(thermal_gap 0.5)
			(thermal_bridge_width 0.5)
			(island_removal_mode 0)
		)
		(polygon
			(pts
				(xy 58.678826 -232.775252) (xy 60.177426 -232.775252) (xy 60.177426 -233.29519) (xy 58.678826 -233.29519)
			)
		)
	)
	(zone
		(layer "In2.Cu")
		(hatch none 0.5)
		(connect_pads
			(clearance 0)
		)
		(min_thickness 0.25)
		(keepout
			(tracks allowed)
			(vias allowed)
			(pads allowed)
			(copperpour allowed)
			(footprints allowed)
		)
		(placement
			(enabled no)
			(sheetname "")
		)
		(fill
			(thermal_gap 0.5)
			(thermal_bridge_width 0.5)
			(island_removal_mode 0)
		)
		(polygon
			(pts
				(xy 51.66233 -350.433132) (xy 51.66233 -351.291652) (xy 51.44643 -351.291652) (xy 51.44643 -350.433132)
			)
		)
	)
	(zone
		(layer "In2.Cu")
		(hatch none 0.5)
		(connect_pads
			(clearance 0)
		)
		(min_thickness 0.25)
		(keepout
			(tracks not_allowed)
			(vias allowed)
			(pads allowed)
			(copperpour not_allowed)
			(footprints allowed)
		)
		(placement
			(enabled no)
			(sheetname "")
		)
		(fill
			(thermal_gap 0.5)
			(thermal_bridge_width 0.5)
			(island_removal_mode 0)
		)
		(polygon
			(pts
				(xy 430.80686 -301.625254) (xy 432.30546 -301.625254) (xy 432.30546 -302.145192) (xy 430.80686 -302.145192)
			)
		)
	)
	(zone
		(layer "In2.Cu")
		(hatch none 0.5)
		(connect_pads
			(clearance 0)
		)
		(min_thickness 0.25)
		(keepout
			(tracks not_allowed)
			(vias allowed)
			(pads allowed)
			(copperpour not_allowed)
			(footprints allowed)
		)
		(placement
			(enabled no)
			(sheetname "")
		)
		(fill
			(thermal_gap 0.5)
			(thermal_bridge_width 0.5)
			(island_removal_mode 0)
		)
		(polygon
			(pts
				(xy 268.898878 -245.52529) (xy 270.397478 -245.52529) (xy 270.397478 -246.045228) (xy 268.898878 -246.045228)
			)
		)
	)
	(zone
		(layer "In2.Cu")
		(hatch none 0.5)
		(connect_pads
			(clearance 0)
		)
		(min_thickness 0.25)
		(keepout
			(tracks not_allowed)
			(vias allowed)
			(pads allowed)
			(copperpour not_allowed)
			(footprints allowed)
		)
		(placement
			(enabled no)
			(sheetname "")
		)
		(fill
			(thermal_gap 0.5)
			(thermal_bridge_width 0.5)
			(island_removal_mode 0)
		)
		(polygon
			(pts
				(xy 175.322738 -231.07523) (xy 176.821338 -231.07523) (xy 176.821338 -231.595168) (xy 175.322738 -231.595168)
			)
		)
	)
	(zone
		(layer "In2.Cu")
		(hatch none 0.5)
		(connect_pads
			(clearance 0)
		)
		(min_thickness 0.25)
		(keepout
			(tracks not_allowed)
			(vias allowed)
			(pads allowed)
			(copperpour not_allowed)
			(footprints allowed)
		)
		(placement
			(enabled no)
			(sheetname "")
		)
		(fill
			(thermal_gap 0.5)
			(thermal_bridge_width 0.5)
			(island_removal_mode 0)
		)
		(polygon
			(pts
				(xy 445.894968 -292.27526) (xy 447.393568 -292.27526) (xy 447.393568 -292.795198) (xy 445.894968 -292.795198)
			)
		)
	)
	(zone
		(layer "In2.Cu")
		(hatch none 0.5)
		(connect_pads
			(clearance 0)
		)
		(min_thickness 0.25)
		(keepout
			(tracks not_allowed)
			(vias allowed)
			(pads allowed)
			(copperpour not_allowed)
			(footprints allowed)
		)
		(placement
			(enabled no)
			(sheetname "")
		)
		(fill
			(thermal_gap 0.5)
			(thermal_bridge_width 0.5)
			(island_removal_mode 0)
		)
		(polygon
			(pts
				(xy 24.402542 -205.575154) (xy 25.901142 -205.575154) (xy 25.901142 -206.095092) (xy 24.402542 -206.095092)
			)
		)
	)
	(zone
		(layer "In2.Cu")
		(hatch none 0.5)
		(connect_pads
			(clearance 0)
		)
		(min_thickness 0.25)
		(keepout
			(tracks not_allowed)
			(vias allowed)
			(pads allowed)
			(copperpour not_allowed)
			(footprints allowed)
		)
		(placement
			(enabled no)
			(sheetname "")
		)
		(fill
			(thermal_gap 0.5)
			(thermal_bridge_width 0.5)
			(island_removal_mode 0)
		)
		(polygon
			(pts
				(xy 415.718752 -238.725202) (xy 417.217352 -238.725202) (xy 417.217352 -239.24514) (xy 415.718752 -239.24514)
			)
		)
	)
	(zone
		(layer "In2.Cu")
		(hatch none 0.5)
		(connect_pads
			(clearance 0)
		)
		(min_thickness 0.25)
		(keepout
			(tracks not_allowed)
			(vias allowed)
			(pads allowed)
			(copperpour not_allowed)
			(footprints allowed)
		)
		(placement
			(enabled no)
			(sheetname "")
		)
		(fill
			(thermal_gap 0.5)
			(thermal_bridge_width 0.5)
			(island_removal_mode 0)
		)
		(polygon
			(pts
				(xy 197.954646 -303.325276) (xy 199.453246 -303.325276) (xy 199.453246 -303.845214) (xy 197.954646 -303.845214)
			)
		)
	)
	(zone
		(layer "In2.Cu")
		(hatch none 0.5)
		(connect_pads
			(clearance 0)
		)
		(min_thickness 0.25)
		(keepout
			(tracks not_allowed)
			(vias allowed)
			(pads allowed)
			(copperpour not_allowed)
			(footprints allowed)
		)
		(placement
			(enabled no)
			(sheetname "")
		)
		(fill
			(thermal_gap 0.5)
			(thermal_bridge_width 0.5)
			(island_removal_mode 0)
		)
		(polygon
			(pts
				(xy 54.578758 -314.375292) (xy 56.077358 -314.375292) (xy 56.077358 -314.89523) (xy 54.578758 -314.89523)
			)
		)
	)
	(zone
		(layer "In2.Cu")
		(hatch none 0.5)
		(connect_pads
			(clearance 0)
		)
		(min_thickness 0.25)
		(keepout
			(tracks not_allowed)
			(vias allowed)
			(pads allowed)
			(copperpour not_allowed)
			(footprints allowed)
		)
		(placement
			(enabled no)
			(sheetname "")
		)
		(fill
			(thermal_gap 0.5)
			(thermal_bridge_width 0.5)
			(island_removal_mode 0)
		)
		(polygon
			(pts
				(xy 302.518826 -239.57534) (xy 304.017426 -239.57534) (xy 304.017426 -240.095278) (xy 302.518826 -240.095278)
			)
		)
	)
	(zone
		(layer "In2.Cu")
		(hatch none 0.5)
		(connect_pads
			(clearance 0)
		)
		(min_thickness 0.25)
		(keepout
			(tracks not_allowed)
			(vias allowed)
			(pads allowed)
			(copperpour not_allowed)
			(footprints allowed)
		)
		(placement
			(enabled no)
			(sheetname "")
		)
		(fill
			(thermal_gap 0.5)
			(thermal_bridge_width 0.5)
			(island_removal_mode 0)
		)
		(polygon
			(pts
				(xy 419.162738 -246.375174) (xy 420.661338 -246.375174) (xy 420.661338 -246.895112) (xy 419.162738 -246.895112)
			)
		)
	)
	(zone
		(layer "In2.Cu")
		(hatch none 0.5)
		(connect_pads
			(clearance 0)
		)
		(min_thickness 0.25)
		(keepout
			(tracks not_allowed)
			(vias allowed)
			(pads allowed)
			(copperpour not_allowed)
			(footprints allowed)
		)
		(placement
			(enabled no)
			(sheetname "")
		)
		(fill
			(thermal_gap 0.5)
			(thermal_bridge_width 0.5)
			(island_removal_mode 0)
		)
		(polygon
			(pts
				(xy 190.410846 -254.025146) (xy 191.909446 -254.025146) (xy 191.909446 -254.545084) (xy 190.410846 -254.545084)
			)
		)
	)
	(zone
		(layer "In2.Cu")
		(hatch none 0.5)
		(connect_pads
			(clearance 0)
		)
		(min_thickness 0.25)
		(keepout
			(tracks not_allowed)
			(vias allowed)
			(pads allowed)
			(copperpour not_allowed)
			(footprints allowed)
		)
		(placement
			(enabled no)
			(sheetname "")
		)
		(fill
			(thermal_gap 0.5)
			(thermal_bridge_width 0.5)
			(island_removal_mode 0)
		)
		(polygon
			(pts
				(xy 302.518826 -246.375174) (xy 304.017426 -246.375174) (xy 304.017426 -246.895112) (xy 302.518826 -246.895112)
			)
		)
	)
	(zone
		(layer "In2.Cu")
		(hatch none 0.5)
		(connect_pads
			(clearance 0)
		)
		(min_thickness 0.25)
		(keepout
			(tracks not_allowed)
			(vias allowed)
			(pads allowed)
			(copperpour not_allowed)
			(footprints allowed)
		)
		(placement
			(enabled no)
			(sheetname "")
		)
		(fill
			(thermal_gap 0.5)
			(thermal_bridge_width 0.5)
			(island_removal_mode 0)
		)
		(polygon
			(pts
				(xy 423.262806 -285.475172) (xy 424.761406 -285.475172) (xy 424.761406 -285.99511) (xy 423.262806 -285.99511)
			)
		)
	)
	(zone
		(layer "In2.Cu")
		(hatch none 0.5)
		(connect_pads
			(clearance 0)
		)
		(min_thickness 0.25)
		(keepout
			(tracks not_allowed)
			(vias allowed)
			(pads allowed)
			(copperpour not_allowed)
			(footprints allowed)
		)
		(placement
			(enabled no)
			(sheetname "")
		)
		(fill
			(thermal_gap 0.5)
			(thermal_bridge_width 0.5)
			(island_removal_mode 0)
		)
		(polygon
			(pts
				(xy 434.250846 -227.675186) (xy 435.749446 -227.675186) (xy 435.749446 -228.195124) (xy 434.250846 -228.195124)
			)
		)
	)
	(zone
		(layer "In2.Cu")
		(hatch none 0.5)
		(connect_pads
			(clearance 0)
		)
		(min_thickness 0.25)
		(keepout
			(tracks not_allowed)
			(vias allowed)
			(pads allowed)
			(copperpour not_allowed)
			(footprints allowed)
		)
		(placement
			(enabled no)
			(sheetname "")
		)
		(fill
			(thermal_gap 0.5)
			(thermal_bridge_width 0.5)
			(island_removal_mode 0)
		)
		(polygon
			(pts
				(xy 411.618684 -317.775336) (xy 413.117284 -317.775336) (xy 413.117284 -318.295274) (xy 411.618684 -318.295274)
			)
		)
	)
	(zone
		(layer "In2.Cu")
		(hatch none 0.5)
		(connect_pads
			(clearance 0)
		)
		(min_thickness 0.25)
		(keepout
			(tracks not_allowed)
			(vias allowed)
			(pads allowed)
			(copperpour not_allowed)
			(footprints allowed)
		)
		(placement
			(enabled no)
			(sheetname "")
		)
		(fill
			(thermal_gap 0.5)
			(thermal_bridge_width 0.5)
			(island_removal_mode 0)
		)
		(polygon
			(pts
				(xy 167.778684 -275.275294) (xy 169.277284 -275.275294) (xy 169.277284 -275.795232) (xy 167.778684 -275.795232)
			)
		)
	)
	(zone
		(layer "In2.Cu")
		(hatch none 0.5)
		(connect_pads
			(clearance 0)
		)
		(min_thickness 0.25)
		(keepout
			(tracks not_allowed)
			(vias allowed)
			(pads allowed)
			(copperpour not_allowed)
			(footprints allowed)
		)
		(placement
			(enabled no)
			(sheetname "")
		)
		(fill
			(thermal_gap 0.5)
			(thermal_bridge_width 0.5)
			(island_removal_mode 0)
		)
		(polygon
			(pts
				(xy 47.034704 -278.675338) (xy 48.533304 -278.675338) (xy 48.533304 -279.195276) (xy 47.034704 -279.195276)
			)
		)
	)
	(zone
		(layer "In2.Cu")
		(hatch none 0.5)
		(connect_pads
			(clearance 0)
		)
		(min_thickness 0.25)
		(keepout
			(tracks not_allowed)
			(vias allowed)
			(pads allowed)
			(copperpour not_allowed)
			(footprints allowed)
		)
		(placement
			(enabled no)
			(sheetname "")
		)
		(fill
			(thermal_gap 0.5)
			(thermal_bridge_width 0.5)
			(island_removal_mode 0)
		)
		(polygon
			(pts
				(xy 186.310778 -304.17516) (xy 187.809378 -304.17516) (xy 187.809378 -304.695098) (xy 186.310778 -304.695098)
			)
		)
	)
	(zone
		(layer "In2.Cu")
		(hatch none 0.5)
		(connect_pads
			(clearance 0)
		)
		(min_thickness 0.25)
		(keepout
			(tracks not_allowed)
			(vias allowed)
			(pads allowed)
			(copperpour not_allowed)
			(footprints allowed)
		)
		(placement
			(enabled no)
			(sheetname "")
		)
		(fill
			(thermal_gap 0.5)
			(thermal_bridge_width 0.5)
			(island_removal_mode 0)
		)
		(polygon
			(pts
				(xy 279.886664 -222.57512) (xy 281.385264 -222.57512) (xy 281.385264 -223.095058) (xy 279.886664 -223.095058)
			)
		)
	)
	(zone
		(layer "In2.Cu")
		(hatch none 0.5)
		(connect_pads
			(clearance 0)
		)
		(min_thickness 0.25)
		(keepout
			(tracks not_allowed)
			(vias allowed)
			(pads allowed)
			(copperpour not_allowed)
			(footprints allowed)
		)
		(placement
			(enabled no)
			(sheetname "")
		)
		(fill
			(thermal_gap 0.5)
			(thermal_bridge_width 0.5)
			(island_removal_mode 0)
		)
		(polygon
			(pts
				(xy 419.162738 -238.725202) (xy 420.661338 -238.725202) (xy 420.661338 -239.24514) (xy 419.162738 -239.24514)
			)
		)
	)
	(zone
		(layer "In2.Cu")
		(hatch none 0.5)
		(connect_pads
			(clearance 0)
		)
		(min_thickness 0.25)
		(keepout
			(tracks not_allowed)
			(vias allowed)
			(pads allowed)
			(copperpour not_allowed)
			(footprints allowed)
		)
		(placement
			(enabled no)
			(sheetname "")
		)
		(fill
			(thermal_gap 0.5)
			(thermal_bridge_width 0.5)
			(island_removal_mode 0)
		)
		(polygon
			(pts
				(xy 268.898878 -228.525324) (xy 270.397478 -228.525324) (xy 270.397478 -229.045262) (xy 268.898878 -229.045262)
			)
		)
	)
	(zone
		(layer "In2.Cu")
		(hatch none 0.5)
		(connect_pads
			(clearance 0)
		)
		(min_thickness 0.25)
		(keepout
			(tracks not_allowed)
			(vias allowed)
			(pads allowed)
			(copperpour not_allowed)
			(footprints allowed)
		)
		(placement
			(enabled no)
			(sheetname "")
		)
		(fill
			(thermal_gap 0.5)
			(thermal_bridge_width 0.5)
			(island_removal_mode 0)
		)
		(polygon
			(pts
				(xy 193.854578 -283.77515) (xy 195.353178 -283.77515) (xy 195.353178 -284.295088) (xy 193.854578 -284.295088)
			)
		)
	)
	(zone
		(layer "In2.Cu")
		(hatch none 0.5)
		(connect_pads
			(clearance 0)
		)
		(min_thickness 0.25)
		(keepout
			(tracks not_allowed)
			(vias allowed)
			(pads allowed)
			(copperpour not_allowed)
			(footprints allowed)
		)
		(placement
			(enabled no)
			(sheetname "")
		)
		(fill
			(thermal_gap 0.5)
			(thermal_bridge_width 0.5)
			(island_removal_mode 0)
		)
		(polygon
			(pts
				(xy 438.350914 -276.125178) (xy 439.849514 -276.125178) (xy 439.849514 -276.645116) (xy 438.350914 -276.645116)
			)
		)
	)
	(zone
		(layer "In2.Cu")
		(hatch none 0.5)
		(connect_pads
			(clearance 0)
		)
		(min_thickness 0.25)
		(keepout
			(tracks not_allowed)
			(vias allowed)
			(pads allowed)
			(copperpour not_allowed)
			(footprints allowed)
		)
		(placement
			(enabled no)
			(sheetname "")
		)
		(fill
			(thermal_gap 0.5)
			(thermal_bridge_width 0.5)
			(island_removal_mode 0)
		)
		(polygon
			(pts
				(xy 16.858742 -311.825132) (xy 18.357342 -311.825132) (xy 18.357342 -312.34507) (xy 16.858742 -312.34507)
			)
		)
	)
	(zone
		(layer "In2.Cu")
		(hatch none 0.5)
		(connect_pads
			(clearance 0)
		)
		(min_thickness 0.25)
		(keepout
			(tracks not_allowed)
			(vias allowed)
			(pads allowed)
			(copperpour not_allowed)
			(footprints allowed)
		)
		(placement
			(enabled no)
			(sheetname "")
		)
		(fill
			(thermal_gap 0.5)
			(thermal_bridge_width 0.5)
			(island_removal_mode 0)
		)
		(polygon
			(pts
				(xy 445.894968 -270.175228) (xy 447.393568 -270.175228) (xy 447.393568 -270.695166) (xy 445.894968 -270.695166)
			)
		)
	)
	(zone
		(layer "In2.Cu")
		(hatch none 0.5)
		(connect_pads
			(clearance 0)
		)
		(min_thickness 0.25)
		(keepout
			(tracks not_allowed)
			(vias allowed)
			(pads allowed)
			(copperpour not_allowed)
			(footprints allowed)
		)
		(placement
			(enabled no)
			(sheetname "")
		)
		(fill
			(thermal_gap 0.5)
			(thermal_bridge_width 0.5)
			(island_removal_mode 0)
		)
		(polygon
			(pts
				(xy 415.718752 -299.925232) (xy 417.217352 -299.925232) (xy 417.217352 -300.44517) (xy 415.718752 -300.44517)
			)
		)
	)
	(zone
		(layer "In2.Cu")
		(hatch none 0.5)
		(connect_pads
			(clearance 0)
		)
		(min_thickness 0.25)
		(keepout
			(tracks not_allowed)
			(vias allowed)
			(pads allowed)
			(copperpour not_allowed)
			(footprints allowed)
		)
		(placement
			(enabled no)
			(sheetname "")
		)
		(fill
			(thermal_gap 0.5)
			(thermal_bridge_width 0.5)
			(island_removal_mode 0)
		)
		(polygon
			(pts
				(xy 449.3387 -241.275108) (xy 450.8373 -241.275108) (xy 450.8373 -241.795046) (xy 449.3387 -241.795046)
			)
		)
	)
	(zone
		(layer "In2.Cu")
		(hatch none 0.5)
		(connect_pads
			(clearance 0)
		)
		(min_thickness 0.25)
		(keepout
			(tracks not_allowed)
			(vias allowed)
			(pads allowed)
			(copperpour not_allowed)
			(footprints allowed)
		)
		(placement
			(enabled no)
			(sheetname "")
		)
		(fill
			(thermal_gap 0.5)
			(thermal_bridge_width 0.5)
			(island_removal_mode 0)
		)
		(polygon
			(pts
				(xy 190.410846 -198.77532) (xy 191.909446 -198.77532) (xy 191.909446 -199.295258) (xy 190.410846 -199.295258)
			)
		)
	)
	(zone
		(layer "In2.Cu")
		(hatch none 0.5)
		(connect_pads
			(clearance 0)
		)
		(min_thickness 0.25)
		(keepout
			(tracks not_allowed)
			(vias allowed)
			(pads allowed)
			(copperpour not_allowed)
			(footprints allowed)
		)
		(placement
			(enabled no)
			(sheetname "")
		)
		(fill
			(thermal_gap 0.5)
			(thermal_bridge_width 0.5)
			(island_removal_mode 0)
		)
		(polygon
			(pts
				(xy 171.22267 -266.775184) (xy 172.72127 -266.775184) (xy 172.72127 -267.295122) (xy 171.22267 -267.295122)
			)
		)
	)
	(zone
		(layer "In2.Cu")
		(hatch none 0.5)
		(connect_pads
			(clearance 0)
		)
		(min_thickness 0.25)
		(keepout
			(tracks not_allowed)
			(vias allowed)
			(pads allowed)
			(copperpour not_allowed)
			(footprints allowed)
		)
		(placement
			(enabled no)
			(sheetname "")
		)
		(fill
			(thermal_gap 0.5)
			(thermal_bridge_width 0.5)
			(island_removal_mode 0)
		)
		(polygon
			(pts
				(xy 294.974772 -220.025214) (xy 296.473372 -220.025214) (xy 296.473372 -220.545152) (xy 294.974772 -220.545152)
			)
		)
	)
	(zone
		(layer "In2.Cu")
		(hatch none 0.5)
		(connect_pads
			(clearance 0)
		)
		(min_thickness 0.25)
		(keepout
			(tracks not_allowed)
			(vias allowed)
			(pads allowed)
			(copperpour not_allowed)
			(footprints allowed)
		)
		(placement
			(enabled no)
			(sheetname "")
		)
		(fill
			(thermal_gap 0.5)
			(thermal_bridge_width 0.5)
			(island_removal_mode 0)
		)
		(polygon
			(pts
				(xy 193.854578 -286.32531) (xy 195.353178 -286.32531) (xy 195.353178 -286.845248) (xy 193.854578 -286.845248)
			)
		)
	)
	(zone
		(layer "In2.Cu")
		(hatch none 0.5)
		(connect_pads
			(clearance 0)
		)
		(min_thickness 0.25)
		(keepout
			(tracks not_allowed)
			(vias allowed)
			(pads allowed)
			(copperpour not_allowed)
			(footprints allowed)
		)
		(placement
			(enabled no)
			(sheetname "")
		)
		(fill
			(thermal_gap 0.5)
			(thermal_bridge_width 0.5)
			(island_removal_mode 0)
		)
		(polygon
			(pts
				(xy 291.530786 -293.975282) (xy 293.029386 -293.975282) (xy 293.029386 -294.49522) (xy 291.530786 -294.49522)
			)
		)
	)
	(zone
		(layer "In2.Cu")
		(hatch none 0.5)
		(connect_pads
			(clearance 0)
		)
		(min_thickness 0.25)
		(keepout
			(tracks not_allowed)
			(vias allowed)
			(pads allowed)
			(copperpour not_allowed)
			(footprints allowed)
		)
		(placement
			(enabled no)
			(sheetname "")
		)
		(fill
			(thermal_gap 0.5)
			(thermal_bridge_width 0.5)
			(island_removal_mode 0)
		)
		(polygon
			(pts
				(xy 171.22267 -205.575154) (xy 172.72127 -205.575154) (xy 172.72127 -206.095092) (xy 171.22267 -206.095092)
			)
		)
	)
	(zone
		(layer "In2.Cu")
		(hatch none 0.5)
		(connect_pads
			(clearance 0)
		)
		(min_thickness 0.25)
		(keepout
			(tracks not_allowed)
			(vias allowed)
			(pads allowed)
			(copperpour not_allowed)
			(footprints allowed)
		)
		(placement
			(enabled no)
			(sheetname "")
		)
		(fill
			(thermal_gap 0.5)
			(thermal_bridge_width 0.5)
			(island_removal_mode 0)
		)
		(polygon
			(pts
				(xy 16.858742 -244.675152) (xy 18.357342 -244.675152) (xy 18.357342 -245.19509) (xy 16.858742 -245.19509)
			)
		)
	)
	(zone
		(layer "In2.Cu")
		(hatch none 0.5)
		(connect_pads
			(clearance 0)
		)
		(min_thickness 0.25)
		(keepout
			(tracks not_allowed)
			(vias allowed)
			(pads allowed)
			(copperpour not_allowed)
			(footprints allowed)
		)
		(placement
			(enabled no)
			(sheetname "")
		)
		(fill
			(thermal_gap 0.5)
			(thermal_bridge_width 0.5)
			(island_removal_mode 0)
		)
		(polygon
			(pts
				(xy 13.54074 -16.036036) (xy 13.54074 -14.609318) (xy 14.201394 -14.609318) (xy 14.201394 -16.036036)
			)
		)
	)
	(zone
		(layer "In2.Cu")
		(hatch none 0.5)
		(connect_pads
			(clearance 0)
		)
		(min_thickness 0.25)
		(keepout
			(tracks not_allowed)
			(vias allowed)
			(pads allowed)
			(copperpour not_allowed)
			(footprints allowed)
		)
		(placement
			(enabled no)
			(sheetname "")
		)
		(fill
			(thermal_gap 0.5)
			(thermal_bridge_width 0.5)
			(island_removal_mode 0)
		)
		(polygon
			(pts
				(xy 279.886664 -308.425342) (xy 281.385264 -308.425342) (xy 281.385264 -308.94528) (xy 279.886664 -308.94528)
			)
		)
	)
	(zone
		(layer "In2.Cu")
		(hatch none 0.5)
		(connect_pads
			(clearance 0)
		)
		(min_thickness 0.25)
		(keepout
			(tracks not_allowed)
			(vias allowed)
			(pads allowed)
			(copperpour not_allowed)
			(footprints allowed)
		)
		(placement
			(enabled no)
			(sheetname "")
		)
		(fill
			(thermal_gap 0.5)
			(thermal_bridge_width 0.5)
			(island_removal_mode 0)
		)
		(polygon
			(pts
				(xy 140.955268 -15.82674) (xy 141.936216 -15.82674) (xy 141.936216 -17.27454) (xy 140.955268 -17.27454)
			)
		)
	)
	(zone
		(layer "In2.Cu")
		(hatch none 0.5)
		(connect_pads
			(clearance 0)
		)
		(min_thickness 0.25)
		(keepout
			(tracks not_allowed)
			(vias allowed)
			(pads allowed)
			(copperpour not_allowed)
			(footprints allowed)
		)
		(placement
			(enabled no)
			(sheetname "")
		)
		(fill
			(thermal_gap 0.5)
			(thermal_bridge_width 0.5)
			(island_removal_mode 0)
		)
		(polygon
			(pts
				(xy 287.430718 -230.225346) (xy 288.929318 -230.225346) (xy 288.929318 -230.745284) (xy 287.430718 -230.745284)
			)
		)
	)
	(zone
		(layer "In2.Cu")
		(hatch none 0.5)
		(connect_pads
			(clearance 0)
		)
		(min_thickness 0.25)
		(keepout
			(tracks not_allowed)
			(vias allowed)
			(pads allowed)
			(copperpour not_allowed)
			(footprints allowed)
		)
		(placement
			(enabled no)
			(sheetname "")
		)
		(fill
			(thermal_gap 0.5)
			(thermal_bridge_width 0.5)
			(island_removal_mode 0)
		)
		(polygon
			(pts
				(xy 434.250846 -254.025146) (xy 435.749446 -254.025146) (xy 435.749446 -254.545084) (xy 434.250846 -254.545084)
			)
		)
	)
	(zone
		(layer "In2.Cu")
		(hatch none 0.5)
		(connect_pads
			(clearance 0)
		)
		(min_thickness 0.25)
		(keepout
			(tracks not_allowed)
			(vias allowed)
			(pads allowed)
			(copperpour not_allowed)
			(footprints allowed)
		)
		(placement
			(enabled no)
			(sheetname "")
		)
		(fill
			(thermal_gap 0.5)
			(thermal_bridge_width 0.5)
			(island_removal_mode 0)
		)
		(polygon
			(pts
				(xy 51.134772 -305.875182) (xy 52.633372 -305.875182) (xy 52.633372 -306.39512) (xy 51.134772 -306.39512)
			)
		)
	)
	(zone
		(layer "In2.Cu")
		(hatch none 0.5)
		(connect_pads
			(clearance 0)
		)
		(min_thickness 0.25)
		(keepout
			(tracks not_allowed)
			(vias allowed)
			(pads allowed)
			(copperpour not_allowed)
			(footprints allowed)
		)
		(placement
			(enabled no)
			(sheetname "")
		)
		(fill
			(thermal_gap 0.5)
			(thermal_bridge_width 0.5)
			(island_removal_mode 0)
		)
		(polygon
			(pts
				(xy 28.50261 -299.925232) (xy 30.00121 -299.925232) (xy 30.00121 -300.44517) (xy 28.50261 -300.44517)
			)
		)
	)
	(zone
		(layer "In2.Cu")
		(hatch none 0.5)
		(connect_pads
			(clearance 0)
		)
		(min_thickness 0.25)
		(keepout
			(tracks not_allowed)
			(vias allowed)
			(pads allowed)
			(copperpour not_allowed)
			(footprints allowed)
		)
		(placement
			(enabled no)
			(sheetname "")
		)
		(fill
			(thermal_gap 0.5)
			(thermal_bridge_width 0.5)
			(island_removal_mode 0)
		)
		(polygon
			(pts
				(xy 201.398632 -237.02518) (xy 202.897232 -237.02518) (xy 202.897232 -237.545118) (xy 201.398632 -237.545118)
			)
		)
	)
	(zone
		(layer "In2.Cu")
		(hatch none 0.5)
		(connect_pads
			(clearance 0)
		)
		(min_thickness 0.25)
		(keepout
			(tracks not_allowed)
			(vias allowed)
			(pads allowed)
			(copperpour not_allowed)
			(footprints allowed)
		)
		(placement
			(enabled no)
			(sheetname "")
		)
		(fill
			(thermal_gap 0.5)
			(thermal_bridge_width 0.5)
			(island_removal_mode 0)
		)
		(polygon
			(pts
				(xy 24.402542 -201.325226) (xy 25.901142 -201.325226) (xy 25.901142 -201.845164) (xy 24.402542 -201.845164)
			)
		)
	)
	(zone
		(layer "In2.Cu")
		(hatch none 0.5)
		(connect_pads
			(clearance 0)
		)
		(min_thickness 0.25)
		(keepout
			(tracks not_allowed)
			(vias allowed)
			(pads allowed)
			(copperpour not_allowed)
			(footprints allowed)
		)
		(placement
			(enabled no)
			(sheetname "")
		)
		(fill
			(thermal_gap 0.5)
			(thermal_bridge_width 0.5)
			(island_removal_mode 0)
		)
		(polygon
			(pts
				(xy 20.95881 -228.525324) (xy 22.45741 -228.525324) (xy 22.45741 -229.045262) (xy 20.95881 -229.045262)
			)
		)
	)
	(zone
		(layer "In2.Cu")
		(hatch none 0.5)
		(connect_pads
			(clearance 0)
		)
		(min_thickness 0.25)
		(keepout
			(tracks not_allowed)
			(vias allowed)
			(pads allowed)
			(copperpour not_allowed)
			(footprints allowed)
		)
		(placement
			(enabled no)
			(sheetname "")
		)
		(fill
			(thermal_gap 0.5)
			(thermal_bridge_width 0.5)
			(island_removal_mode 0)
		)
		(polygon
			(pts
				(xy 201.398632 -197.925182) (xy 202.897232 -197.925182) (xy 202.897232 -198.44512) (xy 201.398632 -198.44512)
			)
		)
	)
	(zone
		(layer "In2.Cu")
		(hatch none 0.5)
		(connect_pads
			(clearance 0)
		)
		(min_thickness 0.25)
		(keepout
			(tracks not_allowed)
			(vias allowed)
			(pads allowed)
			(copperpour not_allowed)
			(footprints allowed)
		)
		(placement
			(enabled no)
			(sheetname "")
		)
		(fill
			(thermal_gap 0.5)
			(thermal_bridge_width 0.5)
			(island_removal_mode 0)
		)
		(polygon
			(pts
				(xy 276.442932 -310.975248) (xy 277.941532 -310.975248) (xy 277.941532 -311.495186) (xy 276.442932 -311.495186)
			)
		)
	)
	(zone
		(layer "In2.Cu")
		(hatch none 0.5)
		(connect_pads
			(clearance 0)
		)
		(min_thickness 0.25)
		(keepout
			(tracks not_allowed)
			(vias allowed)
			(pads allowed)
			(copperpour not_allowed)
			(footprints allowed)
		)
		(placement
			(enabled no)
			(sheetname "")
		)
		(fill
			(thermal_gap 0.5)
			(thermal_bridge_width 0.5)
			(island_removal_mode 0)
		)
		(polygon
			(pts
				(xy 175.322738 -223.425258) (xy 176.821338 -223.425258) (xy 176.821338 -223.945196) (xy 175.322738 -223.945196)
			)
		)
	)
	(zone
		(layer "In2.Cu")
		(hatch none 0.5)
		(connect_pads
			(clearance 0)
		)
		(min_thickness 0.25)
		(keepout
			(tracks not_allowed)
			(vias allowed)
			(pads allowed)
			(copperpour not_allowed)
			(footprints allowed)
		)
		(placement
			(enabled no)
			(sheetname "")
		)
		(fill
			(thermal_gap 0.5)
			(thermal_bridge_width 0.5)
			(island_removal_mode 0)
		)
		(polygon
			(pts
				(xy 294.974772 -286.32531) (xy 296.473372 -286.32531) (xy 296.473372 -286.845248) (xy 294.974772 -286.845248)
			)
		)
	)
	(zone
		(layer "In2.Cu")
		(hatch none 0.5)
		(connect_pads
			(clearance 0)
		)
		(min_thickness 0.25)
		(keepout
			(tracks not_allowed)
			(vias allowed)
			(pads allowed)
			(copperpour not_allowed)
			(footprints allowed)
		)
		(placement
			(enabled no)
			(sheetname "")
		)
		(fill
			(thermal_gap 0.5)
			(thermal_bridge_width 0.5)
			(island_removal_mode 0)
		)
		(polygon
			(pts
				(xy 279.886664 -261.675118) (xy 281.385264 -261.675118) (xy 281.385264 -262.195056) (xy 279.886664 -262.195056)
			)
		)
	)
	(zone
		(layer "In2.Cu")
		(hatch none 0.5)
		(connect_pads
			(clearance 0)
		)
		(min_thickness 0.25)
		(keepout
			(tracks not_allowed)
			(vias allowed)
			(pads allowed)
			(copperpour not_allowed)
			(footprints allowed)
		)
		(placement
			(enabled no)
			(sheetname "")
		)
		(fill
			(thermal_gap 0.5)
			(thermal_bridge_width 0.5)
			(island_removal_mode 0)
		)
		(polygon
			(pts
				(arc
					(start 34.874708 -17.966436)
					(mid 34.897026 -18.020318)
					(end 34.950908 -18.042636)
				)
				(arc
					(start 35.146488 -18.042636)
					(mid 35.168364 -18.039504)
					(end 35.188398 -18.03019)
				)
				(arc
					(start 35.482022 -17.837658)
					(mid 35.523678 -17.825256)
					(end 35.565334 -17.837658)
				)
				(arc
					(start 35.860228 -18.03019)
					(mid 35.880152 -18.039426)
					(end 35.901884 -18.042636)
				)
				(arc
					(start 36.096448 -18.042636)
					(mid 36.15033 -18.020318)
					(end 36.172648 -17.966436)
				)
				(arc
					(start 36.172648 -17.280636)
					(mid 36.15033 -17.226754)
					(end 36.096448 -17.204436)
				)
				(arc
					(start 35.901884 -17.204436)
					(mid 35.88014 -17.207604)
					(end 35.860228 -17.216882)
				)
				(arc
					(start 35.564064 -17.409668)
					(mid 35.52238 -17.42189)
					(end 35.480752 -17.409414)
				)
				(arc
					(start 35.187128 -17.216882)
					(mid 35.167204 -17.207646)
					(end 35.145472 -17.204436)
				)
				(arc
					(start 34.950908 -17.204436)
					(mid 34.897026 -17.226754)
					(end 34.874708 -17.280636)
				)
			)
		)
	)
	(zone
		(layer "In2.Cu")
		(hatch none 0.5)
		(connect_pads
			(clearance 0)
		)
		(min_thickness 0.25)
		(keepout
			(tracks not_allowed)
			(vias allowed)
			(pads allowed)
			(copperpour not_allowed)
			(footprints allowed)
		)
		(placement
			(enabled no)
			(sheetname "")
		)
		(fill
			(thermal_gap 0.5)
			(thermal_bridge_width 0.5)
			(island_removal_mode 0)
		)
		(polygon
			(pts
				(xy 171.22267 -248.075196) (xy 172.72127 -248.075196) (xy 172.72127 -248.595134) (xy 171.22267 -248.595134)
			)
		)
	)
	(zone
		(layer "In2.Cu")
		(hatch none 0.5)
		(connect_pads
			(clearance 0)
		)
		(min_thickness 0.25)
		(keepout
			(tracks not_allowed)
			(vias allowed)
			(pads allowed)
			(copperpour not_allowed)
			(footprints allowed)
		)
		(placement
			(enabled no)
			(sheetname "")
		)
		(fill
			(thermal_gap 0.5)
			(thermal_bridge_width 0.5)
			(island_removal_mode 0)
		)
		(polygon
			(pts
				(xy 171.22267 -308.425342) (xy 172.72127 -308.425342) (xy 172.72127 -308.94528) (xy 171.22267 -308.94528)
			)
		)
	)
	(zone
		(layer "In2.Cu")
		(hatch none 0.5)
		(connect_pads
			(clearance 0)
		)
		(min_thickness 0.25)
		(keepout
			(tracks not_allowed)
			(vias allowed)
			(pads allowed)
			(copperpour not_allowed)
			(footprints allowed)
		)
		(placement
			(enabled no)
			(sheetname "")
		)
		(fill
			(thermal_gap 0.5)
			(thermal_bridge_width 0.5)
			(island_removal_mode 0)
		)
		(polygon
			(pts
				(xy 268.898878 -313.525154) (xy 270.397478 -313.525154) (xy 270.397478 -314.045092) (xy 268.898878 -314.045092)
			)
		)
	)
	(zone
		(layer "In2.Cu")
		(hatch none 0.5)
		(connect_pads
			(clearance 0)
		)
		(min_thickness 0.25)
		(keepout
			(tracks not_allowed)
			(vias allowed)
			(pads allowed)
			(copperpour not_allowed)
			(footprints allowed)
		)
		(placement
			(enabled no)
			(sheetname "")
		)
		(fill
			(thermal_gap 0.5)
			(thermal_bridge_width 0.5)
			(island_removal_mode 0)
		)
		(polygon
			(pts
				(xy 426.706792 -282.075128) (xy 428.205392 -282.075128) (xy 428.205392 -282.595066) (xy 426.706792 -282.595066)
			)
		)
	)
	(zone
		(layer "In2.Cu")
		(hatch none 0.5)
		(connect_pads
			(clearance 0)
		)
		(min_thickness 0.25)
		(keepout
			(tracks not_allowed)
			(vias allowed)
			(pads allowed)
			(copperpour not_allowed)
			(footprints allowed)
		)
		(placement
			(enabled no)
			(sheetname "")
		)
		(fill
			(thermal_gap 0.5)
			(thermal_bridge_width 0.5)
			(island_removal_mode 0)
		)
		(polygon
			(pts
				(xy 445.894968 -301.625254) (xy 447.393568 -301.625254) (xy 447.393568 -302.145192) (xy 445.894968 -302.145192)
			)
		)
	)
	(zone
		(layer "In2.Cu")
		(hatch none 0.5)
		(connect_pads
			(clearance 0)
		)
		(min_thickness 0.25)
		(keepout
			(tracks not_allowed)
			(vias allowed)
			(pads allowed)
			(copperpour not_allowed)
			(footprints allowed)
		)
		(placement
			(enabled no)
			(sheetname "")
		)
		(fill
			(thermal_gap 0.5)
			(thermal_bridge_width 0.5)
			(island_removal_mode 0)
		)
		(polygon
			(pts
				(xy 163.678616 -294.825166) (xy 165.177216 -294.825166) (xy 165.177216 -295.345104) (xy 163.678616 -295.345104)
			)
		)
	)
	(zone
		(layer "In2.Cu")
		(hatch none 0.5)
		(connect_pads
			(clearance 0)
		)
		(min_thickness 0.25)
		(keepout
			(tracks not_allowed)
			(vias allowed)
			(pads allowed)
			(copperpour not_allowed)
			(footprints allowed)
		)
		(placement
			(enabled no)
			(sheetname "")
		)
		(fill
			(thermal_gap 0.5)
			(thermal_bridge_width 0.5)
			(island_removal_mode 0)
		)
		(polygon
			(pts
				(xy 276.442932 -247.225312) (xy 277.941532 -247.225312) (xy 277.941532 -247.74525) (xy 276.442932 -247.74525)
			)
		)
	)
	(zone
		(layer "In2.Cu")
		(hatch none 0.5)
		(connect_pads
			(clearance 0)
		)
		(min_thickness 0.25)
		(keepout
			(tracks not_allowed)
			(vias allowed)
			(pads allowed)
			(copperpour not_allowed)
			(footprints allowed)
		)
		(placement
			(enabled no)
			(sheetname "")
		)
		(fill
			(thermal_gap 0.5)
			(thermal_bridge_width 0.5)
			(island_removal_mode 0)
		)
		(polygon
			(pts
				(xy 419.162738 -202.17511) (xy 420.661338 -202.17511) (xy 420.661338 -202.695048) (xy 419.162738 -202.695048)
			)
		)
	)
	(zone
		(layer "In2.Cu")
		(hatch none 0.5)
		(connect_pads
			(clearance 0)
		)
		(min_thickness 0.25)
		(keepout
			(tracks not_allowed)
			(vias allowed)
			(pads allowed)
			(copperpour not_allowed)
			(footprints allowed)
		)
		(placement
			(enabled no)
			(sheetname "")
		)
		(fill
			(thermal_gap 0.5)
			(thermal_bridge_width 0.5)
			(island_removal_mode 0)
		)
		(polygon
			(pts
				(xy 453.438768 -220.025214) (xy 454.937368 -220.025214) (xy 454.937368 -220.545152) (xy 453.438768 -220.545152)
			)
		)
	)
	(zone
		(layer "In2.Cu")
		(hatch none 0.5)
		(connect_pads
			(clearance 0)
		)
		(min_thickness 0.25)
		(keepout
			(tracks not_allowed)
			(vias allowed)
			(pads allowed)
			(copperpour not_allowed)
			(footprints allowed)
		)
		(placement
			(enabled no)
			(sheetname "")
		)
		(fill
			(thermal_gap 0.5)
			(thermal_bridge_width 0.5)
			(island_removal_mode 0)
		)
		(polygon
			(pts
				(xy 36.046664 -282.925266) (xy 37.545264 -282.925266) (xy 37.545264 -283.445204) (xy 36.046664 -283.445204)
			)
		)
	)
	(zone
		(layer "In2.Cu")
		(hatch none 0.5)
		(connect_pads
			(clearance 0)
		)
		(min_thickness 0.25)
		(keepout
			(tracks not_allowed)
			(vias allowed)
			(pads allowed)
			(copperpour not_allowed)
			(footprints allowed)
		)
		(placement
			(enabled no)
			(sheetname "")
		)
		(fill
			(thermal_gap 0.5)
			(thermal_bridge_width 0.5)
			(island_removal_mode 0)
		)
		(polygon
			(pts
				(xy 287.430718 -208.975198) (xy 288.929318 -208.975198) (xy 288.929318 -209.495136) (xy 287.430718 -209.495136)
			)
		)
	)
	(zone
		(layer "In2.Cu")
		(hatch none 0.5)
		(connect_pads
			(clearance 0)
		)
		(min_thickness 0.25)
		(keepout
			(tracks not_allowed)
			(vias allowed)
			(pads allowed)
			(copperpour not_allowed)
			(footprints allowed)
		)
		(placement
			(enabled no)
			(sheetname "")
		)
		(fill
			(thermal_gap 0.5)
			(thermal_bridge_width 0.5)
			(island_removal_mode 0)
		)
		(polygon
			(pts
				(xy 272.342864 -211.525104) (xy 273.841464 -211.525104) (xy 273.841464 -212.045042) (xy 272.342864 -212.045042)
			)
		)
	)
	(zone
		(layer "In2.Cu")
		(hatch none 0.5)
		(connect_pads
			(clearance 0)
		)
		(min_thickness 0.25)
		(keepout
			(tracks not_allowed)
			(vias allowed)
			(pads allowed)
			(copperpour not_allowed)
			(footprints allowed)
		)
		(placement
			(enabled no)
			(sheetname "")
		)
		(fill
			(thermal_gap 0.5)
			(thermal_bridge_width 0.5)
			(island_removal_mode 0)
		)
		(polygon
			(pts
				(xy 186.310778 -237.02518) (xy 187.809378 -237.02518) (xy 187.809378 -237.545118) (xy 186.310778 -237.545118)
			)
		)
	)
	(zone
		(layer "In2.Cu")
		(hatch none 0.5)
		(connect_pads
			(clearance 0)
		)
		(min_thickness 0.25)
		(keepout
			(tracks not_allowed)
			(vias allowed)
			(pads allowed)
			(copperpour not_allowed)
			(footprints allowed)
		)
		(placement
			(enabled no)
			(sheetname "")
		)
		(fill
			(thermal_gap 0.5)
			(thermal_bridge_width 0.5)
			(island_removal_mode 0)
		)
		(polygon
			(pts
				(xy 302.518826 -283.77515) (xy 304.017426 -283.77515) (xy 304.017426 -284.295088) (xy 302.518826 -284.295088)
			)
		)
	)
	(zone
		(layer "In2.Cu")
		(hatch none 0.5)
		(connect_pads
			(clearance 0)
		)
		(min_thickness 0.25)
		(keepout
			(tracks not_allowed)
			(vias allowed)
			(pads allowed)
			(copperpour not_allowed)
			(footprints allowed)
		)
		(placement
			(enabled no)
			(sheetname "")
		)
		(fill
			(thermal_gap 0.5)
			(thermal_bridge_width 0.5)
			(island_removal_mode 0)
		)
		(polygon
			(pts
				(xy 411.618684 -235.325158) (xy 413.117284 -235.325158) (xy 413.117284 -235.845096) (xy 411.618684 -235.845096)
			)
		)
	)
	(zone
		(layer "In2.Cu")
		(hatch none 0.5)
		(connect_pads
			(clearance 0)
		)
		(min_thickness 0.25)
		(keepout
			(tracks not_allowed)
			(vias allowed)
			(pads allowed)
			(copperpour not_allowed)
			(footprints allowed)
		)
		(placement
			(enabled no)
			(sheetname "")
		)
		(fill
			(thermal_gap 0.5)
			(thermal_bridge_width 0.5)
			(island_removal_mode 0)
		)
		(polygon
			(pts
				(xy 36.046664 -221.725236) (xy 37.545264 -221.725236) (xy 37.545264 -222.245174) (xy 36.046664 -222.245174)
			)
		)
	)
	(zone
		(layer "In2.Cu")
		(hatch none 0.5)
		(connect_pads
			(clearance 0)
		)
		(min_thickness 0.25)
		(keepout
			(tracks not_allowed)
			(vias allowed)
			(pads allowed)
			(copperpour not_allowed)
			(footprints allowed)
		)
		(placement
			(enabled no)
			(sheetname "")
		)
		(fill
			(thermal_gap 0.5)
			(thermal_bridge_width 0.5)
			(island_removal_mode 0)
		)
		(polygon
			(pts
				(xy 20.95881 -210.67522) (xy 22.45741 -210.67522) (xy 22.45741 -211.195158) (xy 20.95881 -211.195158)
			)
		)
	)
	(zone
		(layer "In2.Cu")
		(hatch none 0.5)
		(connect_pads
			(clearance 0)
		)
		(min_thickness 0.25)
		(keepout
			(tracks not_allowed)
			(vias allowed)
			(pads allowed)
			(copperpour not_allowed)
			(footprints allowed)
		)
		(placement
			(enabled no)
			(sheetname "")
		)
		(fill
			(thermal_gap 0.5)
			(thermal_bridge_width 0.5)
			(island_removal_mode 0)
		)
		(polygon
			(pts
				(xy 287.430718 -249.775218) (xy 288.929318 -249.775218) (xy 288.929318 -250.295156) (xy 287.430718 -250.295156)
			)
		)
	)
	(zone
		(layer "In2.Cu")
		(hatch none 0.5)
		(connect_pads
			(clearance 0)
		)
		(min_thickness 0.25)
		(keepout
			(tracks not_allowed)
			(vias allowed)
			(pads allowed)
			(copperpour not_allowed)
			(footprints allowed)
		)
		(placement
			(enabled no)
			(sheetname "")
		)
		(fill
			(thermal_gap 0.5)
			(thermal_bridge_width 0.5)
			(island_removal_mode 0)
		)
		(polygon
			(pts
				(xy 24.402542 -220.875098) (xy 25.901142 -220.875098) (xy 25.901142 -221.395036) (xy 24.402542 -221.395036)
			)
		)
	)
	(zone
		(layer "In2.Cu")
		(hatch none 0.5)
		(connect_pads
			(clearance 0)
		)
		(min_thickness 0.25)
		(keepout
			(tracks not_allowed)
			(vias allowed)
			(pads allowed)
			(copperpour not_allowed)
			(footprints allowed)
		)
		(placement
			(enabled no)
			(sheetname "")
		)
		(fill
			(thermal_gap 0.5)
			(thermal_bridge_width 0.5)
			(island_removal_mode 0)
		)
		(polygon
			(pts
				(xy 434.250846 -291.425122) (xy 435.749446 -291.425122) (xy 435.749446 -291.94506) (xy 434.250846 -291.94506)
			)
		)
	)
	(zone
		(layer "In2.Cu")
		(hatch none 0.5)
		(connect_pads
			(clearance 0)
		)
		(min_thickness 0.25)
		(keepout
			(tracks not_allowed)
			(vias allowed)
			(pads allowed)
			(copperpour not_allowed)
			(footprints allowed)
		)
		(placement
			(enabled no)
			(sheetname "")
		)
		(fill
			(thermal_gap 0.5)
			(thermal_bridge_width 0.5)
			(island_removal_mode 0)
		)
		(polygon
			(pts
				(xy 16.858742 -261.675118) (xy 18.357342 -261.675118) (xy 18.357342 -262.195056) (xy 16.858742 -262.195056)
			)
		)
	)
	(zone
		(layer "In2.Cu")
		(hatch none 0.5)
		(connect_pads
			(clearance 0)
		)
		(min_thickness 0.25)
		(keepout
			(tracks not_allowed)
			(vias allowed)
			(pads allowed)
			(copperpour not_allowed)
			(footprints allowed)
		)
		(placement
			(enabled no)
			(sheetname "")
		)
		(fill
			(thermal_gap 0.5)
			(thermal_bridge_width 0.5)
			(island_removal_mode 0)
		)
		(polygon
			(pts
				(xy 445.894968 -284.625288) (xy 447.393568 -284.625288) (xy 447.393568 -285.145226) (xy 445.894968 -285.145226)
			)
		)
	)
	(zone
		(layer "In2.Cu")
		(hatch none 0.5)
		(connect_pads
			(clearance 0)
		)
		(min_thickness 0.25)
		(keepout
			(tracks allowed)
			(vias allowed)
			(pads allowed)
			(copperpour allowed)
			(footprints allowed)
		)
		(placement
			(enabled no)
			(sheetname "")
		)
		(fill
			(thermal_gap 0.5)
			(thermal_bridge_width 0.5)
			(island_removal_mode 0)
		)
		(polygon
			(pts
				(xy 277.96617 -349.117666) (xy 277.96617 -348.495366) (xy 278.51735 -348.495366) (xy 278.51735 -349.117666)
			)
		)
	)
	(zone
		(layer "In2.Cu")
		(hatch none 0.5)
		(connect_pads
			(clearance 0)
		)
		(min_thickness 0.25)
		(keepout
			(tracks not_allowed)
			(vias allowed)
			(pads allowed)
			(copperpour not_allowed)
			(footprints allowed)
		)
		(placement
			(enabled no)
			(sheetname "")
		)
		(fill
			(thermal_gap 0.5)
			(thermal_bridge_width 0.5)
			(island_removal_mode 0)
		)
		(polygon
			(pts
				(xy 287.430718 -253.175262) (xy 288.929318 -253.175262) (xy 288.929318 -253.6952) (xy 287.430718 -253.6952)
			)
		)
	)
	(zone
		(layer "In2.Cu")
		(hatch none 0.5)
		(connect_pads
			(clearance 0)
		)
		(min_thickness 0.25)
		(keepout
			(tracks not_allowed)
			(vias allowed)
			(pads allowed)
			(copperpour not_allowed)
			(footprints allowed)
		)
		(placement
			(enabled no)
			(sheetname "")
		)
		(fill
			(thermal_gap 0.5)
			(thermal_bridge_width 0.5)
			(island_removal_mode 0)
		)
		(polygon
			(pts
				(xy 438.350914 -277.8252) (xy 439.849514 -277.8252) (xy 439.849514 -278.345138) (xy 438.350914 -278.345138)
			)
		)
	)
	(zone
		(layer "In2.Cu")
		(hatch none 0.5)
		(connect_pads
			(clearance 0)
		)
		(min_thickness 0.25)
		(keepout
			(tracks not_allowed)
			(vias allowed)
			(pads allowed)
			(copperpour not_allowed)
			(footprints allowed)
		)
		(placement
			(enabled no)
			(sheetname "")
		)
		(fill
			(thermal_gap 0.5)
			(thermal_bridge_width 0.5)
			(island_removal_mode 0)
		)
		(polygon
			(pts
				(xy 441.7949 -199.625204) (xy 443.2935 -199.625204) (xy 443.2935 -200.145142) (xy 441.7949 -200.145142)
			)
		)
	)
	(zone
		(layer "In2.Cu")
		(hatch none 0.5)
		(connect_pads
			(clearance 0)
		)
		(min_thickness 0.25)
		(keepout
			(tracks not_allowed)
			(vias allowed)
			(pads allowed)
			(copperpour not_allowed)
			(footprints allowed)
		)
		(placement
			(enabled no)
			(sheetname "")
		)
		(fill
			(thermal_gap 0.5)
			(thermal_bridge_width 0.5)
			(island_removal_mode 0)
		)
		(polygon
			(pts
				(xy 434.250846 -294.825166) (xy 435.749446 -294.825166) (xy 435.749446 -295.345104) (xy 434.250846 -295.345104)
			)
		)
	)
	(zone
		(layer "In2.Cu")
		(hatch none 0.5)
		(connect_pads
			(clearance 0)
		)
		(min_thickness 0.25)
		(keepout
			(tracks not_allowed)
			(vias allowed)
			(pads allowed)
			(copperpour not_allowed)
			(footprints allowed)
		)
		(placement
			(enabled no)
			(sheetname "")
		)
		(fill
			(thermal_gap 0.5)
			(thermal_bridge_width 0.5)
			(island_removal_mode 0)
		)
		(polygon
			(pts
				(xy 28.50261 -236.175296) (xy 30.00121 -236.175296) (xy 30.00121 -236.695234) (xy 28.50261 -236.695234)
			)
		)
	)
	(zone
		(layer "In2.Cu")
		(hatch none 0.5)
		(connect_pads
			(clearance 0)
		)
		(min_thickness 0.25)
		(keepout
			(tracks not_allowed)
			(vias allowed)
			(pads allowed)
			(copperpour not_allowed)
			(footprints allowed)
		)
		(placement
			(enabled no)
			(sheetname "")
		)
		(fill
			(thermal_gap 0.5)
			(thermal_bridge_width 0.5)
			(island_removal_mode 0)
		)
		(polygon
			(pts
				(xy 167.778684 -226.825302) (xy 169.277284 -226.825302) (xy 169.277284 -227.34524) (xy 167.778684 -227.34524)
			)
		)
	)
	(zone
		(layer "In2.Cu")
		(hatch none 0.5)
		(connect_pads
			(clearance 0)
		)
		(min_thickness 0.25)
		(keepout
			(tracks not_allowed)
			(vias allowed)
			(pads allowed)
			(copperpour not_allowed)
			(footprints allowed)
		)
		(placement
			(enabled no)
			(sheetname "")
		)
		(fill
			(thermal_gap 0.5)
			(thermal_bridge_width 0.5)
			(island_removal_mode 0)
		)
		(polygon
			(pts
				(xy 28.50261 -264.225278) (xy 30.00121 -264.225278) (xy 30.00121 -264.745216) (xy 28.50261 -264.745216)
			)
		)
	)
	(zone
		(layer "In2.Cu")
		(hatch none 0.5)
		(connect_pads
			(clearance 0)
		)
		(min_thickness 0.25)
		(keepout
			(tracks not_allowed)
			(vias allowed)
			(pads allowed)
			(copperpour not_allowed)
			(footprints allowed)
		)
		(placement
			(enabled no)
			(sheetname "")
		)
		(fill
			(thermal_gap 0.5)
			(thermal_bridge_width 0.5)
			(island_removal_mode 0)
		)
		(polygon
			(pts
				(xy 272.342864 -261.675118) (xy 273.841464 -261.675118) (xy 273.841464 -262.195056) (xy 272.342864 -262.195056)
			)
		)
	)
	(zone
		(layer "In2.Cu")
		(hatch none 0.5)
		(connect_pads
			(clearance 0)
		)
		(min_thickness 0.25)
		(keepout
			(tracks not_allowed)
			(vias allowed)
			(pads allowed)
			(copperpour not_allowed)
			(footprints allowed)
		)
		(placement
			(enabled no)
			(sheetname "")
		)
		(fill
			(thermal_gap 0.5)
			(thermal_bridge_width 0.5)
			(island_removal_mode 0)
		)
		(polygon
			(pts
				(xy 201.398632 -235.325158) (xy 202.897232 -235.325158) (xy 202.897232 -235.845096) (xy 201.398632 -235.845096)
			)
		)
	)
	(zone
		(layer "In2.Cu")
		(hatch none 0.5)
		(connect_pads
			(clearance 0)
		)
		(min_thickness 0.25)
		(keepout
			(tracks allowed)
			(vias allowed)
			(pads allowed)
			(copperpour allowed)
			(footprints allowed)
		)
		(placement
			(enabled no)
			(sheetname "")
		)
		(fill
			(thermal_gap 0.5)
			(thermal_bridge_width 0.5)
			(island_removal_mode 0)
		)
		(polygon
			(pts
				(xy 19.348958 -416.775138) (xy 18.82267 -416.775138) (xy 18.82267 -416.240722) (xy 19.348958 -416.240722)
			)
		)
	)
	(zone
		(layer "In2.Cu")
		(hatch none 0.5)
		(connect_pads
			(clearance 0)
		)
		(min_thickness 0.25)
		(keepout
			(tracks not_allowed)
			(vias allowed)
			(pads allowed)
			(copperpour not_allowed)
			(footprints allowed)
		)
		(placement
			(enabled no)
			(sheetname "")
		)
		(fill
			(thermal_gap 0.5)
			(thermal_bridge_width 0.5)
			(island_removal_mode 0)
		)
		(polygon
			(pts
				(xy 31.946596 -276.975316) (xy 33.445196 -276.975316) (xy 33.445196 -277.495254) (xy 31.946596 -277.495254)
			)
		)
	)
	(zone
		(layer "In2.Cu")
		(hatch none 0.5)
		(connect_pads
			(clearance 0)
		)
		(min_thickness 0.25)
		(keepout
			(tracks not_allowed)
			(vias allowed)
			(pads allowed)
			(copperpour not_allowed)
			(footprints allowed)
		)
		(placement
			(enabled no)
			(sheetname "")
		)
		(fill
			(thermal_gap 0.5)
			(thermal_bridge_width 0.5)
			(island_removal_mode 0)
		)
		(polygon
			(pts
				(xy 171.22267 -286.32531) (xy 172.72127 -286.32531) (xy 172.72127 -286.845248) (xy 171.22267 -286.845248)
			)
		)
	)
	(zone
		(layer "In2.Cu")
		(hatch none 0.5)
		(connect_pads
			(clearance 0)
		)
		(min_thickness 0.25)
		(keepout
			(tracks not_allowed)
			(vias allowed)
			(pads allowed)
			(copperpour not_allowed)
			(footprints allowed)
		)
		(placement
			(enabled no)
			(sheetname "")
		)
		(fill
			(thermal_gap 0.5)
			(thermal_bridge_width 0.5)
			(island_removal_mode 0)
		)
		(polygon
			(pts
				(xy 51.134772 -279.525222) (xy 52.633372 -279.525222) (xy 52.633372 -280.04516) (xy 51.134772 -280.04516)
			)
		)
	)
	(zone
		(layer "In2.Cu")
		(hatch none 0.5)
		(connect_pads
			(clearance 0)
		)
		(min_thickness 0.25)
		(keepout
			(tracks not_allowed)
			(vias allowed)
			(pads allowed)
			(copperpour not_allowed)
			(footprints allowed)
		)
		(placement
			(enabled no)
			(sheetname "")
		)
		(fill
			(thermal_gap 0.5)
			(thermal_bridge_width 0.5)
			(island_removal_mode 0)
		)
		(polygon
			(pts
				(xy 441.7949 -202.17511) (xy 443.2935 -202.17511) (xy 443.2935 -202.695048) (xy 441.7949 -202.695048)
			)
		)
	)
	(zone
		(layer "In2.Cu")
		(hatch none 0.5)
		(connect_pads
			(clearance 0)
		)
		(min_thickness 0.25)
		(keepout
			(tracks not_allowed)
			(vias allowed)
			(pads allowed)
			(copperpour not_allowed)
			(footprints allowed)
		)
		(placement
			(enabled no)
			(sheetname "")
		)
		(fill
			(thermal_gap 0.5)
			(thermal_bridge_width 0.5)
			(island_removal_mode 0)
		)
		(polygon
			(pts
				(xy 190.410846 -262.525256) (xy 191.909446 -262.525256) (xy 191.909446 -263.045194) (xy 190.410846 -263.045194)
			)
		)
	)
	(zone
		(layer "In2.Cu")
		(hatch none 0.5)
		(connect_pads
			(clearance 0)
		)
		(min_thickness 0.25)
		(keepout
			(tracks not_allowed)
			(vias allowed)
			(pads allowed)
			(copperpour not_allowed)
			(footprints allowed)
		)
		(placement
			(enabled no)
			(sheetname "")
		)
		(fill
			(thermal_gap 0.5)
			(thermal_bridge_width 0.5)
			(island_removal_mode 0)
		)
		(polygon
			(pts
				(xy 283.986732 -290.575238) (xy 285.485332 -290.575238) (xy 285.485332 -291.095176) (xy 283.986732 -291.095176)
			)
		)
	)
	(zone
		(layer "In2.Cu")
		(hatch none 0.5)
		(connect_pads
			(clearance 0)
		)
		(min_thickness 0.25)
		(keepout
			(tracks not_allowed)
			(vias allowed)
			(pads allowed)
			(copperpour not_allowed)
			(footprints allowed)
		)
		(placement
			(enabled no)
			(sheetname "")
		)
		(fill
			(thermal_gap 0.5)
			(thermal_bridge_width 0.5)
			(island_removal_mode 0)
		)
		(polygon
			(pts
				(xy 167.778684 -254.025146) (xy 169.277284 -254.025146) (xy 169.277284 -254.545084) (xy 167.778684 -254.545084)
			)
		)
	)
	(zone
		(layer "In2.Cu")
		(hatch none 0.5)
		(connect_pads
			(clearance 0)
		)
		(min_thickness 0.25)
		(keepout
			(tracks not_allowed)
			(vias allowed)
			(pads allowed)
			(copperpour not_allowed)
			(footprints allowed)
		)
		(placement
			(enabled no)
			(sheetname "")
		)
		(fill
			(thermal_gap 0.5)
			(thermal_bridge_width 0.5)
			(island_removal_mode 0)
		)
		(polygon
			(pts
				(xy 171.22267 -233.625136) (xy 172.72127 -233.625136) (xy 172.72127 -234.145074) (xy 171.22267 -234.145074)
			)
		)
	)
	(zone
		(layer "In2.Cu")
		(hatch none 0.5)
		(connect_pads
			(clearance 0)
		)
		(min_thickness 0.25)
		(keepout
			(tracks not_allowed)
			(vias allowed)
			(pads allowed)
			(copperpour not_allowed)
			(footprints allowed)
		)
		(placement
			(enabled no)
			(sheetname "")
		)
		(fill
			(thermal_gap 0.5)
			(thermal_bridge_width 0.5)
			(island_removal_mode 0)
		)
		(polygon
			(pts
				(xy 272.342864 -218.325192) (xy 273.841464 -218.325192) (xy 273.841464 -218.84513) (xy 272.342864 -218.84513)
			)
		)
	)
	(zone
		(layer "In2.Cu")
		(hatch none 0.5)
		(connect_pads
			(clearance 0)
		)
		(min_thickness 0.25)
		(keepout
			(tracks not_allowed)
			(vias allowed)
			(pads allowed)
			(copperpour not_allowed)
			(footprints allowed)
		)
		(placement
			(enabled no)
			(sheetname "")
		)
		(fill
			(thermal_gap 0.5)
			(thermal_bridge_width 0.5)
			(island_removal_mode 0)
		)
		(polygon
			(pts
				(xy 24.402542 -197.925182) (xy 25.901142 -197.925182) (xy 25.901142 -198.44512) (xy 24.402542 -198.44512)
			)
		)
	)
	(zone
		(layer "In2.Cu")
		(hatch none 0.5)
		(connect_pads
			(clearance 0)
		)
		(min_thickness 0.25)
		(keepout
			(tracks not_allowed)
			(vias allowed)
			(pads allowed)
			(copperpour not_allowed)
			(footprints allowed)
		)
		(placement
			(enabled no)
			(sheetname "")
		)
		(fill
			(thermal_gap 0.5)
			(thermal_bridge_width 0.5)
			(island_removal_mode 0)
		)
		(polygon
			(pts
				(xy 287.430718 -295.675304) (xy 288.929318 -295.675304) (xy 288.929318 -296.195242) (xy 287.430718 -296.195242)
			)
		)
	)
	(zone
		(layer "In2.Cu")
		(hatch none 0.5)
		(connect_pads
			(clearance 0)
		)
		(min_thickness 0.25)
		(keepout
			(tracks not_allowed)
			(vias allowed)
			(pads allowed)
			(copperpour not_allowed)
			(footprints allowed)
		)
		(placement
			(enabled no)
			(sheetname "")
		)
		(fill
			(thermal_gap 0.5)
			(thermal_bridge_width 0.5)
			(island_removal_mode 0)
		)
		(polygon
			(pts
				(xy 268.898878 -248.925334) (xy 270.397478 -248.925334) (xy 270.397478 -249.445272) (xy 268.898878 -249.445272)
			)
		)
	)
	(zone
		(layer "In2.Cu")
		(hatch none 0.5)
		(connect_pads
			(clearance 0)
		)
		(min_thickness 0.25)
		(keepout
			(tracks not_allowed)
			(vias allowed)
			(pads allowed)
			(copperpour not_allowed)
			(footprints allowed)
		)
		(placement
			(enabled no)
			(sheetname "")
		)
		(fill
			(thermal_gap 0.5)
			(thermal_bridge_width 0.5)
			(island_removal_mode 0)
		)
		(polygon
			(pts
				(xy 449.3387 -211.525104) (xy 450.8373 -211.525104) (xy 450.8373 -212.045042) (xy 449.3387 -212.045042)
			)
		)
	)
	(zone
		(layer "In2.Cu")
		(hatch none 0.5)
		(connect_pads
			(clearance 0)
		)
		(min_thickness 0.25)
		(keepout
			(tracks not_allowed)
			(vias allowed)
			(pads allowed)
			(copperpour not_allowed)
			(footprints allowed)
		)
		(placement
			(enabled no)
			(sheetname "")
		)
		(fill
			(thermal_gap 0.5)
			(thermal_bridge_width 0.5)
			(island_removal_mode 0)
		)
		(polygon
			(pts
				(xy 139.775184 -32.0167)
				(arc
					(start 139.775184 -32.156908)
					(mid 139.804393 -32.22679)
					(end 139.874498 -32.25546)
				)
				(arc
					(start 140.175742 -32.25546)
					(mid 140.245847 -32.22679)
					(end 140.275056 -32.156908)
				)
				(xy 140.275056 -32.0167) (xy 140.215112 -32.0167)
				(arc
					(start 140.215112 -31.447486)
					(mid 140.258611 -31.411117)
					(end 140.275056 -31.356808)
				)
				(arc
					(start 140.275056 -31.096712)
					(mid 140.258737 -31.04232)
					(end 140.215112 -31.006034)
				)
				(xy 140.215112 -30.43682) (xy 140.275056 -30.43682)
				(arc
					(start 140.275056 -30.296612)
					(mid 140.245847 -30.22673)
					(end 140.175742 -30.19806)
				)
				(arc
					(start 139.874498 -30.19806)
					(mid 139.804393 -30.22673)
					(end 139.775184 -30.296612)
				)
				(xy 139.775184 -30.43682) (xy 139.835128 -30.43682)
				(arc
					(start 139.835128 -31.006034)
					(mid 139.791629 -31.042403)
					(end 139.775184 -31.096712)
				)
				(arc
					(start 139.775184 -31.356808)
					(mid 139.791503 -31.4112)
					(end 139.835128 -31.447486)
				)
				(xy 139.835128 -32.0167)
			)
		)
	)
	(zone
		(layer "In2.Cu")
		(hatch none 0.5)
		(connect_pads
			(clearance 0)
		)
		(min_thickness 0.25)
		(keepout
			(tracks not_allowed)
			(vias allowed)
			(pads allowed)
			(copperpour not_allowed)
			(footprints allowed)
		)
		(placement
			(enabled no)
			(sheetname "")
		)
		(fill
			(thermal_gap 0.5)
			(thermal_bridge_width 0.5)
			(island_removal_mode 0)
		)
		(polygon
			(pts
				(xy 287.430718 -214.925148) (xy 288.929318 -214.925148) (xy 288.929318 -215.445086) (xy 287.430718 -215.445086)
			)
		)
	)
	(zone
		(layer "In2.Cu")
		(hatch none 0.5)
		(connect_pads
			(clearance 0)
		)
		(min_thickness 0.25)
		(keepout
			(tracks not_allowed)
			(vias allowed)
			(pads allowed)
			(copperpour not_allowed)
			(footprints allowed)
		)
		(placement
			(enabled no)
			(sheetname "")
		)
		(fill
			(thermal_gap 0.5)
			(thermal_bridge_width 0.5)
			(island_removal_mode 0)
		)
		(polygon
			(pts
				(xy 47.034704 -254.025146) (xy 48.533304 -254.025146) (xy 48.533304 -254.545084) (xy 47.034704 -254.545084)
			)
		)
	)
	(zone
		(layer "In2.Cu")
		(hatch none 0.5)
		(connect_pads
			(clearance 0)
		)
		(min_thickness 0.25)
		(keepout
			(tracks not_allowed)
			(vias allowed)
			(pads allowed)
			(copperpour not_allowed)
			(footprints allowed)
		)
		(placement
			(enabled no)
			(sheetname "")
		)
		(fill
			(thermal_gap 0.5)
			(thermal_bridge_width 0.5)
			(island_removal_mode 0)
		)
		(polygon
			(pts
				(xy 268.898878 -203.025248) (xy 270.397478 -203.025248) (xy 270.397478 -203.545186) (xy 268.898878 -203.545186)
			)
		)
	)
	(zone
		(layer "In2.Cu")
		(hatch none 0.5)
		(connect_pads
			(clearance 0)
		)
		(min_thickness 0.25)
		(keepout
			(tracks not_allowed)
			(vias allowed)
			(pads allowed)
			(copperpour not_allowed)
			(footprints allowed)
		)
		(placement
			(enabled no)
			(sheetname "")
		)
		(fill
			(thermal_gap 0.5)
			(thermal_bridge_width 0.5)
			(island_removal_mode 0)
		)
		(polygon
			(pts
				(xy 47.034704 -280.375106) (xy 48.533304 -280.375106) (xy 48.533304 -280.895044) (xy 47.034704 -280.895044)
			)
		)
	)
	(zone
		(layer "In2.Cu")
		(hatch none 0.5)
		(connect_pads
			(clearance 0)
		)
		(min_thickness 0.25)
		(keepout
			(tracks not_allowed)
			(vias allowed)
			(pads allowed)
			(copperpour not_allowed)
			(footprints allowed)
		)
		(placement
			(enabled no)
			(sheetname "")
		)
		(fill
			(thermal_gap 0.5)
			(thermal_bridge_width 0.5)
			(island_removal_mode 0)
		)
		(polygon
			(pts
				(xy 197.954646 -267.625322) (xy 199.453246 -267.625322) (xy 199.453246 -268.14526) (xy 197.954646 -268.14526)
			)
		)
	)
	(zone
		(layer "In2.Cu")
		(hatch none 0.5)
		(connect_pads
			(clearance 0)
		)
		(min_thickness 0.25)
		(keepout
			(tracks not_allowed)
			(vias allowed)
			(pads allowed)
			(copperpour not_allowed)
			(footprints allowed)
		)
		(placement
			(enabled no)
			(sheetname "")
		)
		(fill
			(thermal_gap 0.5)
			(thermal_bridge_width 0.5)
			(island_removal_mode 0)
		)
		(polygon
			(pts
				(xy 299.07484 -294.825166) (xy 300.57344 -294.825166) (xy 300.57344 -295.345104) (xy 299.07484 -295.345104)
			)
		)
	)
	(zone
		(layer "In2.Cu")
		(hatch none 0.5)
		(connect_pads
			(clearance 0)
		)
		(min_thickness 0.25)
		(keepout
			(tracks not_allowed)
			(vias allowed)
			(pads allowed)
			(copperpour not_allowed)
			(footprints allowed)
		)
		(placement
			(enabled no)
			(sheetname "")
		)
		(fill
			(thermal_gap 0.5)
			(thermal_bridge_width 0.5)
			(island_removal_mode 0)
		)
		(polygon
			(pts
				(xy 163.678616 -314.375292) (xy 165.177216 -314.375292) (xy 165.177216 -314.89523) (xy 163.678616 -314.89523)
			)
		)
	)
	(zone
		(layer "In2.Cu")
		(hatch none 0.5)
		(connect_pads
			(clearance 0)
		)
		(min_thickness 0.25)
		(keepout
			(tracks not_allowed)
			(vias allowed)
			(pads allowed)
			(copperpour not_allowed)
			(footprints allowed)
		)
		(placement
			(enabled no)
			(sheetname "")
		)
		(fill
			(thermal_gap 0.5)
			(thermal_bridge_width 0.5)
			(island_removal_mode 0)
		)
		(polygon
			(pts
				(xy 272.342864 -251.47524) (xy 273.841464 -251.47524) (xy 273.841464 -251.995178) (xy 272.342864 -251.995178)
			)
		)
	)
	(zone
		(layer "In2.Cu")
		(hatch none 0.5)
		(connect_pads
			(clearance 0)
		)
		(min_thickness 0.25)
		(keepout
			(tracks not_allowed)
			(vias allowed)
			(pads allowed)
			(copperpour not_allowed)
			(footprints allowed)
		)
		(placement
			(enabled no)
			(sheetname "")
		)
		(fill
			(thermal_gap 0.5)
			(thermal_bridge_width 0.5)
			(island_removal_mode 0)
		)
		(polygon
			(pts
				(xy 445.894968 -228.525324) (xy 447.393568 -228.525324) (xy 447.393568 -229.045262) (xy 445.894968 -229.045262)
			)
		)
	)
	(zone
		(layer "In2.Cu")
		(hatch none 0.5)
		(connect_pads
			(clearance 0)
		)
		(min_thickness 0.25)
		(keepout
			(tracks not_allowed)
			(vias allowed)
			(pads allowed)
			(copperpour not_allowed)
			(footprints allowed)
		)
		(placement
			(enabled no)
			(sheetname "")
		)
		(fill
			(thermal_gap 0.5)
			(thermal_bridge_width 0.5)
			(island_removal_mode 0)
		)
		(polygon
			(pts
				(xy 36.046664 -223.425258) (xy 37.545264 -223.425258) (xy 37.545264 -223.945196) (xy 36.046664 -223.945196)
			)
		)
	)
	(zone
		(layer "In2.Cu")
		(hatch none 0.5)
		(connect_pads
			(clearance 0)
		)
		(min_thickness 0.25)
		(keepout
			(tracks not_allowed)
			(vias allowed)
			(pads allowed)
			(copperpour not_allowed)
			(footprints allowed)
		)
		(placement
			(enabled no)
			(sheetname "")
		)
		(fill
			(thermal_gap 0.5)
			(thermal_bridge_width 0.5)
			(island_removal_mode 0)
		)
		(polygon
			(pts
				(xy 167.778684 -229.375208) (xy 169.277284 -229.375208) (xy 169.277284 -229.895146) (xy 167.778684 -229.895146)
			)
		)
	)
	(zone
		(layer "In2.Cu")
		(hatch none 0.5)
		(connect_pads
			(clearance 0)
		)
		(min_thickness 0.25)
		(keepout
			(tracks not_allowed)
			(vias allowed)
			(pads allowed)
			(copperpour not_allowed)
			(footprints allowed)
		)
		(placement
			(enabled no)
			(sheetname "")
		)
		(fill
			(thermal_gap 0.5)
			(thermal_bridge_width 0.5)
			(island_removal_mode 0)
		)
		(polygon
			(pts
				(xy 423.262806 -305.875182) (xy 424.761406 -305.875182) (xy 424.761406 -306.39512) (xy 423.262806 -306.39512)
			)
		)
	)
	(zone
		(layer "In2.Cu")
		(hatch none 0.5)
		(connect_pads
			(clearance 0)
		)
		(min_thickness 0.25)
		(keepout
			(tracks not_allowed)
			(vias allowed)
			(pads allowed)
			(copperpour not_allowed)
			(footprints allowed)
		)
		(placement
			(enabled no)
			(sheetname "")
		)
		(fill
			(thermal_gap 0.5)
			(thermal_bridge_width 0.5)
			(island_removal_mode 0)
		)
		(polygon
			(pts
				(xy 20.95881 -281.225244) (xy 22.45741 -281.225244) (xy 22.45741 -281.745182) (xy 20.95881 -281.745182)
			)
		)
	)
	(zone
		(layer "In2.Cu")
		(hatch none 0.5)
		(connect_pads
			(clearance 0)
		)
		(min_thickness 0.25)
		(keepout
			(tracks allowed)
			(vias allowed)
			(pads allowed)
			(copperpour allowed)
			(footprints allowed)
		)
		(placement
			(enabled no)
			(sheetname "")
		)
		(fill
			(thermal_gap 0.5)
			(thermal_bridge_width 0.5)
			(island_removal_mode 0)
		)
		(polygon
			(pts
				(xy 41.71315 -347.583252) (xy 41.71315 -348.507812) (xy 41.42359 -348.507812) (xy 41.42359 -347.583252)
			)
		)
	)
	(zone
		(layer "In2.Cu")
		(hatch none 0.5)
		(connect_pads
			(clearance 0)
		)
		(min_thickness 0.25)
		(keepout
			(tracks allowed)
			(vias allowed)
			(pads allowed)
			(copperpour allowed)
			(footprints allowed)
		)
		(placement
			(enabled no)
			(sheetname "")
		)
		(fill
			(thermal_gap 0.5)
			(thermal_bridge_width 0.5)
			(island_removal_mode 0)
		)
		(polygon
			(pts
				(xy 427.076616 -353.516184) (xy 427.076616 -352.893884) (xy 427.627796 -352.893884) (xy 427.627796 -353.516184)
			)
		)
	)
	(zone
		(layer "In2.Cu")
		(hatch none 0.5)
		(connect_pads
			(clearance 0)
		)
		(min_thickness 0.25)
		(keepout
			(tracks not_allowed)
			(vias allowed)
			(pads allowed)
			(copperpour not_allowed)
			(footprints allowed)
		)
		(placement
			(enabled no)
			(sheetname "")
		)
		(fill
			(thermal_gap 0.5)
			(thermal_bridge_width 0.5)
			(island_removal_mode 0)
		)
		(polygon
			(pts
				(xy 201.398632 -230.225346) (xy 202.897232 -230.225346) (xy 202.897232 -230.745284) (xy 201.398632 -230.745284)
			)
		)
	)
	(zone
		(layer "In2.Cu")
		(hatch none 0.5)
		(connect_pads
			(clearance 0)
		)
		(min_thickness 0.25)
		(keepout
			(tracks not_allowed)
			(vias allowed)
			(pads allowed)
			(copperpour not_allowed)
			(footprints allowed)
		)
		(placement
			(enabled no)
			(sheetname "")
		)
		(fill
			(thermal_gap 0.5)
			(thermal_bridge_width 0.5)
			(island_removal_mode 0)
		)
		(polygon
			(pts
				(xy 302.518826 -306.72532) (xy 304.017426 -306.72532) (xy 304.017426 -307.245258) (xy 302.518826 -307.245258)
			)
		)
	)
	(zone
		(layer "In2.Cu")
		(hatch none 0.5)
		(connect_pads
			(clearance 0)
		)
		(min_thickness 0.25)
		(keepout
			(tracks not_allowed)
			(vias allowed)
			(pads allowed)
			(copperpour not_allowed)
			(footprints allowed)
		)
		(placement
			(enabled no)
			(sheetname "")
		)
		(fill
			(thermal_gap 0.5)
			(thermal_bridge_width 0.5)
			(island_removal_mode 0)
		)
		(polygon
			(pts
				(xy 31.946596 -299.075348) (xy 33.445196 -299.075348) (xy 33.445196 -299.595286) (xy 31.946596 -299.595286)
			)
		)
	)
	(zone
		(layer "In2.Cu")
		(hatch none 0.5)
		(connect_pads
			(clearance 0)
		)
		(min_thickness 0.25)
		(keepout
			(tracks not_allowed)
			(vias allowed)
			(pads allowed)
			(copperpour not_allowed)
			(footprints allowed)
		)
		(placement
			(enabled no)
			(sheetname "")
		)
		(fill
			(thermal_gap 0.5)
			(thermal_bridge_width 0.5)
			(island_removal_mode 0)
		)
		(polygon
			(pts
				(xy 299.07484 -221.725236) (xy 300.57344 -221.725236) (xy 300.57344 -222.245174) (xy 299.07484 -222.245174)
			)
		)
	)
	(zone
		(layer "In2.Cu")
		(hatch none 0.5)
		(connect_pads
			(clearance 0)
		)
		(min_thickness 0.25)
		(keepout
			(tracks allowed)
			(vias allowed)
			(pads allowed)
			(copperpour allowed)
			(footprints allowed)
		)
		(placement
			(enabled no)
			(sheetname "")
		)
		(fill
			(thermal_gap 0.5)
			(thermal_bridge_width 0.5)
			(island_removal_mode 0)
		)
		(polygon
			(pts
				(xy 98.46945 -340.072218) (xy 98.46945 -339.449918) (xy 99.02063 -339.449918) (xy 99.02063 -340.072218)
			)
		)
	)
	(zone
		(layer "In2.Cu")
		(hatch none 0.5)
		(connect_pads
			(clearance 0)
		)
		(min_thickness 0.25)
		(keepout
			(tracks not_allowed)
			(vias allowed)
			(pads allowed)
			(copperpour not_allowed)
			(footprints allowed)
		)
		(placement
			(enabled no)
			(sheetname "")
		)
		(fill
			(thermal_gap 0.5)
			(thermal_bridge_width 0.5)
			(island_removal_mode 0)
		)
		(polygon
			(pts
				(xy 51.134772 -264.225278) (xy 52.633372 -264.225278) (xy 52.633372 -264.745216) (xy 51.134772 -264.745216)
			)
		)
	)
	(zone
		(layer "In2.Cu")
		(hatch none 0.5)
		(connect_pads
			(clearance 0)
		)
		(min_thickness 0.25)
		(keepout
			(tracks not_allowed)
			(vias allowed)
			(pads allowed)
			(copperpour not_allowed)
			(footprints allowed)
		)
		(placement
			(enabled no)
			(sheetname "")
		)
		(fill
			(thermal_gap 0.5)
			(thermal_bridge_width 0.5)
			(island_removal_mode 0)
		)
		(polygon
			(pts
				(xy 283.986732 -198.77532) (xy 285.485332 -198.77532) (xy 285.485332 -199.295258) (xy 283.986732 -199.295258)
			)
		)
	)
	(zone
		(layer "In2.Cu")
		(hatch none 0.5)
		(connect_pads
			(clearance 0)
		)
		(min_thickness 0.25)
		(keepout
			(tracks not_allowed)
			(vias allowed)
			(pads allowed)
			(copperpour not_allowed)
			(footprints allowed)
		)
		(placement
			(enabled no)
			(sheetname "")
		)
		(fill
			(thermal_gap 0.5)
			(thermal_bridge_width 0.5)
			(island_removal_mode 0)
		)
		(polygon
			(pts
				(xy 434.250846 -306.72532) (xy 435.749446 -306.72532) (xy 435.749446 -307.245258) (xy 434.250846 -307.245258)
			)
		)
	)
	(zone
		(layer "In2.Cu")
		(hatch none 0.5)
		(connect_pads
			(clearance 0)
		)
		(min_thickness 0.25)
		(keepout
			(tracks not_allowed)
			(vias allowed)
			(pads allowed)
			(copperpour not_allowed)
			(footprints allowed)
		)
		(placement
			(enabled no)
			(sheetname "")
		)
		(fill
			(thermal_gap 0.5)
			(thermal_bridge_width 0.5)
			(island_removal_mode 0)
		)
		(polygon
			(pts
				(xy 302.518826 -317.775336) (xy 304.017426 -317.775336) (xy 304.017426 -318.295274) (xy 302.518826 -318.295274)
			)
		)
	)
	(zone
		(layer "In2.Cu")
		(hatch none 0.5)
		(connect_pads
			(clearance 0)
		)
		(min_thickness 0.25)
		(keepout
			(tracks not_allowed)
			(vias allowed)
			(pads allowed)
			(copperpour not_allowed)
			(footprints allowed)
		)
		(placement
			(enabled no)
			(sheetname "")
		)
		(fill
			(thermal_gap 0.5)
			(thermal_bridge_width 0.5)
			(island_removal_mode 0)
		)
		(polygon
			(pts
				(xy 28.50261 -292.27526) (xy 30.00121 -292.27526) (xy 30.00121 -292.795198) (xy 28.50261 -292.795198)
			)
		)
	)
	(zone
		(layer "In2.Cu")
		(hatch none 0.5)
		(connect_pads
			(clearance 0)
		)
		(min_thickness 0.25)
		(keepout
			(tracks not_allowed)
			(vias allowed)
			(pads allowed)
			(copperpour not_allowed)
			(footprints allowed)
		)
		(placement
			(enabled no)
			(sheetname "")
		)
		(fill
			(thermal_gap 0.5)
			(thermal_bridge_width 0.5)
			(island_removal_mode 0)
		)
		(polygon
			(pts
				(xy 411.618684 -242.97513) (xy 413.117284 -242.97513) (xy 413.117284 -243.495068) (xy 411.618684 -243.495068)
			)
		)
	)
	(zone
		(layer "In2.Cu")
		(hatch none 0.5)
		(connect_pads
			(clearance 0)
		)
		(min_thickness 0.25)
		(keepout
			(tracks not_allowed)
			(vias allowed)
			(pads allowed)
			(copperpour not_allowed)
			(footprints allowed)
		)
		(placement
			(enabled no)
			(sheetname "")
		)
		(fill
			(thermal_gap 0.5)
			(thermal_bridge_width 0.5)
			(island_removal_mode 0)
		)
		(polygon
			(pts
				(arc
					(start 32.080708 -16.442436)
					(mid 32.103026 -16.496318)
					(end 32.156908 -16.518636)
				)
				(arc
					(start 32.352488 -16.518636)
					(mid 32.374364 -16.515504)
					(end 32.394398 -16.50619)
				)
				(arc
					(start 32.688022 -16.313658)
					(mid 32.729678 -16.301256)
					(end 32.771334 -16.313658)
				)
				(arc
					(start 33.066228 -16.50619)
					(mid 33.086152 -16.515426)
					(end 33.107884 -16.518636)
				)
				(arc
					(start 33.302448 -16.518636)
					(mid 33.35633 -16.496318)
					(end 33.378648 -16.442436)
				)
				(arc
					(start 33.378648 -15.756636)
					(mid 33.35633 -15.702754)
					(end 33.302448 -15.680436)
				)
				(arc
					(start 33.107884 -15.680436)
					(mid 33.08614 -15.683604)
					(end 33.066228 -15.692882)
				)
				(arc
					(start 32.770064 -15.885668)
					(mid 32.72838 -15.89789)
					(end 32.686752 -15.885414)
				)
				(arc
					(start 32.393128 -15.692882)
					(mid 32.373204 -15.683646)
					(end 32.351472 -15.680436)
				)
				(arc
					(start 32.156908 -15.680436)
					(mid 32.103026 -15.702754)
					(end 32.080708 -15.756636)
				)
			)
		)
	)
	(zone
		(layer "In2.Cu")
		(hatch none 0.5)
		(connect_pads
			(clearance 0)
		)
		(min_thickness 0.25)
		(keepout
			(tracks not_allowed)
			(vias allowed)
			(pads allowed)
			(copperpour not_allowed)
			(footprints allowed)
		)
		(placement
			(enabled no)
			(sheetname "")
		)
		(fill
			(thermal_gap 0.5)
			(thermal_bridge_width 0.5)
			(island_removal_mode 0)
		)
		(polygon
			(pts
				(xy 58.678826 -197.075298) (xy 60.177426 -197.075298) (xy 60.177426 -197.595236) (xy 58.678826 -197.595236)
			)
		)
	)
	(zone
		(layer "In2.Cu")
		(hatch none 0.5)
		(connect_pads
			(clearance 0)
		)
		(min_thickness 0.25)
		(keepout
			(tracks not_allowed)
			(vias allowed)
			(pads allowed)
			(copperpour not_allowed)
			(footprints allowed)
		)
		(placement
			(enabled no)
			(sheetname "")
		)
		(fill
			(thermal_gap 0.5)
			(thermal_bridge_width 0.5)
			(island_removal_mode 0)
		)
		(polygon
			(pts
				(xy 415.718752 -290.575238) (xy 417.217352 -290.575238) (xy 417.217352 -291.095176) (xy 415.718752 -291.095176)
			)
		)
	)
	(zone
		(layer "In2.Cu")
		(hatch none 0.5)
		(connect_pads
			(clearance 0)
		)
		(min_thickness 0.25)
		(keepout
			(tracks not_allowed)
			(vias allowed)
			(pads allowed)
			(copperpour not_allowed)
			(footprints allowed)
		)
		(placement
			(enabled no)
			(sheetname "")
		)
		(fill
			(thermal_gap 0.5)
			(thermal_bridge_width 0.5)
			(island_removal_mode 0)
		)
		(polygon
			(pts
				(xy 186.310778 -229.375208) (xy 187.809378 -229.375208) (xy 187.809378 -229.895146) (xy 186.310778 -229.895146)
			)
		)
	)
	(zone
		(layer "In2.Cu")
		(hatch none 0.5)
		(connect_pads
			(clearance 0)
		)
		(min_thickness 0.25)
		(keepout
			(tracks not_allowed)
			(vias allowed)
			(pads allowed)
			(copperpour not_allowed)
			(footprints allowed)
		)
		(placement
			(enabled no)
			(sheetname "")
		)
		(fill
			(thermal_gap 0.5)
			(thermal_bridge_width 0.5)
			(island_removal_mode 0)
		)
		(polygon
			(pts
				(xy 193.854578 -254.025146) (xy 195.353178 -254.025146) (xy 195.353178 -254.545084) (xy 193.854578 -254.545084)
			)
		)
	)
	(zone
		(layer "In2.Cu")
		(hatch none 0.5)
		(connect_pads
			(clearance 0)
		)
		(min_thickness 0.25)
		(keepout
			(tracks not_allowed)
			(vias allowed)
			(pads allowed)
			(copperpour not_allowed)
			(footprints allowed)
		)
		(placement
			(enabled no)
			(sheetname "")
		)
		(fill
			(thermal_gap 0.5)
			(thermal_bridge_width 0.5)
			(island_removal_mode 0)
		)
		(polygon
			(pts
				(xy 279.886664 -276.125178) (xy 281.385264 -276.125178) (xy 281.385264 -276.645116) (xy 279.886664 -276.645116)
			)
		)
	)
	(zone
		(layer "In2.Cu")
		(hatch none 0.5)
		(connect_pads
			(clearance 0)
		)
		(min_thickness 0.25)
		(keepout
			(tracks not_allowed)
			(vias allowed)
			(pads allowed)
			(copperpour not_allowed)
			(footprints allowed)
		)
		(placement
			(enabled no)
			(sheetname "")
		)
		(fill
			(thermal_gap 0.5)
			(thermal_bridge_width 0.5)
			(island_removal_mode 0)
		)
		(polygon
			(pts
				(xy 434.250846 -263.37514) (xy 435.749446 -263.37514) (xy 435.749446 -263.895078) (xy 434.250846 -263.895078)
			)
		)
	)
	(zone
		(layer "In2.Cu")
		(hatch none 0.5)
		(connect_pads
			(clearance 0)
		)
		(min_thickness 0.25)
		(keepout
			(tracks not_allowed)
			(vias allowed)
			(pads allowed)
			(copperpour not_allowed)
			(footprints allowed)
		)
		(placement
			(enabled no)
			(sheetname "")
		)
		(fill
			(thermal_gap 0.5)
			(thermal_bridge_width 0.5)
			(island_removal_mode 0)
		)
		(polygon
			(pts
				(xy 291.530786 -203.025248) (xy 293.029386 -203.025248) (xy 293.029386 -203.545186) (xy 291.530786 -203.545186)
			)
		)
	)
	(zone
		(layer "In2.Cu")
		(hatch none 0.5)
		(connect_pads
			(clearance 0)
		)
		(min_thickness 0.25)
		(keepout
			(tracks not_allowed)
			(vias allowed)
			(pads allowed)
			(copperpour not_allowed)
			(footprints allowed)
		)
		(placement
			(enabled no)
			(sheetname "")
		)
		(fill
			(thermal_gap 0.5)
			(thermal_bridge_width 0.5)
			(island_removal_mode 0)
		)
		(polygon
			(pts
				(xy 24.402542 -230.225346) (xy 25.901142 -230.225346) (xy 25.901142 -230.745284) (xy 24.402542 -230.745284)
			)
		)
	)
	(zone
		(layer "In2.Cu")
		(hatch none 0.5)
		(connect_pads
			(clearance 0)
		)
		(min_thickness 0.25)
		(keepout
			(tracks not_allowed)
			(vias allowed)
			(pads allowed)
			(copperpour not_allowed)
			(footprints allowed)
		)
		(placement
			(enabled no)
			(sheetname "")
		)
		(fill
			(thermal_gap 0.5)
			(thermal_bridge_width 0.5)
			(island_removal_mode 0)
		)
		(polygon
			(pts
				(xy 197.954646 -231.07523) (xy 199.453246 -231.07523) (xy 199.453246 -231.595168) (xy 197.954646 -231.595168)
			)
		)
	)
	(zone
		(layer "In2.Cu")
		(hatch none 0.5)
		(connect_pads
			(clearance 0)
		)
		(min_thickness 0.25)
		(keepout
			(tracks not_allowed)
			(vias allowed)
			(pads allowed)
			(copperpour not_allowed)
			(footprints allowed)
		)
		(placement
			(enabled no)
			(sheetname "")
		)
		(fill
			(thermal_gap 0.5)
			(thermal_bridge_width 0.5)
			(island_removal_mode 0)
		)
		(polygon
			(pts
				(xy 438.350914 -312.67527) (xy 439.849514 -312.67527) (xy 439.849514 -313.195208) (xy 438.350914 -313.195208)
			)
		)
	)
	(zone
		(layer "In2.Cu")
		(hatch none 0.5)
		(connect_pads
			(clearance 0)
		)
		(min_thickness 0.25)
		(keepout
			(tracks not_allowed)
			(vias allowed)
			(pads allowed)
			(copperpour not_allowed)
			(footprints allowed)
		)
		(placement
			(enabled no)
			(sheetname "")
		)
		(fill
			(thermal_gap 0.5)
			(thermal_bridge_width 0.5)
			(island_removal_mode 0)
		)
		(polygon
			(pts
				(xy 302.518826 -199.625204) (xy 304.017426 -199.625204) (xy 304.017426 -200.145142) (xy 302.518826 -200.145142)
			)
		)
	)
	(zone
		(layer "In2.Cu")
		(hatch none 0.5)
		(connect_pads
			(clearance 0)
		)
		(min_thickness 0.25)
		(keepout
			(tracks not_allowed)
			(vias allowed)
			(pads allowed)
			(copperpour not_allowed)
			(footprints allowed)
		)
		(placement
			(enabled no)
			(sheetname "")
		)
		(fill
			(thermal_gap 0.5)
			(thermal_bridge_width 0.5)
			(island_removal_mode 0)
		)
		(polygon
			(pts
				(xy 163.678616 -203.875132) (xy 165.177216 -203.875132) (xy 165.177216 -204.39507) (xy 163.678616 -204.39507)
			)
		)
	)
	(zone
		(layer "In2.Cu")
		(hatch none 0.5)
		(connect_pads
			(clearance 0)
		)
		(min_thickness 0.25)
		(keepout
			(tracks not_allowed)
			(vias allowed)
			(pads allowed)
			(copperpour not_allowed)
			(footprints allowed)
		)
		(placement
			(enabled no)
			(sheetname "")
		)
		(fill
			(thermal_gap 0.5)
			(thermal_bridge_width 0.5)
			(island_removal_mode 0)
		)
		(polygon
			(pts
				(xy 58.678826 -262.525256) (xy 60.177426 -262.525256) (xy 60.177426 -263.045194) (xy 58.678826 -263.045194)
			)
		)
	)
	(zone
		(layer "In2.Cu")
		(hatch none 0.5)
		(connect_pads
			(clearance 0)
		)
		(min_thickness 0.25)
		(keepout
			(tracks not_allowed)
			(vias allowed)
			(pads allowed)
			(copperpour not_allowed)
			(footprints allowed)
		)
		(placement
			(enabled no)
			(sheetname "")
		)
		(fill
			(thermal_gap 0.5)
			(thermal_bridge_width 0.5)
			(island_removal_mode 0)
		)
		(polygon
			(pts
				(xy 186.310778 -297.375326) (xy 187.809378 -297.375326) (xy 187.809378 -297.895264) (xy 186.310778 -297.895264)
			)
		)
	)
	(zone
		(layer "In2.Cu")
		(hatch none 0.5)
		(connect_pads
			(clearance 0)
		)
		(min_thickness 0.25)
		(keepout
			(tracks not_allowed)
			(vias allowed)
			(pads allowed)
			(copperpour not_allowed)
			(footprints allowed)
		)
		(placement
			(enabled no)
			(sheetname "")
		)
		(fill
			(thermal_gap 0.5)
			(thermal_bridge_width 0.5)
			(island_removal_mode 0)
		)
		(polygon
			(pts
				(xy 175.322738 -198.77532) (xy 176.821338 -198.77532) (xy 176.821338 -199.295258) (xy 175.322738 -199.295258)
			)
		)
	)
	(zone
		(layer "In2.Cu")
		(hatch none 0.5)
		(connect_pads
			(clearance 0)
		)
		(min_thickness 0.25)
		(keepout
			(tracks not_allowed)
			(vias allowed)
			(pads allowed)
			(copperpour not_allowed)
			(footprints allowed)
		)
		(placement
			(enabled no)
			(sheetname "")
		)
		(fill
			(thermal_gap 0.5)
			(thermal_bridge_width 0.5)
			(island_removal_mode 0)
		)
		(polygon
			(pts
				(xy 190.410846 -267.625322) (xy 191.909446 -267.625322) (xy 191.909446 -268.14526) (xy 190.410846 -268.14526)
			)
		)
	)
	(zone
		(layer "In2.Cu")
		(hatch none 0.5)
		(connect_pads
			(clearance 0)
		)
		(min_thickness 0.25)
		(keepout
			(tracks not_allowed)
			(vias allowed)
			(pads allowed)
			(copperpour not_allowed)
			(footprints allowed)
		)
		(placement
			(enabled no)
			(sheetname "")
		)
		(fill
			(thermal_gap 0.5)
			(thermal_bridge_width 0.5)
			(island_removal_mode 0)
		)
		(polygon
			(pts
				(xy 36.046664 -273.575272) (xy 37.545264 -273.575272) (xy 37.545264 -274.09521) (xy 36.046664 -274.09521)
			)
		)
	)
	(zone
		(layer "In2.Cu")
		(hatch none 0.5)
		(connect_pads
			(clearance 0)
		)
		(min_thickness 0.25)
		(keepout
			(tracks not_allowed)
			(vias allowed)
			(pads allowed)
			(copperpour not_allowed)
			(footprints allowed)
		)
		(placement
			(enabled no)
			(sheetname "")
		)
		(fill
			(thermal_gap 0.5)
			(thermal_bridge_width 0.5)
			(island_removal_mode 0)
		)
		(polygon
			(pts
				(xy 58.678826 -254.025146) (xy 60.177426 -254.025146) (xy 60.177426 -254.545084) (xy 58.678826 -254.545084)
			)
		)
	)
	(zone
		(layer "In2.Cu")
		(hatch none 0.5)
		(connect_pads
			(clearance 0)
		)
		(min_thickness 0.25)
		(keepout
			(tracks not_allowed)
			(vias allowed)
			(pads allowed)
			(copperpour not_allowed)
			(footprints allowed)
		)
		(placement
			(enabled no)
			(sheetname "")
		)
		(fill
			(thermal_gap 0.5)
			(thermal_bridge_width 0.5)
			(island_removal_mode 0)
		)
		(polygon
			(pts
				(xy 299.07484 -219.17533) (xy 300.57344 -219.17533) (xy 300.57344 -219.695268) (xy 299.07484 -219.695268)
			)
		)
	)
	(zone
		(layer "In2.Cu")
		(hatch none 0.5)
		(connect_pads
			(clearance 0)
		)
		(min_thickness 0.25)
		(keepout
			(tracks not_allowed)
			(vias allowed)
			(pads allowed)
			(copperpour not_allowed)
			(footprints allowed)
		)
		(placement
			(enabled no)
			(sheetname "")
		)
		(fill
			(thermal_gap 0.5)
			(thermal_bridge_width 0.5)
			(island_removal_mode 0)
		)
		(polygon
			(pts
				(xy 197.954646 -310.975248) (xy 199.453246 -310.975248) (xy 199.453246 -311.495186) (xy 197.954646 -311.495186)
			)
		)
	)
	(zone
		(layer "In2.Cu")
		(hatch none 0.5)
		(connect_pads
			(clearance 0)
		)
		(min_thickness 0.25)
		(keepout
			(tracks not_allowed)
			(vias allowed)
			(pads allowed)
			(copperpour not_allowed)
			(footprints allowed)
		)
		(placement
			(enabled no)
			(sheetname "")
		)
		(fill
			(thermal_gap 0.5)
			(thermal_bridge_width 0.5)
			(island_removal_mode 0)
		)
		(polygon
			(pts
				(xy 283.986732 -310.975248) (xy 285.485332 -310.975248) (xy 285.485332 -311.495186) (xy 283.986732 -311.495186)
			)
		)
	)
	(zone
		(layer "In2.Cu")
		(hatch none 0.5)
		(connect_pads
			(clearance 0)
		)
		(min_thickness 0.25)
		(keepout
			(tracks not_allowed)
			(vias allowed)
			(pads allowed)
			(copperpour not_allowed)
			(footprints allowed)
		)
		(placement
			(enabled no)
			(sheetname "")
		)
		(fill
			(thermal_gap 0.5)
			(thermal_bridge_width 0.5)
			(island_removal_mode 0)
		)
		(polygon
			(pts
				(xy 54.578758 -278.675338) (xy 56.077358 -278.675338) (xy 56.077358 -279.195276) (xy 54.578758 -279.195276)
			)
		)
	)
	(zone
		(layer "In2.Cu")
		(hatch none 0.5)
		(connect_pads
			(clearance 0)
		)
		(min_thickness 0.25)
		(keepout
			(tracks not_allowed)
			(vias allowed)
			(pads allowed)
			(copperpour not_allowed)
			(footprints allowed)
		)
		(placement
			(enabled no)
			(sheetname "")
		)
		(fill
			(thermal_gap 0.5)
			(thermal_bridge_width 0.5)
			(island_removal_mode 0)
		)
		(polygon
			(pts
				(xy 28.50261 -210.67522) (xy 30.00121 -210.67522) (xy 30.00121 -211.195158) (xy 28.50261 -211.195158)
			)
		)
	)
	(zone
		(layer "In2.Cu")
		(hatch none 0.5)
		(connect_pads
			(clearance 0)
		)
		(min_thickness 0.25)
		(keepout
			(tracks not_allowed)
			(vias allowed)
			(pads allowed)
			(copperpour not_allowed)
			(footprints allowed)
		)
		(placement
			(enabled no)
			(sheetname "")
		)
		(fill
			(thermal_gap 0.5)
			(thermal_bridge_width 0.5)
			(island_removal_mode 0)
		)
		(polygon
			(pts
				(xy 441.7949 -233.625136) (xy 443.2935 -233.625136) (xy 443.2935 -234.145074) (xy 441.7949 -234.145074)
			)
		)
	)
	(zone
		(layer "In2.Cu")
		(hatch none 0.5)
		(connect_pads
			(clearance 0)
		)
		(min_thickness 0.25)
		(keepout
			(tracks not_allowed)
			(vias allowed)
			(pads allowed)
			(copperpour not_allowed)
			(footprints allowed)
		)
		(placement
			(enabled no)
			(sheetname "")
		)
		(fill
			(thermal_gap 0.5)
			(thermal_bridge_width 0.5)
			(island_removal_mode 0)
		)
		(polygon
			(pts
				(xy 193.854578 -265.075162) (xy 195.353178 -265.075162) (xy 195.353178 -265.5951) (xy 193.854578 -265.5951)
			)
		)
	)
	(zone
		(layer "In2.Cu")
		(hatch none 0.5)
		(connect_pads
			(clearance 0)
		)
		(min_thickness 0.25)
		(keepout
			(tracks not_allowed)
			(vias allowed)
			(pads allowed)
			(copperpour not_allowed)
			(footprints allowed)
		)
		(placement
			(enabled no)
			(sheetname "")
		)
		(fill
			(thermal_gap 0.5)
			(thermal_bridge_width 0.5)
			(island_removal_mode 0)
		)
		(polygon
			(pts
				(xy 272.342864 -289.725354) (xy 273.841464 -289.725354) (xy 273.841464 -290.245292) (xy 272.342864 -290.245292)
			)
		)
	)
	(zone
		(layer "In2.Cu")
		(hatch none 0.5)
		(connect_pads
			(clearance 0)
		)
		(min_thickness 0.25)
		(keepout
			(tracks not_allowed)
			(vias allowed)
			(pads allowed)
			(copperpour not_allowed)
			(footprints allowed)
		)
		(placement
			(enabled no)
			(sheetname "")
		)
		(fill
			(thermal_gap 0.5)
			(thermal_bridge_width 0.5)
			(island_removal_mode 0)
		)
		(polygon
			(pts
				(xy 193.854578 -249.775218) (xy 195.353178 -249.775218) (xy 195.353178 -250.295156) (xy 193.854578 -250.295156)
			)
		)
	)
	(zone
		(layer "In2.Cu")
		(hatch none 0.5)
		(connect_pads
			(clearance 0)
		)
		(min_thickness 0.25)
		(keepout
			(tracks not_allowed)
			(vias allowed)
			(pads allowed)
			(copperpour not_allowed)
			(footprints allowed)
		)
		(placement
			(enabled no)
			(sheetname "")
		)
		(fill
			(thermal_gap 0.5)
			(thermal_bridge_width 0.5)
			(island_removal_mode 0)
		)
		(polygon
			(pts
				(xy 186.310778 -305.025298) (xy 187.809378 -305.025298) (xy 187.809378 -305.545236) (xy 186.310778 -305.545236)
			)
		)
	)
	(zone
		(layer "In2.Cu")
		(hatch none 0.5)
		(connect_pads
			(clearance 0)
		)
		(min_thickness 0.25)
		(keepout
			(tracks not_allowed)
			(vias allowed)
			(pads allowed)
			(copperpour not_allowed)
			(footprints allowed)
		)
		(placement
			(enabled no)
			(sheetname "")
		)
		(fill
			(thermal_gap 0.5)
			(thermal_bridge_width 0.5)
			(island_removal_mode 0)
		)
		(polygon
			(pts
				(xy 279.886664 -266.775184) (xy 281.385264 -266.775184) (xy 281.385264 -267.295122) (xy 279.886664 -267.295122)
			)
		)
	)
	(zone
		(layer "In2.Cu")
		(hatch none 0.5)
		(connect_pads
			(clearance 0)
		)
		(min_thickness 0.25)
		(keepout
			(tracks not_allowed)
			(vias allowed)
			(pads allowed)
			(copperpour not_allowed)
			(footprints allowed)
		)
		(placement
			(enabled no)
			(sheetname "")
		)
		(fill
			(thermal_gap 0.5)
			(thermal_bridge_width 0.5)
			(island_removal_mode 0)
		)
		(polygon
			(pts
				(xy 47.034704 -282.075128) (xy 48.533304 -282.075128) (xy 48.533304 -282.595066) (xy 47.034704 -282.595066)
			)
		)
	)
	(zone
		(layer "In2.Cu")
		(hatch none 0.5)
		(connect_pads
			(clearance 0)
		)
		(min_thickness 0.25)
		(keepout
			(tracks not_allowed)
			(vias allowed)
			(pads allowed)
			(copperpour not_allowed)
			(footprints allowed)
		)
		(placement
			(enabled no)
			(sheetname "")
		)
		(fill
			(thermal_gap 0.5)
			(thermal_bridge_width 0.5)
			(island_removal_mode 0)
		)
		(polygon
			(pts
				(xy 430.80686 -210.67522) (xy 432.30546 -210.67522) (xy 432.30546 -211.195158) (xy 430.80686 -211.195158)
			)
		)
	)
	(zone
		(layer "In2.Cu")
		(hatch none 0.5)
		(connect_pads
			(clearance 0)
		)
		(min_thickness 0.25)
		(keepout
			(tracks not_allowed)
			(vias allowed)
			(pads allowed)
			(copperpour not_allowed)
			(footprints allowed)
		)
		(placement
			(enabled no)
			(sheetname "")
		)
		(fill
			(thermal_gap 0.5)
			(thermal_bridge_width 0.5)
			(island_removal_mode 0)
		)
		(polygon
			(pts
				(xy 31.946596 -213.225126) (xy 33.445196 -213.225126) (xy 33.445196 -213.745064) (xy 31.946596 -213.745064)
			)
		)
	)
	(zone
		(layer "In2.Cu")
		(hatch none 0.5)
		(connect_pads
			(clearance 0)
		)
		(min_thickness 0.25)
		(keepout
			(tracks not_allowed)
			(vias allowed)
			(pads allowed)
			(copperpour not_allowed)
			(footprints allowed)
		)
		(placement
			(enabled no)
			(sheetname "")
		)
		(fill
			(thermal_gap 0.5)
			(thermal_bridge_width 0.5)
			(island_removal_mode 0)
		)
		(polygon
			(pts
				(xy 201.398632 -268.475206) (xy 202.897232 -268.475206) (xy 202.897232 -268.995144) (xy 201.398632 -268.995144)
			)
		)
	)
	(zone
		(layer "In2.Cu")
		(hatch none 0.5)
		(connect_pads
			(clearance 0)
		)
		(min_thickness 0.25)
		(keepout
			(tracks not_allowed)
			(vias allowed)
			(pads allowed)
			(copperpour not_allowed)
			(footprints allowed)
		)
		(placement
			(enabled no)
			(sheetname "")
		)
		(fill
			(thermal_gap 0.5)
			(thermal_bridge_width 0.5)
			(island_removal_mode 0)
		)
		(polygon
			(pts
				(xy 441.7949 -299.075348) (xy 443.2935 -299.075348) (xy 443.2935 -299.595286) (xy 441.7949 -299.595286)
			)
		)
	)
	(zone
		(layer "In2.Cu")
		(hatch none 0.5)
		(connect_pads
			(clearance 0)
		)
		(min_thickness 0.25)
		(keepout
			(tracks not_allowed)
			(vias allowed)
			(pads allowed)
			(copperpour not_allowed)
			(footprints allowed)
		)
		(placement
			(enabled no)
			(sheetname "")
		)
		(fill
			(thermal_gap 0.5)
			(thermal_bridge_width 0.5)
			(island_removal_mode 0)
		)
		(polygon
			(pts
				(xy 294.974772 -214.925148) (xy 296.473372 -214.925148) (xy 296.473372 -215.445086) (xy 294.974772 -215.445086)
			)
		)
	)
	(zone
		(layer "In2.Cu")
		(hatch none 0.5)
		(connect_pads
			(clearance 0)
		)
		(min_thickness 0.25)
		(keepout
			(tracks not_allowed)
			(vias allowed)
			(pads allowed)
			(copperpour not_allowed)
			(footprints allowed)
		)
		(placement
			(enabled no)
			(sheetname "")
		)
		(fill
			(thermal_gap 0.5)
			(thermal_bridge_width 0.5)
			(island_removal_mode 0)
		)
		(polygon
			(pts
				(arc
					(start 429.87214 -7.672324)
					(mid 429.894458 -7.618442)
					(end 429.94834 -7.596124)
				)
				(arc
					(start 430.984914 -7.596124)
					(mid 431.038796 -7.618442)
					(end 431.061114 -7.672324)
				)
				(arc
					(start 431.061114 -9.071864)
					(mid 431.038796 -9.125746)
					(end 430.984914 -9.148064)
				)
				(arc
					(start 429.94834 -9.148064)
					(mid 429.894458 -9.125746)
					(end 429.87214 -9.071864)
				)
			)
		)
	)
	(zone
		(layer "In2.Cu")
		(hatch none 0.5)
		(connect_pads
			(clearance 0)
		)
		(min_thickness 0.25)
		(keepout
			(tracks not_allowed)
			(vias allowed)
			(pads allowed)
			(copperpour not_allowed)
			(footprints allowed)
		)
		(placement
			(enabled no)
			(sheetname "")
		)
		(fill
			(thermal_gap 0.5)
			(thermal_bridge_width 0.5)
			(island_removal_mode 0)
		)
		(polygon
			(pts
				(xy 276.442932 -312.67527) (xy 277.941532 -312.67527) (xy 277.941532 -313.195208) (xy 276.442932 -313.195208)
			)
		)
	)
	(zone
		(layer "In2.Cu")
		(hatch none 0.5)
		(connect_pads
			(clearance 0)
		)
		(min_thickness 0.25)
		(keepout
			(tracks not_allowed)
			(vias allowed)
			(pads allowed)
			(copperpour not_allowed)
			(footprints allowed)
		)
		(placement
			(enabled no)
			(sheetname "")
		)
		(fill
			(thermal_gap 0.5)
			(thermal_bridge_width 0.5)
			(island_removal_mode 0)
		)
		(polygon
			(pts
				(xy 47.034704 -261.675118) (xy 48.533304 -261.675118) (xy 48.533304 -262.195056) (xy 47.034704 -262.195056)
			)
		)
	)
	(zone
		(layer "In2.Cu")
		(hatch none 0.5)
		(connect_pads
			(clearance 0)
		)
		(min_thickness 0.25)
		(keepout
			(tracks allowed)
			(vias allowed)
			(pads allowed)
			(copperpour allowed)
			(footprints allowed)
		)
		(placement
			(enabled no)
			(sheetname "")
		)
		(fill
			(thermal_gap 0.5)
			(thermal_bridge_width 0.5)
			(island_removal_mode 0)
		)
		(polygon
			(pts
				(xy 424.247818 -175.711612) (xy 422.571418 -175.711612) (xy 422.393618 -175.889412) (xy 422.393618 -176.245012)
				(xy 422.596818 -176.448212) (xy 424.679618 -176.448212) (xy 426.864018 -174.263812) (xy 426.864018 -161.411412)
				(xy 424.374818 -158.922212) (xy 421.606218 -158.922212) (xy 419.802818 -157.118812) (xy 401.286218 -157.118812)
				(xy 388.459218 -144.291812) (xy 386.300218 -144.291812) (xy 386.122418 -144.469612) (xy 386.122418 -144.952212)
				(xy 386.300218 -145.130012) (xy 388.052818 -145.130012) (xy 400.829018 -157.906212) (xy 419.447218 -157.906212)
				(xy 421.377618 -159.836612) (xy 424.044618 -159.836612) (xy 426.076618 -161.868612) (xy 426.076618 -173.882812)
			)
		)
	)
	(zone
		(layer "In2.Cu")
		(hatch none 0.5)
		(connect_pads
			(clearance 0)
		)
		(min_thickness 0.25)
		(keepout
			(tracks not_allowed)
			(vias allowed)
			(pads allowed)
			(copperpour not_allowed)
			(footprints allowed)
		)
		(placement
			(enabled no)
			(sheetname "")
		)
		(fill
			(thermal_gap 0.5)
			(thermal_bridge_width 0.5)
			(island_removal_mode 0)
		)
		(polygon
			(pts
				(xy 24.402542 -274.425156) (xy 25.901142 -274.425156) (xy 25.901142 -274.945094) (xy 24.402542 -274.945094)
			)
		)
	)
	(zone
		(layer "In2.Cu")
		(hatch none 0.5)
		(connect_pads
			(clearance 0)
		)
		(min_thickness 0.25)
		(keepout
			(tracks not_allowed)
			(vias allowed)
			(pads allowed)
			(copperpour not_allowed)
			(footprints allowed)
		)
		(placement
			(enabled no)
			(sheetname "")
		)
		(fill
			(thermal_gap 0.5)
			(thermal_bridge_width 0.5)
			(island_removal_mode 0)
		)
		(polygon
			(pts
				(xy 268.898878 -294.825166) (xy 270.397478 -294.825166) (xy 270.397478 -295.345104) (xy 268.898878 -295.345104)
			)
		)
	)
	(zone
		(layer "In2.Cu")
		(hatch none 0.5)
		(connect_pads
			(clearance 0)
		)
		(min_thickness 0.25)
		(keepout
			(tracks not_allowed)
			(vias allowed)
			(pads allowed)
			(copperpour not_allowed)
			(footprints allowed)
		)
		(placement
			(enabled no)
			(sheetname "")
		)
		(fill
			(thermal_gap 0.5)
			(thermal_bridge_width 0.5)
			(island_removal_mode 0)
		)
		(polygon
			(pts
				(xy 190.410846 -236.175296) (xy 191.909446 -236.175296) (xy 191.909446 -236.695234) (xy 190.410846 -236.695234)
			)
		)
	)
	(zone
		(layer "In2.Cu")
		(hatch none 0.5)
		(connect_pads
			(clearance 0)
		)
		(min_thickness 0.25)
		(keepout
			(tracks not_allowed)
			(vias allowed)
			(pads allowed)
			(copperpour not_allowed)
			(footprints allowed)
		)
		(placement
			(enabled no)
			(sheetname "")
		)
		(fill
			(thermal_gap 0.5)
			(thermal_bridge_width 0.5)
			(island_removal_mode 0)
		)
		(polygon
			(pts
				(xy 294.974772 -310.12511) (xy 296.473372 -310.12511) (xy 296.473372 -310.645048) (xy 294.974772 -310.645048)
			)
		)
	)
	(zone
		(layer "In2.Cu")
		(hatch none 0.5)
		(connect_pads
			(clearance 0)
		)
		(min_thickness 0.25)
		(keepout
			(tracks not_allowed)
			(vias allowed)
			(pads allowed)
			(copperpour not_allowed)
			(footprints allowed)
		)
		(placement
			(enabled no)
			(sheetname "")
		)
		(fill
			(thermal_gap 0.5)
			(thermal_bridge_width 0.5)
			(island_removal_mode 0)
		)
		(polygon
			(pts
				(xy 279.886664 -286.32531) (xy 281.385264 -286.32531) (xy 281.385264 -286.845248) (xy 279.886664 -286.845248)
			)
		)
	)
	(zone
		(layer "In2.Cu")
		(hatch none 0.5)
		(connect_pads
			(clearance 0)
		)
		(min_thickness 0.25)
		(keepout
			(tracks not_allowed)
			(vias allowed)
			(pads allowed)
			(copperpour not_allowed)
			(footprints allowed)
		)
		(placement
			(enabled no)
			(sheetname "")
		)
		(fill
			(thermal_gap 0.5)
			(thermal_bridge_width 0.5)
			(island_removal_mode 0)
		)
		(polygon
			(pts
				(xy 411.618684 -288.025332) (xy 413.117284 -288.025332) (xy 413.117284 -288.54527) (xy 411.618684 -288.54527)
			)
		)
	)
	(zone
		(layer "In2.Cu")
		(hatch none 0.5)
		(connect_pads
			(clearance 0)
		)
		(min_thickness 0.25)
		(keepout
			(tracks not_allowed)
			(vias allowed)
			(pads allowed)
			(copperpour not_allowed)
			(footprints allowed)
		)
		(placement
			(enabled no)
			(sheetname "")
		)
		(fill
			(thermal_gap 0.5)
			(thermal_bridge_width 0.5)
			(island_removal_mode 0)
		)
		(polygon
			(pts
				(xy 31.946596 -220.025214) (xy 33.445196 -220.025214) (xy 33.445196 -220.545152) (xy 31.946596 -220.545152)
			)
		)
	)
	(zone
		(layer "In2.Cu")
		(hatch none 0.5)
		(connect_pads
			(clearance 0)
		)
		(min_thickness 0.25)
		(keepout
			(tracks not_allowed)
			(vias allowed)
			(pads allowed)
			(copperpour not_allowed)
			(footprints allowed)
		)
		(placement
			(enabled no)
			(sheetname "")
		)
		(fill
			(thermal_gap 0.5)
			(thermal_bridge_width 0.5)
			(island_removal_mode 0)
		)
		(polygon
			(pts
				(xy 193.854578 -288.025332) (xy 195.353178 -288.025332) (xy 195.353178 -288.54527) (xy 193.854578 -288.54527)
			)
		)
	)
	(zone
		(layer "In2.Cu")
		(hatch none 0.5)
		(connect_pads
			(clearance 0)
		)
		(min_thickness 0.25)
		(keepout
			(tracks not_allowed)
			(vias allowed)
			(pads allowed)
			(copperpour not_allowed)
			(footprints allowed)
		)
		(placement
			(enabled no)
			(sheetname "")
		)
		(fill
			(thermal_gap 0.5)
			(thermal_bridge_width 0.5)
			(island_removal_mode 0)
		)
		(polygon
			(pts
				(xy 190.410846 -203.025248) (xy 191.909446 -203.025248) (xy 191.909446 -203.545186) (xy 190.410846 -203.545186)
			)
		)
	)
	(zone
		(layer "In2.Cu")
		(hatch none 0.5)
		(connect_pads
			(clearance 0)
		)
		(min_thickness 0.25)
		(keepout
			(tracks not_allowed)
			(vias allowed)
			(pads allowed)
			(copperpour not_allowed)
			(footprints allowed)
		)
		(placement
			(enabled no)
			(sheetname "")
		)
		(fill
			(thermal_gap 0.5)
			(thermal_bridge_width 0.5)
			(island_removal_mode 0)
		)
		(polygon
			(pts
				(xy 272.342864 -274.425156) (xy 273.841464 -274.425156) (xy 273.841464 -274.945094) (xy 272.342864 -274.945094)
			)
		)
	)
	(zone
		(layer "In2.Cu")
		(hatch none 0.5)
		(connect_pads
			(clearance 0)
		)
		(min_thickness 0.25)
		(keepout
			(tracks not_allowed)
			(vias allowed)
			(pads allowed)
			(copperpour not_allowed)
			(footprints allowed)
		)
		(placement
			(enabled no)
			(sheetname "")
		)
		(fill
			(thermal_gap 0.5)
			(thermal_bridge_width 0.5)
			(island_removal_mode 0)
		)
		(polygon
			(pts
				(xy 306.618894 -284.625288) (xy 308.117494 -284.625288) (xy 308.117494 -285.145226) (xy 306.618894 -285.145226)
			)
		)
	)
	(zone
		(layer "In2.Cu")
		(hatch none 0.5)
		(connect_pads
			(clearance 0)
		)
		(min_thickness 0.25)
		(keepout
			(tracks not_allowed)
			(vias allowed)
			(pads allowed)
			(copperpour not_allowed)
			(footprints allowed)
		)
		(placement
			(enabled no)
			(sheetname "")
		)
		(fill
			(thermal_gap 0.5)
			(thermal_bridge_width 0.5)
			(island_removal_mode 0)
		)
		(polygon
			(pts
				(xy 302.518826 -213.225126) (xy 304.017426 -213.225126) (xy 304.017426 -213.745064) (xy 302.518826 -213.745064)
			)
		)
	)
	(zone
		(layer "In2.Cu")
		(hatch none 0.5)
		(connect_pads
			(clearance 0)
		)
		(min_thickness 0.25)
		(keepout
			(tracks not_allowed)
			(vias allowed)
			(pads allowed)
			(copperpour not_allowed)
			(footprints allowed)
		)
		(placement
			(enabled no)
			(sheetname "")
		)
		(fill
			(thermal_gap 0.5)
			(thermal_bridge_width 0.5)
			(island_removal_mode 0)
		)
		(polygon
			(pts
				(xy 163.678616 -285.475172) (xy 165.177216 -285.475172) (xy 165.177216 -285.99511) (xy 163.678616 -285.99511)
			)
		)
	)
	(zone
		(layer "In2.Cu")
		(hatch none 0.5)
		(connect_pads
			(clearance 0)
		)
		(min_thickness 0.25)
		(keepout
			(tracks not_allowed)
			(vias allowed)
			(pads allowed)
			(copperpour not_allowed)
			(footprints allowed)
		)
		(placement
			(enabled no)
			(sheetname "")
		)
		(fill
			(thermal_gap 0.5)
			(thermal_bridge_width 0.5)
			(island_removal_mode 0)
		)
		(polygon
			(pts
				(xy 423.262806 -217.475308) (xy 424.761406 -217.475308) (xy 424.761406 -217.995246) (xy 423.262806 -217.995246)
			)
		)
	)
	(zone
		(layer "In2.Cu")
		(hatch none 0.5)
		(connect_pads
			(clearance 0)
		)
		(min_thickness 0.25)
		(keepout
			(tracks not_allowed)
			(vias allowed)
			(pads allowed)
			(copperpour not_allowed)
			(footprints allowed)
		)
		(placement
			(enabled no)
			(sheetname "")
		)
		(fill
			(thermal_gap 0.5)
			(thermal_bridge_width 0.5)
			(island_removal_mode 0)
		)
		(polygon
			(pts
				(xy 54.578758 -304.17516) (xy 56.077358 -304.17516) (xy 56.077358 -304.695098) (xy 54.578758 -304.695098)
			)
		)
	)
	(zone
		(layer "In2.Cu")
		(hatch none 0.5)
		(connect_pads
			(clearance 0)
		)
		(min_thickness 0.25)
		(keepout
			(tracks not_allowed)
			(vias allowed)
			(pads allowed)
			(copperpour not_allowed)
			(footprints allowed)
		)
		(placement
			(enabled no)
			(sheetname "")
		)
		(fill
			(thermal_gap 0.5)
			(thermal_bridge_width 0.5)
			(island_removal_mode 0)
		)
		(polygon
			(pts
				(xy 294.974772 -220.875098) (xy 296.473372 -220.875098) (xy 296.473372 -221.395036) (xy 294.974772 -221.395036)
			)
		)
	)
	(zone
		(layer "In2.Cu")
		(hatch none 0.5)
		(connect_pads
			(clearance 0)
		)
		(min_thickness 0.25)
		(keepout
			(tracks not_allowed)
			(vias allowed)
			(pads allowed)
			(copperpour not_allowed)
			(footprints allowed)
		)
		(placement
			(enabled no)
			(sheetname "")
		)
		(fill
			(thermal_gap 0.5)
			(thermal_bridge_width 0.5)
			(island_removal_mode 0)
		)
		(polygon
			(pts
				(xy 426.706792 -246.375174) (xy 428.205392 -246.375174) (xy 428.205392 -246.895112) (xy 426.706792 -246.895112)
			)
		)
	)
	(zone
		(layer "In2.Cu")
		(hatch none 0.5)
		(connect_pads
			(clearance 0)
		)
		(min_thickness 0.25)
		(keepout
			(tracks not_allowed)
			(vias allowed)
			(pads allowed)
			(copperpour not_allowed)
			(footprints allowed)
		)
		(placement
			(enabled no)
			(sheetname "")
		)
		(fill
			(thermal_gap 0.5)
			(thermal_bridge_width 0.5)
			(island_removal_mode 0)
		)
		(polygon
			(pts
				(xy 287.430718 -263.37514) (xy 288.929318 -263.37514) (xy 288.929318 -263.895078) (xy 287.430718 -263.895078)
			)
		)
	)
	(zone
		(layer "In2.Cu")
		(hatch none 0.5)
		(connect_pads
			(clearance 0)
		)
		(min_thickness 0.25)
		(keepout
			(tracks not_allowed)
			(vias allowed)
			(pads allowed)
			(copperpour not_allowed)
			(footprints allowed)
		)
		(placement
			(enabled no)
			(sheetname "")
		)
		(fill
			(thermal_gap 0.5)
			(thermal_bridge_width 0.5)
			(island_removal_mode 0)
		)
		(polygon
			(pts
				(xy 449.3387 -248.075196) (xy 450.8373 -248.075196) (xy 450.8373 -248.595134) (xy 449.3387 -248.595134)
			)
		)
	)
	(zone
		(layer "In2.Cu")
		(hatch none 0.5)
		(connect_pads
			(clearance 0)
		)
		(min_thickness 0.25)
		(keepout
			(tracks not_allowed)
			(vias allowed)
			(pads allowed)
			(copperpour not_allowed)
			(footprints allowed)
		)
		(placement
			(enabled no)
			(sheetname "")
		)
		(fill
			(thermal_gap 0.5)
			(thermal_bridge_width 0.5)
			(island_removal_mode 0)
		)
		(polygon
			(pts
				(xy 193.854578 -224.275142) (xy 195.353178 -224.275142) (xy 195.353178 -224.79508) (xy 193.854578 -224.79508)
			)
		)
	)
	(zone
		(layer "In2.Cu")
		(hatch none 0.5)
		(connect_pads
			(clearance 0)
		)
		(min_thickness 0.25)
		(keepout
			(tracks not_allowed)
			(vias allowed)
			(pads allowed)
			(copperpour not_allowed)
			(footprints allowed)
		)
		(placement
			(enabled no)
			(sheetname "")
		)
		(fill
			(thermal_gap 0.5)
			(thermal_bridge_width 0.5)
			(island_removal_mode 0)
		)
		(polygon
			(pts
				(xy 423.262806 -201.325226) (xy 424.761406 -201.325226) (xy 424.761406 -201.845164) (xy 423.262806 -201.845164)
			)
		)
	)
	(zone
		(layer "In2.Cu")
		(hatch none 0.5)
		(connect_pads
			(clearance 0)
		)
		(min_thickness 0.25)
		(keepout
			(tracks not_allowed)
			(vias allowed)
			(pads allowed)
			(copperpour not_allowed)
			(footprints allowed)
		)
		(placement
			(enabled no)
			(sheetname "")
		)
		(fill
			(thermal_gap 0.5)
			(thermal_bridge_width 0.5)
			(island_removal_mode 0)
		)
		(polygon
			(pts
				(xy 163.678616 -207.275176) (xy 165.177216 -207.275176) (xy 165.177216 -207.795114) (xy 163.678616 -207.795114)
			)
		)
	)
	(zone
		(layer "In2.Cu")
		(hatch none 0.5)
		(connect_pads
			(clearance 0)
		)
		(min_thickness 0.25)
		(keepout
			(tracks allowed)
			(vias allowed)
			(pads allowed)
			(copperpour allowed)
			(footprints allowed)
		)
		(placement
			(enabled no)
			(sheetname "")
		)
		(fill
			(thermal_gap 0.5)
			(thermal_bridge_width 0.5)
			(island_removal_mode 0)
		)
		(polygon
			(pts
				(xy 82.197194 -337.394296) (xy 82.197194 -336.771996) (xy 82.748374 -336.771996) (xy 82.748374 -337.394296)
			)
		)
	)
	(zone
		(layer "In2.Cu")
		(hatch none 0.5)
		(connect_pads
			(clearance 0)
		)
		(min_thickness 0.25)
		(keepout
			(tracks not_allowed)
			(vias allowed)
			(pads allowed)
			(copperpour not_allowed)
			(footprints allowed)
		)
		(placement
			(enabled no)
			(sheetname "")
		)
		(fill
			(thermal_gap 0.5)
			(thermal_bridge_width 0.5)
			(island_removal_mode 0)
		)
		(polygon
			(pts
				(xy 24.402542 -266.775184) (xy 25.901142 -266.775184) (xy 25.901142 -267.295122) (xy 24.402542 -267.295122)
			)
		)
	)
	(zone
		(layer "In2.Cu")
		(hatch none 0.5)
		(connect_pads
			(clearance 0)
		)
		(min_thickness 0.25)
		(keepout
			(tracks not_allowed)
			(vias allowed)
			(pads allowed)
			(copperpour not_allowed)
			(footprints allowed)
		)
		(placement
			(enabled no)
			(sheetname "")
		)
		(fill
			(thermal_gap 0.5)
			(thermal_bridge_width 0.5)
			(island_removal_mode 0)
		)
		(polygon
			(pts
				(xy 430.80686 -229.375208) (xy 432.30546 -229.375208) (xy 432.30546 -229.895146) (xy 430.80686 -229.895146)
			)
		)
	)
	(zone
		(layer "In2.Cu")
		(hatch none 0.5)
		(connect_pads
			(clearance 0)
		)
		(min_thickness 0.25)
		(keepout
			(tracks not_allowed)
			(vias allowed)
			(pads allowed)
			(copperpour not_allowed)
			(footprints allowed)
		)
		(placement
			(enabled no)
			(sheetname "")
		)
		(fill
			(thermal_gap 0.5)
			(thermal_bridge_width 0.5)
			(island_removal_mode 0)
		)
		(polygon
			(pts
				(xy 283.986732 -197.075298) (xy 285.485332 -197.075298) (xy 285.485332 -197.595236) (xy 283.986732 -197.595236)
			)
		)
	)
	(zone
		(layer "In2.Cu")
		(hatch none 0.5)
		(connect_pads
			(clearance 0)
		)
		(min_thickness 0.25)
		(keepout
			(tracks not_allowed)
			(vias allowed)
			(pads allowed)
			(copperpour not_allowed)
			(footprints allowed)
		)
		(placement
			(enabled no)
			(sheetname "")
		)
		(fill
			(thermal_gap 0.5)
			(thermal_bridge_width 0.5)
			(island_removal_mode 0)
		)
		(polygon
			(pts
				(xy 54.578758 -218.325192) (xy 56.077358 -218.325192) (xy 56.077358 -218.84513) (xy 54.578758 -218.84513)
			)
		)
	)
	(zone
		(layer "In2.Cu")
		(hatch none 0.5)
		(connect_pads
			(clearance 0)
		)
		(min_thickness 0.25)
		(keepout
			(tracks not_allowed)
			(vias allowed)
			(pads allowed)
			(copperpour not_allowed)
			(footprints allowed)
		)
		(placement
			(enabled no)
			(sheetname "")
		)
		(fill
			(thermal_gap 0.5)
			(thermal_bridge_width 0.5)
			(island_removal_mode 0)
		)
		(polygon
			(pts
				(xy 438.350914 -248.925334) (xy 439.849514 -248.925334) (xy 439.849514 -249.445272) (xy 438.350914 -249.445272)
			)
		)
	)
	(zone
		(layer "In2.Cu")
		(hatch none 0.5)
		(connect_pads
			(clearance 0)
		)
		(min_thickness 0.25)
		(keepout
			(tracks not_allowed)
			(vias allowed)
			(pads allowed)
			(copperpour not_allowed)
			(footprints allowed)
		)
		(placement
			(enabled no)
			(sheetname "")
		)
		(fill
			(thermal_gap 0.5)
			(thermal_bridge_width 0.5)
			(island_removal_mode 0)
		)
		(polygon
			(pts
				(xy 36.046664 -312.67527) (xy 37.545264 -312.67527) (xy 37.545264 -313.195208) (xy 36.046664 -313.195208)
			)
		)
	)
	(zone
		(layer "In2.Cu")
		(hatch none 0.5)
		(connect_pads
			(clearance 0)
		)
		(min_thickness 0.25)
		(keepout
			(tracks allowed)
			(vias allowed)
			(pads allowed)
			(copperpour allowed)
			(footprints allowed)
		)
		(placement
			(enabled no)
			(sheetname "")
		)
		(fill
			(thermal_gap 0.5)
			(thermal_bridge_width 0.5)
			(island_removal_mode 0)
		)
		(polygon
			(pts
				(xy 321.694556 -338.210144) (xy 321.694556 -337.587844) (xy 322.245736 -337.587844) (xy 322.245736 -338.210144)
			)
		)
	)
	(zone
		(layer "In2.Cu")
		(hatch none 0.5)
		(connect_pads
			(clearance 0)
		)
		(min_thickness 0.25)
		(keepout
			(tracks not_allowed)
			(vias allowed)
			(pads allowed)
			(copperpour not_allowed)
			(footprints allowed)
		)
		(placement
			(enabled no)
			(sheetname "")
		)
		(fill
			(thermal_gap 0.5)
			(thermal_bridge_width 0.5)
			(island_removal_mode 0)
		)
		(polygon
			(pts
				(xy 306.618894 -309.275226) (xy 308.117494 -309.275226) (xy 308.117494 -309.795164) (xy 306.618894 -309.795164)
			)
		)
	)
	(zone
		(layer "In2.Cu")
		(hatch none 0.5)
		(connect_pads
			(clearance 0)
		)
		(min_thickness 0.25)
		(keepout
			(tracks not_allowed)
			(vias allowed)
			(pads allowed)
			(copperpour not_allowed)
			(footprints allowed)
		)
		(placement
			(enabled no)
			(sheetname "")
		)
		(fill
			(thermal_gap 0.5)
			(thermal_bridge_width 0.5)
			(island_removal_mode 0)
		)
		(polygon
			(pts
				(xy 201.398632 -314.375292) (xy 202.897232 -314.375292) (xy 202.897232 -314.89523) (xy 201.398632 -314.89523)
			)
		)
	)
	(zone
		(layer "In2.Cu")
		(hatch none 0.5)
		(connect_pads
			(clearance 0)
		)
		(min_thickness 0.25)
		(keepout
			(tracks not_allowed)
			(vias allowed)
			(pads allowed)
			(copperpour not_allowed)
			(footprints allowed)
		)
		(placement
			(enabled no)
			(sheetname "")
		)
		(fill
			(thermal_gap 0.5)
			(thermal_bridge_width 0.5)
			(island_removal_mode 0)
		)
		(polygon
			(pts
				(xy 430.80686 -242.125246) (xy 432.30546 -242.125246) (xy 432.30546 -242.645184) (xy 430.80686 -242.645184)
			)
		)
	)
	(zone
		(layer "In2.Cu")
		(hatch none 0.5)
		(connect_pads
			(clearance 0)
		)
		(min_thickness 0.25)
		(keepout
			(tracks not_allowed)
			(vias allowed)
			(pads allowed)
			(copperpour not_allowed)
			(footprints allowed)
		)
		(placement
			(enabled no)
			(sheetname "")
		)
		(fill
			(thermal_gap 0.5)
			(thermal_bridge_width 0.5)
			(island_removal_mode 0)
		)
		(polygon
			(pts
				(xy 24.402542 -306.72532) (xy 25.901142 -306.72532) (xy 25.901142 -307.245258) (xy 24.402542 -307.245258)
			)
		)
	)
	(zone
		(layer "In2.Cu")
		(hatch none 0.5)
		(connect_pads
			(clearance 0)
		)
		(min_thickness 0.25)
		(keepout
			(tracks not_allowed)
			(vias allowed)
			(pads allowed)
			(copperpour not_allowed)
			(footprints allowed)
		)
		(placement
			(enabled no)
			(sheetname "")
		)
		(fill
			(thermal_gap 0.5)
			(thermal_bridge_width 0.5)
			(island_removal_mode 0)
		)
		(polygon
			(pts
				(xy 197.954646 -304.17516) (xy 199.453246 -304.17516) (xy 199.453246 -304.695098) (xy 197.954646 -304.695098)
			)
		)
	)
	(zone
		(layer "In2.Cu")
		(hatch none 0.5)
		(connect_pads
			(clearance 0)
		)
		(min_thickness 0.25)
		(keepout
			(tracks not_allowed)
			(vias allowed)
			(pads allowed)
			(copperpour not_allowed)
			(footprints allowed)
		)
		(placement
			(enabled no)
			(sheetname "")
		)
		(fill
			(thermal_gap 0.5)
			(thermal_bridge_width 0.5)
			(island_removal_mode 0)
		)
		(polygon
			(pts
				(xy 163.678616 -282.075128) (xy 165.177216 -282.075128) (xy 165.177216 -282.595066) (xy 163.678616 -282.595066)
			)
		)
	)
	(zone
		(layer "In2.Cu")
		(hatch none 0.5)
		(connect_pads
			(clearance 0)
		)
		(min_thickness 0.25)
		(keepout
			(tracks not_allowed)
			(vias allowed)
			(pads allowed)
			(copperpour not_allowed)
			(footprints allowed)
		)
		(placement
			(enabled no)
			(sheetname "")
		)
		(fill
			(thermal_gap 0.5)
			(thermal_bridge_width 0.5)
			(island_removal_mode 0)
		)
		(polygon
			(pts
				(xy 453.438768 -209.825336) (xy 454.937368 -209.825336) (xy 454.937368 -210.345274) (xy 453.438768 -210.345274)
			)
		)
	)
	(zone
		(layer "In2.Cu")
		(hatch none 0.5)
		(connect_pads
			(clearance 0)
		)
		(min_thickness 0.25)
		(keepout
			(tracks not_allowed)
			(vias allowed)
			(pads allowed)
			(copperpour not_allowed)
			(footprints allowed)
		)
		(placement
			(enabled no)
			(sheetname "")
		)
		(fill
			(thermal_gap 0.5)
			(thermal_bridge_width 0.5)
			(island_removal_mode 0)
		)
		(polygon
			(pts
				(xy 28.50261 -279.525222) (xy 30.00121 -279.525222) (xy 30.00121 -280.04516) (xy 28.50261 -280.04516)
			)
		)
	)
	(zone
		(layer "In2.Cu")
		(hatch none 0.5)
		(connect_pads
			(clearance 0)
		)
		(min_thickness 0.25)
		(keepout
			(tracks not_allowed)
			(vias allowed)
			(pads allowed)
			(copperpour not_allowed)
			(footprints allowed)
		)
		(placement
			(enabled no)
			(sheetname "")
		)
		(fill
			(thermal_gap 0.5)
			(thermal_bridge_width 0.5)
			(island_removal_mode 0)
		)
		(polygon
			(pts
				(xy 291.530786 -247.225312) (xy 293.029386 -247.225312) (xy 293.029386 -247.74525) (xy 291.530786 -247.74525)
			)
		)
	)
	(zone
		(layer "In2.Cu")
		(hatch none 0.5)
		(connect_pads
			(clearance 0)
		)
		(min_thickness 0.25)
		(keepout
			(tracks not_allowed)
			(vias allowed)
			(pads allowed)
			(copperpour not_allowed)
			(footprints allowed)
		)
		(placement
			(enabled no)
			(sheetname "")
		)
		(fill
			(thermal_gap 0.5)
			(thermal_bridge_width 0.5)
			(island_removal_mode 0)
		)
		(polygon
			(pts
				(xy 441.7949 -263.37514) (xy 443.2935 -263.37514) (xy 443.2935 -263.895078) (xy 441.7949 -263.895078)
			)
		)
	)
	(zone
		(layer "In2.Cu")
		(hatch none 0.5)
		(connect_pads
			(clearance 0)
		)
		(min_thickness 0.25)
		(keepout
			(tracks not_allowed)
			(vias allowed)
			(pads allowed)
			(copperpour not_allowed)
			(footprints allowed)
		)
		(placement
			(enabled no)
			(sheetname "")
		)
		(fill
			(thermal_gap 0.5)
			(thermal_bridge_width 0.5)
			(island_removal_mode 0)
		)
		(polygon
			(pts
				(xy 430.80686 -276.125178) (xy 432.30546 -276.125178) (xy 432.30546 -276.645116) (xy 430.80686 -276.645116)
			)
		)
	)
	(zone
		(layer "In2.Cu")
		(hatch none 0.5)
		(connect_pads
			(clearance 0)
		)
		(min_thickness 0.25)
		(keepout
			(tracks not_allowed)
			(vias allowed)
			(pads allowed)
			(copperpour not_allowed)
			(footprints allowed)
		)
		(placement
			(enabled no)
			(sheetname "")
		)
		(fill
			(thermal_gap 0.5)
			(thermal_bridge_width 0.5)
			(island_removal_mode 0)
		)
		(polygon
			(pts
				(xy 291.530786 -277.8252) (xy 293.029386 -277.8252) (xy 293.029386 -278.345138) (xy 291.530786 -278.345138)
			)
		)
	)
	(zone
		(layer "In2.Cu")
		(hatch none 0.5)
		(connect_pads
			(clearance 0)
		)
		(min_thickness 0.25)
		(keepout
			(tracks not_allowed)
			(vias allowed)
			(pads allowed)
			(copperpour not_allowed)
			(footprints allowed)
		)
		(placement
			(enabled no)
			(sheetname "")
		)
		(fill
			(thermal_gap 0.5)
			(thermal_bridge_width 0.5)
			(island_removal_mode 0)
		)
		(polygon
			(pts
				(xy 415.718752 -221.725236) (xy 417.217352 -221.725236) (xy 417.217352 -222.245174) (xy 415.718752 -222.245174)
			)
		)
	)
	(zone
		(layer "In2.Cu")
		(hatch none 0.5)
		(connect_pads
			(clearance 0)
		)
		(min_thickness 0.25)
		(keepout
			(tracks not_allowed)
			(vias allowed)
			(pads allowed)
			(copperpour not_allowed)
			(footprints allowed)
		)
		(placement
			(enabled no)
			(sheetname "")
		)
		(fill
			(thermal_gap 0.5)
			(thermal_bridge_width 0.5)
			(island_removal_mode 0)
		)
		(polygon
			(pts
				(xy 415.718752 -277.8252) (xy 417.217352 -277.8252) (xy 417.217352 -278.345138) (xy 415.718752 -278.345138)
			)
		)
	)
	(zone
		(layer "In2.Cu")
		(hatch none 0.5)
		(connect_pads
			(clearance 0)
		)
		(min_thickness 0.25)
		(keepout
			(tracks not_allowed)
			(vias allowed)
			(pads allowed)
			(copperpour not_allowed)
			(footprints allowed)
		)
		(placement
			(enabled no)
			(sheetname "")
		)
		(fill
			(thermal_gap 0.5)
			(thermal_bridge_width 0.5)
			(island_removal_mode 0)
		)
		(polygon
			(pts
				(xy 279.886664 -197.925182) (xy 281.385264 -197.925182) (xy 281.385264 -198.44512) (xy 279.886664 -198.44512)
			)
		)
	)
	(zone
		(layer "In2.Cu")
		(hatch none 0.5)
		(connect_pads
			(clearance 0)
		)
		(min_thickness 0.25)
		(keepout
			(tracks allowed)
			(vias allowed)
			(pads allowed)
			(copperpour allowed)
			(footprints allowed)
		)
		(placement
			(enabled no)
			(sheetname "")
		)
		(fill
			(thermal_gap 0.5)
			(thermal_bridge_width 0.5)
			(island_removal_mode 0)
		)
		(polygon
			(pts
				(xy 350.172528 -158.542482) (xy 350.172528 -157.996128) (xy 350.724978 -157.996128) (xy 350.724978 -158.542482)
			)
		)
	)
	(zone
		(layer "In2.Cu")
		(hatch none 0.5)
		(connect_pads
			(clearance 0)
		)
		(min_thickness 0.25)
		(keepout
			(tracks not_allowed)
			(vias allowed)
			(pads allowed)
			(copperpour not_allowed)
			(footprints allowed)
		)
		(placement
			(enabled no)
			(sheetname "")
		)
		(fill
			(thermal_gap 0.5)
			(thermal_bridge_width 0.5)
			(island_removal_mode 0)
		)
		(polygon
			(pts
				(xy 54.578758 -233.625136) (xy 56.077358 -233.625136) (xy 56.077358 -234.145074) (xy 54.578758 -234.145074)
			)
		)
	)
	(zone
		(layer "In2.Cu")
		(hatch none 0.5)
		(connect_pads
			(clearance 0)
		)
		(min_thickness 0.25)
		(keepout
			(tracks not_allowed)
			(vias allowed)
			(pads allowed)
			(copperpour not_allowed)
			(footprints allowed)
		)
		(placement
			(enabled no)
			(sheetname "")
		)
		(fill
			(thermal_gap 0.5)
			(thermal_bridge_width 0.5)
			(island_removal_mode 0)
		)
		(polygon
			(pts
				(xy 411.618684 -265.075162) (xy 413.117284 -265.075162) (xy 413.117284 -265.5951) (xy 411.618684 -265.5951)
			)
		)
	)
	(zone
		(layer "In2.Cu")
		(hatch none 0.5)
		(connect_pads
			(clearance 0)
		)
		(min_thickness 0.25)
		(keepout
			(tracks not_allowed)
			(vias allowed)
			(pads allowed)
			(copperpour not_allowed)
			(footprints allowed)
		)
		(placement
			(enabled no)
			(sheetname "")
		)
		(fill
			(thermal_gap 0.5)
			(thermal_bridge_width 0.5)
			(island_removal_mode 0)
		)
		(polygon
			(pts
				(xy 299.07484 -262.525256) (xy 300.57344 -262.525256) (xy 300.57344 -263.045194) (xy 299.07484 -263.045194)
			)
		)
	)
	(zone
		(layer "In2.Cu")
		(hatch none 0.5)
		(connect_pads
			(clearance 0)
		)
		(min_thickness 0.25)
		(keepout
			(tracks not_allowed)
			(vias allowed)
			(pads allowed)
			(copperpour not_allowed)
			(footprints allowed)
		)
		(placement
			(enabled no)
			(sheetname "")
		)
		(fill
			(thermal_gap 0.5)
			(thermal_bridge_width 0.5)
			(island_removal_mode 0)
		)
		(polygon
			(pts
				(xy 430.80686 -209.825336) (xy 432.30546 -209.825336) (xy 432.30546 -210.345274) (xy 430.80686 -210.345274)
			)
		)
	)
	(zone
		(layer "In2.Cu")
		(hatch none 0.5)
		(connect_pads
			(clearance 0)
		)
		(min_thickness 0.25)
		(keepout
			(tracks not_allowed)
			(vias allowed)
			(pads allowed)
			(copperpour not_allowed)
			(footprints allowed)
		)
		(placement
			(enabled no)
			(sheetname "")
		)
		(fill
			(thermal_gap 0.5)
			(thermal_bridge_width 0.5)
			(island_removal_mode 0)
		)
		(polygon
			(pts
				(xy 51.134772 -201.325226) (xy 52.633372 -201.325226) (xy 52.633372 -201.845164) (xy 51.134772 -201.845164)
			)
		)
	)
	(zone
		(layer "In2.Cu")
		(hatch none 0.5)
		(connect_pads
			(clearance 0)
		)
		(min_thickness 0.25)
		(keepout
			(tracks not_allowed)
			(vias allowed)
			(pads allowed)
			(copperpour not_allowed)
			(footprints allowed)
		)
		(placement
			(enabled no)
			(sheetname "")
		)
		(fill
			(thermal_gap 0.5)
			(thermal_bridge_width 0.5)
			(island_removal_mode 0)
		)
		(polygon
			(pts
				(xy 430.80686 -307.575204) (xy 432.30546 -307.575204) (xy 432.30546 -308.095142) (xy 430.80686 -308.095142)
			)
		)
	)
	(zone
		(layer "In2.Cu")
		(hatch none 0.5)
		(connect_pads
			(clearance 0)
		)
		(min_thickness 0.25)
		(keepout
			(tracks not_allowed)
			(vias allowed)
			(pads allowed)
			(copperpour not_allowed)
			(footprints allowed)
		)
		(placement
			(enabled no)
			(sheetname "")
		)
		(fill
			(thermal_gap 0.5)
			(thermal_bridge_width 0.5)
			(island_removal_mode 0)
		)
		(polygon
			(pts
				(xy 186.310778 -218.325192) (xy 187.809378 -218.325192) (xy 187.809378 -218.84513) (xy 186.310778 -218.84513)
			)
		)
	)
	(zone
		(layer "In2.Cu")
		(hatch none 0.5)
		(connect_pads
			(clearance 0)
		)
		(min_thickness 0.25)
		(keepout
			(tracks not_allowed)
			(vias allowed)
			(pads allowed)
			(copperpour not_allowed)
			(footprints allowed)
		)
		(placement
			(enabled no)
			(sheetname "")
		)
		(fill
			(thermal_gap 0.5)
			(thermal_bridge_width 0.5)
			(island_removal_mode 0)
		)
		(polygon
			(pts
				(xy 445.894968 -219.17533) (xy 447.393568 -219.17533) (xy 447.393568 -219.695268) (xy 445.894968 -219.695268)
			)
		)
	)
	(zone
		(layer "In2.Cu")
		(hatch none 0.5)
		(connect_pads
			(clearance 0)
		)
		(min_thickness 0.25)
		(keepout
			(tracks not_allowed)
			(vias allowed)
			(pads allowed)
			(copperpour not_allowed)
			(footprints allowed)
		)
		(placement
			(enabled no)
			(sheetname "")
		)
		(fill
			(thermal_gap 0.5)
			(thermal_bridge_width 0.5)
			(island_removal_mode 0)
		)
		(polygon
			(pts
				(arc
					(start 315.099446 -379.360684)
					(mid 315.11937 -379.36992)
					(end 315.141102 -379.37313)
				)
				(arc
					(start 315.335666 -379.37313)
					(mid 315.389548 -379.350812)
					(end 315.411866 -379.29693)
				)
				(arc
					(start 315.411866 -378.61113)
					(mid 315.389548 -378.557248)
					(end 315.335666 -378.53493)
				)
				(arc
					(start 315.141102 -378.53493)
					(mid 315.119358 -378.538098)
					(end 315.099446 -378.547376)
				)
				(arc
					(start 314.803282 -378.740162)
					(mid 314.761598 -378.752384)
					(end 314.71997 -378.739908)
				)
				(arc
					(start 314.426346 -378.547376)
					(mid 314.406422 -378.53814)
					(end 314.38469 -378.53493)
				)
				(arc
					(start 314.190126 -378.53493)
					(mid 314.136244 -378.557248)
					(end 314.113926 -378.61113)
				)
				(arc
					(start 314.113926 -379.29693)
					(mid 314.136244 -379.350812)
					(end 314.190126 -379.37313)
				)
				(arc
					(start 314.38596 -379.37313)
					(mid 314.407704 -379.369962)
					(end 314.427616 -379.360684)
				)
				(arc
					(start 314.72124 -379.168152)
					(mid 314.762896 -379.15575)
					(end 314.804552 -379.168152)
				)
			)
		)
	)
	(zone
		(layer "In2.Cu")
		(hatch none 0.5)
		(connect_pads
			(clearance 0)
		)
		(min_thickness 0.25)
		(keepout
			(tracks not_allowed)
			(vias allowed)
			(pads allowed)
			(copperpour not_allowed)
			(footprints allowed)
		)
		(placement
			(enabled no)
			(sheetname "")
		)
		(fill
			(thermal_gap 0.5)
			(thermal_bridge_width 0.5)
			(island_removal_mode 0)
		)
		(polygon
			(pts
				(xy 31.946596 -304.17516) (xy 33.445196 -304.17516) (xy 33.445196 -304.695098) (xy 31.946596 -304.695098)
			)
		)
	)
	(zone
		(layer "In2.Cu")
		(hatch none 0.5)
		(connect_pads
			(clearance 0)
		)
		(min_thickness 0.25)
		(keepout
			(tracks not_allowed)
			(vias allowed)
			(pads allowed)
			(copperpour not_allowed)
			(footprints allowed)
		)
		(placement
			(enabled no)
			(sheetname "")
		)
		(fill
			(thermal_gap 0.5)
			(thermal_bridge_width 0.5)
			(island_removal_mode 0)
		)
		(polygon
			(pts
				(xy 197.954646 -237.875318) (xy 199.453246 -237.875318) (xy 199.453246 -238.395256) (xy 197.954646 -238.395256)
			)
		)
	)
	(zone
		(layer "In2.Cu")
		(hatch none 0.5)
		(connect_pads
			(clearance 0)
		)
		(min_thickness 0.25)
		(keepout
			(tracks not_allowed)
			(vias allowed)
			(pads allowed)
			(copperpour not_allowed)
			(footprints allowed)
		)
		(placement
			(enabled no)
			(sheetname "")
		)
		(fill
			(thermal_gap 0.5)
			(thermal_bridge_width 0.5)
			(island_removal_mode 0)
		)
		(polygon
			(pts
				(xy 294.974772 -201.325226) (xy 296.473372 -201.325226) (xy 296.473372 -201.845164) (xy 294.974772 -201.845164)
			)
		)
	)
	(zone
		(layer "In2.Cu")
		(hatch none 0.5)
		(connect_pads
			(clearance 0)
		)
		(min_thickness 0.25)
		(keepout
			(tracks not_allowed)
			(vias allowed)
			(pads allowed)
			(copperpour not_allowed)
			(footprints allowed)
		)
		(placement
			(enabled no)
			(sheetname "")
		)
		(fill
			(thermal_gap 0.5)
			(thermal_bridge_width 0.5)
			(island_removal_mode 0)
		)
		(polygon
			(pts
				(xy 434.250846 -299.075348) (xy 435.749446 -299.075348) (xy 435.749446 -299.595286) (xy 434.250846 -299.595286)
			)
		)
	)
	(zone
		(layer "In2.Cu")
		(hatch none 0.5)
		(connect_pads
			(clearance 0)
		)
		(min_thickness 0.25)
		(keepout
			(tracks not_allowed)
			(vias allowed)
			(pads allowed)
			(copperpour not_allowed)
			(footprints allowed)
		)
		(placement
			(enabled no)
			(sheetname "")
		)
		(fill
			(thermal_gap 0.5)
			(thermal_bridge_width 0.5)
			(island_removal_mode 0)
		)
		(polygon
			(pts
				(xy 201.398632 -299.075348) (xy 202.897232 -299.075348) (xy 202.897232 -299.595286) (xy 201.398632 -299.595286)
			)
		)
	)
	(zone
		(layer "In2.Cu")
		(hatch none 0.5)
		(connect_pads
			(clearance 0)
		)
		(min_thickness 0.25)
		(keepout
			(tracks not_allowed)
			(vias allowed)
			(pads allowed)
			(copperpour not_allowed)
			(footprints allowed)
		)
		(placement
			(enabled no)
			(sheetname "")
		)
		(fill
			(thermal_gap 0.5)
			(thermal_bridge_width 0.5)
			(island_removal_mode 0)
		)
		(polygon
			(pts
				(xy 283.986732 -309.275226) (xy 285.485332 -309.275226) (xy 285.485332 -309.795164) (xy 283.986732 -309.795164)
			)
		)
	)
	(zone
		(layer "In2.Cu")
		(hatch none 0.5)
		(connect_pads
			(clearance 0)
		)
		(min_thickness 0.25)
		(keepout
			(tracks not_allowed)
			(vias allowed)
			(pads allowed)
			(copperpour not_allowed)
			(footprints allowed)
		)
		(placement
			(enabled no)
			(sheetname "")
		)
		(fill
			(thermal_gap 0.5)
			(thermal_bridge_width 0.5)
			(island_removal_mode 0)
		)
		(polygon
			(pts
				(xy 16.395446 -105.9561)
				(arc
					(start 16.395446 -106.096308)
					(mid 16.424655 -106.16619)
					(end 16.49476 -106.19486)
				)
				(arc
					(start 16.796004 -106.19486)
					(mid 16.866109 -106.16619)
					(end 16.895318 -106.096308)
				)
				(xy 16.895318 -105.9561) (xy 16.835374 -105.9561)
				(arc
					(start 16.835374 -105.386886)
					(mid 16.878873 -105.350517)
					(end 16.895318 -105.296208)
				)
				(arc
					(start 16.895318 -105.036112)
					(mid 16.878999 -104.98172)
					(end 16.835374 -104.945434)
				)
				(xy 16.835374 -104.37622) (xy 16.895318 -104.37622)
				(arc
					(start 16.895318 -104.236012)
					(mid 16.866109 -104.16613)
					(end 16.796004 -104.13746)
				)
				(arc
					(start 16.49476 -104.13746)
					(mid 16.424655 -104.16613)
					(end 16.395446 -104.236012)
				)
				(xy 16.395446 -104.37622) (xy 16.45539 -104.37622)
				(arc
					(start 16.45539 -104.945434)
					(mid 16.411891 -104.981803)
					(end 16.395446 -105.036112)
				)
				(arc
					(start 16.395446 -105.296208)
					(mid 16.411765 -105.3506)
					(end 16.45539 -105.386886)
				)
				(xy 16.45539 -105.9561)
			)
		)
	)
	(zone
		(layer "In2.Cu")
		(hatch none 0.5)
		(connect_pads
			(clearance 0)
		)
		(min_thickness 0.25)
		(keepout
			(tracks not_allowed)
			(vias allowed)
			(pads allowed)
			(copperpour not_allowed)
			(footprints allowed)
		)
		(placement
			(enabled no)
			(sheetname "")
		)
		(fill
			(thermal_gap 0.5)
			(thermal_bridge_width 0.5)
			(island_removal_mode 0)
		)
		(polygon
			(pts
				(xy 276.442932 -245.52529) (xy 277.941532 -245.52529) (xy 277.941532 -246.045228) (xy 276.442932 -246.045228)
			)
		)
	)
	(zone
		(layer "In2.Cu")
		(hatch none 0.5)
		(connect_pads
			(clearance 0)
		)
		(min_thickness 0.25)
		(keepout
			(tracks not_allowed)
			(vias allowed)
			(pads allowed)
			(copperpour not_allowed)
			(footprints allowed)
		)
		(placement
			(enabled no)
			(sheetname "")
		)
		(fill
			(thermal_gap 0.5)
			(thermal_bridge_width 0.5)
			(island_removal_mode 0)
		)
		(polygon
			(pts
				(xy 193.854578 -291.425122) (xy 195.353178 -291.425122) (xy 195.353178 -291.94506) (xy 193.854578 -291.94506)
			)
		)
	)
	(zone
		(layer "In2.Cu")
		(hatch none 0.5)
		(connect_pads
			(clearance 0)
		)
		(min_thickness 0.25)
		(keepout
			(tracks not_allowed)
			(vias allowed)
			(pads allowed)
			(copperpour not_allowed)
			(footprints allowed)
		)
		(placement
			(enabled no)
			(sheetname "")
		)
		(fill
			(thermal_gap 0.5)
			(thermal_bridge_width 0.5)
			(island_removal_mode 0)
		)
		(polygon
			(pts
				(xy 299.07484 -232.775252) (xy 300.57344 -232.775252) (xy 300.57344 -233.29519) (xy 299.07484 -233.29519)
			)
		)
	)
	(zone
		(layer "In2.Cu")
		(hatch none 0.5)
		(connect_pads
			(clearance 0)
		)
		(min_thickness 0.25)
		(keepout
			(tracks allowed)
			(vias allowed)
			(pads allowed)
			(copperpour allowed)
			(footprints allowed)
		)
		(placement
			(enabled no)
			(sheetname "")
		)
		(fill
			(thermal_gap 0.5)
			(thermal_bridge_width 0.5)
			(island_removal_mode 0)
		)
		(polygon
			(pts
				(xy 73.84161 -338.138008) (xy 73.84161 -337.515708) (xy 74.39279 -337.515708) (xy 74.39279 -338.138008)
			)
		)
	)
	(zone
		(layer "In2.Cu")
		(hatch none 0.5)
		(connect_pads
			(clearance 0)
		)
		(min_thickness 0.25)
		(keepout
			(tracks not_allowed)
			(vias allowed)
			(pads allowed)
			(copperpour not_allowed)
			(footprints allowed)
		)
		(placement
			(enabled no)
			(sheetname "")
		)
		(fill
			(thermal_gap 0.5)
			(thermal_bridge_width 0.5)
			(island_removal_mode 0)
		)
		(polygon
			(pts
				(xy 411.618684 -278.675338) (xy 413.117284 -278.675338) (xy 413.117284 -279.195276) (xy 411.618684 -279.195276)
			)
		)
	)
	(zone
		(layer "In2.Cu")
		(hatch none 0.5)
		(connect_pads
			(clearance 0)
		)
		(min_thickness 0.25)
		(keepout
			(tracks not_allowed)
			(vias allowed)
			(pads allowed)
			(copperpour not_allowed)
			(footprints allowed)
		)
		(placement
			(enabled no)
			(sheetname "")
		)
		(fill
			(thermal_gap 0.5)
			(thermal_bridge_width 0.5)
			(island_removal_mode 0)
		)
		(polygon
			(pts
				(xy 16.858742 -305.025298) (xy 18.357342 -305.025298) (xy 18.357342 -305.545236) (xy 16.858742 -305.545236)
			)
		)
	)
	(zone
		(layer "In2.Cu")
		(hatch none 0.5)
		(connect_pads
			(clearance 0)
		)
		(min_thickness 0.25)
		(keepout
			(tracks not_allowed)
			(vias allowed)
			(pads allowed)
			(copperpour not_allowed)
			(footprints allowed)
		)
		(placement
			(enabled no)
			(sheetname "")
		)
		(fill
			(thermal_gap 0.5)
			(thermal_bridge_width 0.5)
			(island_removal_mode 0)
		)
		(polygon
			(pts
				(xy 306.618894 -301.625254) (xy 308.117494 -301.625254) (xy 308.117494 -302.145192) (xy 306.618894 -302.145192)
			)
		)
	)
	(zone
		(layer "In2.Cu")
		(hatch none 0.5)
		(connect_pads
			(clearance 0)
		)
		(min_thickness 0.25)
		(keepout
			(tracks not_allowed)
			(vias allowed)
			(pads allowed)
			(copperpour not_allowed)
			(footprints allowed)
		)
		(placement
			(enabled no)
			(sheetname "")
		)
		(fill
			(thermal_gap 0.5)
			(thermal_bridge_width 0.5)
			(island_removal_mode 0)
		)
		(polygon
			(pts
				(xy 453.438768 -293.975282) (xy 454.937368 -293.975282) (xy 454.937368 -294.49522) (xy 453.438768 -294.49522)
			)
		)
	)
	(zone
		(layer "In2.Cu")
		(hatch none 0.5)
		(connect_pads
			(clearance 0)
		)
		(min_thickness 0.25)
		(keepout
			(tracks not_allowed)
			(vias allowed)
			(pads allowed)
			(copperpour not_allowed)
			(footprints allowed)
		)
		(placement
			(enabled no)
			(sheetname "")
		)
		(fill
			(thermal_gap 0.5)
			(thermal_bridge_width 0.5)
			(island_removal_mode 0)
		)
		(polygon
			(pts
				(xy 299.07484 -243.825268) (xy 300.57344 -243.825268) (xy 300.57344 -244.345206) (xy 299.07484 -244.345206)
			)
		)
	)
	(zone
		(layer "In2.Cu")
		(hatch none 0.5)
		(connect_pads
			(clearance 0)
		)
		(min_thickness 0.25)
		(keepout
			(tracks not_allowed)
			(vias allowed)
			(pads allowed)
			(copperpour not_allowed)
			(footprints allowed)
		)
		(placement
			(enabled no)
			(sheetname "")
		)
		(fill
			(thermal_gap 0.5)
			(thermal_bridge_width 0.5)
			(island_removal_mode 0)
		)
		(polygon
			(pts
				(xy 47.034704 -299.075348) (xy 48.533304 -299.075348) (xy 48.533304 -299.595286) (xy 47.034704 -299.595286)
			)
		)
	)
	(zone
		(layer "In2.Cu")
		(hatch none 0.5)
		(connect_pads
			(clearance 0)
		)
		(min_thickness 0.25)
		(keepout
			(tracks not_allowed)
			(vias allowed)
			(pads allowed)
			(copperpour not_allowed)
			(footprints allowed)
		)
		(placement
			(enabled no)
			(sheetname "")
		)
		(fill
			(thermal_gap 0.5)
			(thermal_bridge_width 0.5)
			(island_removal_mode 0)
		)
		(polygon
			(pts
				(arc
					(start 345.925394 -381.824484)
					(mid 345.945318 -381.83372)
					(end 345.96705 -381.83693)
				)
				(arc
					(start 346.161614 -381.83693)
					(mid 346.215496 -381.814612)
					(end 346.237814 -381.76073)
				)
				(arc
					(start 346.237814 -381.07493)
					(mid 346.215496 -381.021048)
					(end 346.161614 -380.99873)
				)
				(arc
					(start 345.96705 -380.99873)
					(mid 345.945306 -381.001898)
					(end 345.925394 -381.011176)
				)
				(arc
					(start 345.62923 -381.203962)
					(mid 345.587546 -381.216184)
					(end 345.545918 -381.203708)
				)
				(arc
					(start 345.252294 -381.011176)
					(mid 345.23237 -381.00194)
					(end 345.210638 -380.99873)
				)
				(arc
					(start 345.016074 -380.99873)
					(mid 344.962192 -381.021048)
					(end 344.939874 -381.07493)
				)
				(arc
					(start 344.939874 -381.76073)
					(mid 344.962192 -381.814612)
					(end 345.016074 -381.83693)
				)
				(arc
					(start 345.211908 -381.83693)
					(mid 345.233652 -381.833762)
					(end 345.253564 -381.824484)
				)
				(arc
					(start 345.547188 -381.631952)
					(mid 345.588844 -381.61955)
					(end 345.6305 -381.631952)
				)
			)
		)
	)
	(zone
		(layer "In2.Cu")
		(hatch none 0.5)
		(connect_pads
			(clearance 0)
		)
		(min_thickness 0.25)
		(keepout
			(tracks not_allowed)
			(vias allowed)
			(pads allowed)
			(copperpour not_allowed)
			(footprints allowed)
		)
		(placement
			(enabled no)
			(sheetname "")
		)
		(fill
			(thermal_gap 0.5)
			(thermal_bridge_width 0.5)
			(island_removal_mode 0)
		)
		(polygon
			(pts
				(xy 28.50261 -284.625288) (xy 30.00121 -284.625288) (xy 30.00121 -285.145226) (xy 28.50261 -285.145226)
			)
		)
	)
	(zone
		(layer "In2.Cu")
		(hatch none 0.5)
		(connect_pads
			(clearance 0)
		)
		(min_thickness 0.25)
		(keepout
			(tracks not_allowed)
			(vias allowed)
			(pads allowed)
			(copperpour not_allowed)
			(footprints allowed)
		)
		(placement
			(enabled no)
			(sheetname "")
		)
		(fill
			(thermal_gap 0.5)
			(thermal_bridge_width 0.5)
			(island_removal_mode 0)
		)
		(polygon
			(pts
				(xy 171.22267 -295.675304) (xy 172.72127 -295.675304) (xy 172.72127 -296.195242) (xy 171.22267 -296.195242)
			)
		)
	)
	(zone
		(layer "In2.Cu")
		(hatch none 0.5)
		(connect_pads
			(clearance 0)
		)
		(min_thickness 0.25)
		(keepout
			(tracks not_allowed)
			(vias allowed)
			(pads allowed)
			(copperpour not_allowed)
			(footprints allowed)
		)
		(placement
			(enabled no)
			(sheetname "")
		)
		(fill
			(thermal_gap 0.5)
			(thermal_bridge_width 0.5)
			(island_removal_mode 0)
		)
		(polygon
			(pts
				(xy 167.778684 -312.67527) (xy 169.277284 -312.67527) (xy 169.277284 -313.195208) (xy 167.778684 -313.195208)
			)
		)
	)
	(zone
		(layer "In2.Cu")
		(hatch none 0.5)
		(connect_pads
			(clearance 0)
		)
		(min_thickness 0.25)
		(keepout
			(tracks not_allowed)
			(vias allowed)
			(pads allowed)
			(copperpour not_allowed)
			(footprints allowed)
		)
		(placement
			(enabled no)
			(sheetname "")
		)
		(fill
			(thermal_gap 0.5)
			(thermal_bridge_width 0.5)
			(island_removal_mode 0)
		)
		(polygon
			(pts
				(xy 54.578758 -213.225126) (xy 56.077358 -213.225126) (xy 56.077358 -213.745064) (xy 54.578758 -213.745064)
			)
		)
	)
	(zone
		(layer "In2.Cu")
		(hatch none 0.5)
		(connect_pads
			(clearance 0)
		)
		(min_thickness 0.25)
		(keepout
			(tracks not_allowed)
			(vias allowed)
			(pads allowed)
			(copperpour not_allowed)
			(footprints allowed)
		)
		(placement
			(enabled no)
			(sheetname "")
		)
		(fill
			(thermal_gap 0.5)
			(thermal_bridge_width 0.5)
			(island_removal_mode 0)
		)
		(polygon
			(pts
				(xy 54.578758 -283.77515) (xy 56.077358 -283.77515) (xy 56.077358 -284.295088) (xy 54.578758 -284.295088)
			)
		)
	)
	(zone
		(layer "In2.Cu")
		(hatch none 0.5)
		(connect_pads
			(clearance 0)
		)
		(min_thickness 0.25)
		(keepout
			(tracks not_allowed)
			(vias allowed)
			(pads allowed)
			(copperpour not_allowed)
			(footprints allowed)
		)
		(placement
			(enabled no)
			(sheetname "")
		)
		(fill
			(thermal_gap 0.5)
			(thermal_bridge_width 0.5)
			(island_removal_mode 0)
		)
		(polygon
			(pts
				(xy 201.398632 -216.62517) (xy 202.897232 -216.62517) (xy 202.897232 -217.145108) (xy 201.398632 -217.145108)
			)
		)
	)
	(zone
		(layer "In2.Cu")
		(hatch none 0.5)
		(connect_pads
			(clearance 0)
		)
		(min_thickness 0.25)
		(keepout
			(tracks not_allowed)
			(vias allowed)
			(pads allowed)
			(copperpour not_allowed)
			(footprints allowed)
		)
		(placement
			(enabled no)
			(sheetname "")
		)
		(fill
			(thermal_gap 0.5)
			(thermal_bridge_width 0.5)
			(island_removal_mode 0)
		)
		(polygon
			(pts
				(xy 441.7949 -225.975164) (xy 443.2935 -225.975164) (xy 443.2935 -226.495102) (xy 441.7949 -226.495102)
			)
		)
	)
	(zone
		(layer "In2.Cu")
		(hatch none 0.5)
		(connect_pads
			(clearance 0)
		)
		(min_thickness 0.25)
		(keepout
			(tracks not_allowed)
			(vias allowed)
			(pads allowed)
			(copperpour not_allowed)
			(footprints allowed)
		)
		(placement
			(enabled no)
			(sheetname "")
		)
		(fill
			(thermal_gap 0.5)
			(thermal_bridge_width 0.5)
			(island_removal_mode 0)
		)
		(polygon
			(pts
				(xy 167.778684 -285.475172) (xy 169.277284 -285.475172) (xy 169.277284 -285.99511) (xy 167.778684 -285.99511)
			)
		)
	)
	(zone
		(layer "In2.Cu")
		(hatch none 0.5)
		(connect_pads
			(clearance 0)
		)
		(min_thickness 0.25)
		(keepout
			(tracks not_allowed)
			(vias allowed)
			(pads allowed)
			(copperpour not_allowed)
			(footprints allowed)
		)
		(placement
			(enabled no)
			(sheetname "")
		)
		(fill
			(thermal_gap 0.5)
			(thermal_bridge_width 0.5)
			(island_removal_mode 0)
		)
		(polygon
			(pts
				(xy 423.262806 -287.175194) (xy 424.761406 -287.175194) (xy 424.761406 -287.695132) (xy 423.262806 -287.695132)
			)
		)
	)
	(zone
		(layer "In2.Cu")
		(hatch none 0.5)
		(connect_pads
			(clearance 0)
		)
		(min_thickness 0.25)
		(keepout
			(tracks not_allowed)
			(vias allowed)
			(pads allowed)
			(copperpour not_allowed)
			(footprints allowed)
		)
		(placement
			(enabled no)
			(sheetname "")
		)
		(fill
			(thermal_gap 0.5)
			(thermal_bridge_width 0.5)
			(island_removal_mode 0)
		)
		(polygon
			(pts
				(xy 291.530786 -288.875216) (xy 293.029386 -288.875216) (xy 293.029386 -289.395154) (xy 291.530786 -289.395154)
			)
		)
	)
	(zone
		(layer "In2.Cu")
		(hatch none 0.5)
		(connect_pads
			(clearance 0)
		)
		(min_thickness 0.25)
		(keepout
			(tracks not_allowed)
			(vias allowed)
			(pads allowed)
			(copperpour not_allowed)
			(footprints allowed)
		)
		(placement
			(enabled no)
			(sheetname "")
		)
		(fill
			(thermal_gap 0.5)
			(thermal_bridge_width 0.5)
			(island_removal_mode 0)
		)
		(polygon
			(pts
				(xy 201.398632 -222.57512) (xy 202.897232 -222.57512) (xy 202.897232 -223.095058) (xy 201.398632 -223.095058)
			)
		)
	)
	(zone
		(layer "In2.Cu")
		(hatch none 0.5)
		(connect_pads
			(clearance 0)
		)
		(min_thickness 0.25)
		(keepout
			(tracks not_allowed)
			(vias allowed)
			(pads allowed)
			(copperpour not_allowed)
			(footprints allowed)
		)
		(placement
			(enabled no)
			(sheetname "")
		)
		(fill
			(thermal_gap 0.5)
			(thermal_bridge_width 0.5)
			(island_removal_mode 0)
		)
		(polygon
			(pts
				(xy 434.250846 -208.975198) (xy 435.749446 -208.975198) (xy 435.749446 -209.495136) (xy 434.250846 -209.495136)
			)
		)
	)
	(zone
		(layer "In2.Cu")
		(hatch none 0.5)
		(connect_pads
			(clearance 0)
		)
		(min_thickness 0.25)
		(keepout
			(tracks not_allowed)
			(vias allowed)
			(pads allowed)
			(copperpour not_allowed)
			(footprints allowed)
		)
		(placement
			(enabled no)
			(sheetname "")
		)
		(fill
			(thermal_gap 0.5)
			(thermal_bridge_width 0.5)
			(island_removal_mode 0)
		)
		(polygon
			(pts
				(xy 36.046664 -236.175296) (xy 37.545264 -236.175296) (xy 37.545264 -236.695234) (xy 36.046664 -236.695234)
			)
		)
	)
	(zone
		(layer "In2.Cu")
		(hatch none 0.5)
		(connect_pads
			(clearance 0)
		)
		(min_thickness 0.25)
		(keepout
			(tracks not_allowed)
			(vias allowed)
			(pads allowed)
			(copperpour not_allowed)
			(footprints allowed)
		)
		(placement
			(enabled no)
			(sheetname "")
		)
		(fill
			(thermal_gap 0.5)
			(thermal_bridge_width 0.5)
			(island_removal_mode 0)
		)
		(polygon
			(pts
				(xy 294.974772 -248.075196) (xy 296.473372 -248.075196) (xy 296.473372 -248.595134) (xy 294.974772 -248.595134)
			)
		)
	)
	(zone
		(layer "In2.Cu")
		(hatch none 0.5)
		(connect_pads
			(clearance 0)
		)
		(min_thickness 0.25)
		(keepout
			(tracks not_allowed)
			(vias allowed)
			(pads allowed)
			(copperpour not_allowed)
			(footprints allowed)
		)
		(placement
			(enabled no)
			(sheetname "")
		)
		(fill
			(thermal_gap 0.5)
			(thermal_bridge_width 0.5)
			(island_removal_mode 0)
		)
		(polygon
			(pts
				(xy 299.07484 -212.375242) (xy 300.57344 -212.375242) (xy 300.57344 -212.89518) (xy 299.07484 -212.89518)
			)
		)
	)
	(zone
		(layer "In2.Cu")
		(hatch none 0.5)
		(connect_pads
			(clearance 0)
		)
		(min_thickness 0.25)
		(keepout
			(tracks not_allowed)
			(vias allowed)
			(pads allowed)
			(copperpour not_allowed)
			(footprints allowed)
		)
		(placement
			(enabled no)
			(sheetname "")
		)
		(fill
			(thermal_gap 0.5)
			(thermal_bridge_width 0.5)
			(island_removal_mode 0)
		)
		(polygon
			(pts
				(xy 283.986732 -304.17516) (xy 285.485332 -304.17516) (xy 285.485332 -304.695098) (xy 283.986732 -304.695098)
			)
		)
	)
	(zone
		(layer "In2.Cu")
		(hatch none 0.5)
		(connect_pads
			(clearance 0)
		)
		(min_thickness 0.25)
		(keepout
			(tracks not_allowed)
			(vias allowed)
			(pads allowed)
			(copperpour not_allowed)
			(footprints allowed)
		)
		(placement
			(enabled no)
			(sheetname "")
		)
		(fill
			(thermal_gap 0.5)
			(thermal_bridge_width 0.5)
			(island_removal_mode 0)
		)
		(polygon
			(pts
				(xy 58.678826 -273.575272) (xy 60.177426 -273.575272) (xy 60.177426 -274.09521) (xy 58.678826 -274.09521)
			)
		)
	)
	(zone
		(layer "In2.Cu")
		(hatch none 0.5)
		(connect_pads
			(clearance 0)
		)
		(min_thickness 0.25)
		(keepout
			(tracks not_allowed)
			(vias allowed)
			(pads allowed)
			(copperpour not_allowed)
			(footprints allowed)
		)
		(placement
			(enabled no)
			(sheetname "")
		)
		(fill
			(thermal_gap 0.5)
			(thermal_bridge_width 0.5)
			(island_removal_mode 0)
		)
		(polygon
			(pts
				(xy 302.518826 -294.825166) (xy 304.017426 -294.825166) (xy 304.017426 -295.345104) (xy 302.518826 -295.345104)
			)
		)
	)
	(zone
		(layer "In2.Cu")
		(hatch none 0.5)
		(connect_pads
			(clearance 0)
		)
		(min_thickness 0.25)
		(keepout
			(tracks not_allowed)
			(vias allowed)
			(pads allowed)
			(copperpour not_allowed)
			(footprints allowed)
		)
		(placement
			(enabled no)
			(sheetname "")
		)
		(fill
			(thermal_gap 0.5)
			(thermal_bridge_width 0.5)
			(island_removal_mode 0)
		)
		(polygon
			(pts
				(xy 449.3387 -265.075162) (xy 450.8373 -265.075162) (xy 450.8373 -265.5951) (xy 449.3387 -265.5951)
			)
		)
	)
	(zone
		(layer "In2.Cu")
		(hatch none 0.5)
		(connect_pads
			(clearance 0)
		)
		(min_thickness 0.25)
		(keepout
			(tracks not_allowed)
			(vias allowed)
			(pads allowed)
			(copperpour not_allowed)
			(footprints allowed)
		)
		(placement
			(enabled no)
			(sheetname "")
		)
		(fill
			(thermal_gap 0.5)
			(thermal_bridge_width 0.5)
			(island_removal_mode 0)
		)
		(polygon
			(pts
				(xy 430.80686 -304.17516) (xy 432.30546 -304.17516) (xy 432.30546 -304.695098) (xy 430.80686 -304.695098)
			)
		)
	)
	(zone
		(layer "In2.Cu")
		(hatch none 0.5)
		(connect_pads
			(clearance 0)
		)
		(min_thickness 0.25)
		(keepout
			(tracks not_allowed)
			(vias allowed)
			(pads allowed)
			(copperpour not_allowed)
			(footprints allowed)
		)
		(placement
			(enabled no)
			(sheetname "")
		)
		(fill
			(thermal_gap 0.5)
			(thermal_bridge_width 0.5)
			(island_removal_mode 0)
		)
		(polygon
			(pts
				(xy 186.310778 -199.625204) (xy 187.809378 -199.625204) (xy 187.809378 -200.145142) (xy 186.310778 -200.145142)
			)
		)
	)
	(zone
		(layer "In2.Cu")
		(hatch none 0.5)
		(connect_pads
			(clearance 0)
		)
		(min_thickness 0.25)
		(keepout
			(tracks not_allowed)
			(vias allowed)
			(pads allowed)
			(copperpour not_allowed)
			(footprints allowed)
		)
		(placement
			(enabled no)
			(sheetname "")
		)
		(fill
			(thermal_gap 0.5)
			(thermal_bridge_width 0.5)
			(island_removal_mode 0)
		)
		(polygon
			(pts
				(xy 51.134772 -277.8252) (xy 52.633372 -277.8252) (xy 52.633372 -278.345138) (xy 51.134772 -278.345138)
			)
		)
	)
	(zone
		(layer "In2.Cu")
		(hatch none 0.5)
		(connect_pads
			(clearance 0)
		)
		(min_thickness 0.25)
		(keepout
			(tracks not_allowed)
			(vias allowed)
			(pads allowed)
			(copperpour not_allowed)
			(footprints allowed)
		)
		(placement
			(enabled no)
			(sheetname "")
		)
		(fill
			(thermal_gap 0.5)
			(thermal_bridge_width 0.5)
			(island_removal_mode 0)
		)
		(polygon
			(pts
				(xy 175.322738 -234.475274) (xy 176.821338 -234.475274) (xy 176.821338 -234.995212) (xy 175.322738 -234.995212)
			)
		)
	)
	(zone
		(layer "In2.Cu")
		(hatch none 0.5)
		(connect_pads
			(clearance 0)
		)
		(min_thickness 0.25)
		(keepout
			(tracks not_allowed)
			(vias allowed)
			(pads allowed)
			(copperpour not_allowed)
			(footprints allowed)
		)
		(placement
			(enabled no)
			(sheetname "")
		)
		(fill
			(thermal_gap 0.5)
			(thermal_bridge_width 0.5)
			(island_removal_mode 0)
		)
		(polygon
			(pts
				(xy 283.986732 -206.425292) (xy 285.485332 -206.425292) (xy 285.485332 -206.94523) (xy 283.986732 -206.94523)
			)
		)
	)
	(zone
		(layer "In2.Cu")
		(hatch none 0.5)
		(connect_pads
			(clearance 0)
		)
		(min_thickness 0.25)
		(keepout
			(tracks not_allowed)
			(vias allowed)
			(pads allowed)
			(copperpour not_allowed)
			(footprints allowed)
		)
		(placement
			(enabled no)
			(sheetname "")
		)
		(fill
			(thermal_gap 0.5)
			(thermal_bridge_width 0.5)
			(island_removal_mode 0)
		)
		(polygon
			(pts
				(xy 441.7949 -278.675338) (xy 443.2935 -278.675338) (xy 443.2935 -279.195276) (xy 441.7949 -279.195276)
			)
		)
	)
	(zone
		(layer "In2.Cu")
		(hatch none 0.5)
		(connect_pads
			(clearance 0)
		)
		(min_thickness 0.25)
		(keepout
			(tracks not_allowed)
			(vias allowed)
			(pads allowed)
			(copperpour not_allowed)
			(footprints allowed)
		)
		(placement
			(enabled no)
			(sheetname "")
		)
		(fill
			(thermal_gap 0.5)
			(thermal_bridge_width 0.5)
			(island_removal_mode 0)
		)
		(polygon
			(pts
				(xy 28.50261 -265.9253) (xy 30.00121 -265.9253) (xy 30.00121 -266.445238) (xy 28.50261 -266.445238)
			)
		)
	)
	(zone
		(layer "In2.Cu")
		(hatch none 0.5)
		(connect_pads
			(clearance 0)
		)
		(min_thickness 0.25)
		(keepout
			(tracks not_allowed)
			(vias allowed)
			(pads allowed)
			(copperpour not_allowed)
			(footprints allowed)
		)
		(placement
			(enabled no)
			(sheetname "")
		)
		(fill
			(thermal_gap 0.5)
			(thermal_bridge_width 0.5)
			(island_removal_mode 0)
		)
		(polygon
			(pts
				(xy 47.034704 -199.625204) (xy 48.533304 -199.625204) (xy 48.533304 -200.145142) (xy 47.034704 -200.145142)
			)
		)
	)
	(zone
		(layer "In2.Cu")
		(hatch none 0.5)
		(connect_pads
			(clearance 0)
		)
		(min_thickness 0.25)
		(keepout
			(tracks not_allowed)
			(vias allowed)
			(pads allowed)
			(copperpour not_allowed)
			(footprints allowed)
		)
		(placement
			(enabled no)
			(sheetname "")
		)
		(fill
			(thermal_gap 0.5)
			(thermal_bridge_width 0.5)
			(island_removal_mode 0)
		)
		(polygon
			(pts
				(xy 306.618894 -294.825166) (xy 308.117494 -294.825166) (xy 308.117494 -295.345104) (xy 306.618894 -295.345104)
			)
		)
	)
	(zone
		(layer "In2.Cu")
		(hatch none 0.5)
		(connect_pads
			(clearance 0)
		)
		(min_thickness 0.25)
		(keepout
			(tracks not_allowed)
			(vias allowed)
			(pads allowed)
			(copperpour not_allowed)
			(footprints allowed)
		)
		(placement
			(enabled no)
			(sheetname "")
		)
		(fill
			(thermal_gap 0.5)
			(thermal_bridge_width 0.5)
			(island_removal_mode 0)
		)
		(polygon
			(pts
				(arc
					(start 29.286708 -17.966436)
					(mid 29.309026 -18.020318)
					(end 29.362908 -18.042636)
				)
				(arc
					(start 29.558488 -18.042636)
					(mid 29.580364 -18.039504)
					(end 29.600398 -18.03019)
				)
				(arc
					(start 29.894022 -17.837658)
					(mid 29.935678 -17.825256)
					(end 29.977334 -17.837658)
				)
				(arc
					(start 30.272228 -18.03019)
					(mid 30.292152 -18.039426)
					(end 30.313884 -18.042636)
				)
				(arc
					(start 30.508448 -18.042636)
					(mid 30.56233 -18.020318)
					(end 30.584648 -17.966436)
				)
				(arc
					(start 30.584648 -17.280636)
					(mid 30.56233 -17.226754)
					(end 30.508448 -17.204436)
				)
				(arc
					(start 30.313884 -17.204436)
					(mid 30.29214 -17.207604)
					(end 30.272228 -17.216882)
				)
				(arc
					(start 29.976064 -17.409668)
					(mid 29.93438 -17.42189)
					(end 29.892752 -17.409414)
				)
				(arc
					(start 29.599128 -17.216882)
					(mid 29.579204 -17.207646)
					(end 29.557472 -17.204436)
				)
				(arc
					(start 29.362908 -17.204436)
					(mid 29.309026 -17.226754)
					(end 29.286708 -17.280636)
				)
			)
		)
	)
	(zone
		(layer "In2.Cu")
		(hatch none 0.5)
		(connect_pads
			(clearance 0)
		)
		(min_thickness 0.25)
		(keepout
			(tracks not_allowed)
			(vias allowed)
			(pads allowed)
			(copperpour not_allowed)
			(footprints allowed)
		)
		(placement
			(enabled no)
			(sheetname "")
		)
		(fill
			(thermal_gap 0.5)
			(thermal_bridge_width 0.5)
			(island_removal_mode 0)
		)
		(polygon
			(pts
				(xy 28.50261 -294.825166) (xy 30.00121 -294.825166) (xy 30.00121 -295.345104) (xy 28.50261 -295.345104)
			)
		)
	)
	(zone
		(layer "In2.Cu")
		(hatch none 0.5)
		(connect_pads
			(clearance 0)
		)
		(min_thickness 0.25)
		(keepout
			(tracks not_allowed)
			(vias allowed)
			(pads allowed)
			(copperpour not_allowed)
			(footprints allowed)
		)
		(placement
			(enabled no)
			(sheetname "")
		)
		(fill
			(thermal_gap 0.5)
			(thermal_bridge_width 0.5)
			(island_removal_mode 0)
		)
		(polygon
			(pts
				(xy 287.430718 -285.475172) (xy 288.929318 -285.475172) (xy 288.929318 -285.99511) (xy 287.430718 -285.99511)
			)
		)
	)
	(zone
		(layer "In2.Cu")
		(hatch none 0.5)
		(connect_pads
			(clearance 0)
		)
		(min_thickness 0.25)
		(keepout
			(tracks not_allowed)
			(vias allowed)
			(pads allowed)
			(copperpour not_allowed)
			(footprints allowed)
		)
		(placement
			(enabled no)
			(sheetname "")
		)
		(fill
			(thermal_gap 0.5)
			(thermal_bridge_width 0.5)
			(island_removal_mode 0)
		)
		(polygon
			(pts
				(xy 58.678826 -200.475342) (xy 60.177426 -200.475342) (xy 60.177426 -200.99528) (xy 58.678826 -200.99528)
			)
		)
	)
	(zone
		(layer "In2.Cu")
		(hatch none 0.5)
		(connect_pads
			(clearance 0)
		)
		(min_thickness 0.25)
		(keepout
			(tracks not_allowed)
			(vias allowed)
			(pads allowed)
			(copperpour not_allowed)
			(footprints allowed)
		)
		(placement
			(enabled no)
			(sheetname "")
		)
		(fill
			(thermal_gap 0.5)
			(thermal_bridge_width 0.5)
			(island_removal_mode 0)
		)
		(polygon
			(pts
				(xy 291.530786 -271.87525) (xy 293.029386 -271.87525) (xy 293.029386 -272.395188) (xy 291.530786 -272.395188)
			)
		)
	)
	(zone
		(layer "In2.Cu")
		(hatch none 0.5)
		(connect_pads
			(clearance 0)
		)
		(min_thickness 0.25)
		(keepout
			(tracks not_allowed)
			(vias allowed)
			(pads allowed)
			(copperpour not_allowed)
			(footprints allowed)
		)
		(placement
			(enabled no)
			(sheetname "")
		)
		(fill
			(thermal_gap 0.5)
			(thermal_bridge_width 0.5)
			(island_removal_mode 0)
		)
		(polygon
			(pts
				(arc
					(start 395.152372 -7.672324)
					(mid 395.17469 -7.618442)
					(end 395.228572 -7.596124)
				)
				(arc
					(start 396.265146 -7.596124)
					(mid 396.319028 -7.618442)
					(end 396.341346 -7.672324)
				)
				(arc
					(start 396.341346 -9.071864)
					(mid 396.319028 -9.125746)
					(end 396.265146 -9.148064)
				)
				(arc
					(start 395.228572 -9.148064)
					(mid 395.17469 -9.125746)
					(end 395.152372 -9.071864)
				)
			)
		)
	)
	(zone
		(layer "In2.Cu")
		(hatch none 0.5)
		(connect_pads
			(clearance 0)
		)
		(min_thickness 0.25)
		(keepout
			(tracks not_allowed)
			(vias allowed)
			(pads allowed)
			(copperpour not_allowed)
			(footprints allowed)
		)
		(placement
			(enabled no)
			(sheetname "")
		)
		(fill
			(thermal_gap 0.5)
			(thermal_bridge_width 0.5)
			(island_removal_mode 0)
		)
		(polygon
			(pts
				(xy 430.80686 -247.225312) (xy 432.30546 -247.225312) (xy 432.30546 -247.74525) (xy 430.80686 -247.74525)
			)
		)
	)
	(zone
		(layer "In2.Cu")
		(hatch none 0.5)
		(connect_pads
			(clearance 0)
		)
		(min_thickness 0.25)
		(keepout
			(tracks allowed)
			(vias allowed)
			(pads allowed)
			(copperpour allowed)
			(footprints allowed)
		)
		(placement
			(enabled no)
			(sheetname "")
		)
		(fill
			(thermal_gap 0.5)
			(thermal_bridge_width 0.5)
			(island_removal_mode 0)
		)
		(polygon
			(pts
				(xy 336.48777 -338.848192) (xy 336.48777 -338.225892) (xy 337.03895 -338.225892) (xy 337.03895 -338.848192)
			)
		)
	)
	(zone
		(layer "In2.Cu")
		(hatch none 0.5)
		(connect_pads
			(clearance 0)
		)
		(min_thickness 0.25)
		(keepout
			(tracks not_allowed)
			(vias allowed)
			(pads allowed)
			(copperpour not_allowed)
			(footprints allowed)
		)
		(placement
			(enabled no)
			(sheetname "")
		)
		(fill
			(thermal_gap 0.5)
			(thermal_bridge_width 0.5)
			(island_removal_mode 0)
		)
		(polygon
			(pts
				(xy 276.442932 -270.175228) (xy 277.941532 -270.175228) (xy 277.941532 -270.695166) (xy 276.442932 -270.695166)
			)
		)
	)
	(zone
		(layer "In2.Cu")
		(hatch none 0.5)
		(connect_pads
			(clearance 0)
		)
		(min_thickness 0.25)
		(keepout
			(tracks allowed)
			(vias allowed)
			(pads allowed)
			(copperpour allowed)
			(footprints allowed)
		)
		(placement
			(enabled no)
			(sheetname "")
		)
		(fill
			(thermal_gap 0.5)
			(thermal_bridge_width 0.5)
			(island_removal_mode 0)
		)
		(polygon
			(pts
				(xy 179.916836 -354.517452) (xy 179.916836 -353.895152) (xy 180.468016 -353.895152) (xy 180.468016 -354.517452)
			)
		)
	)
	(zone
		(layer "In2.Cu")
		(hatch none 0.5)
		(connect_pads
			(clearance 0)
		)
		(min_thickness 0.25)
		(keepout
			(tracks not_allowed)
			(vias allowed)
			(pads allowed)
			(copperpour not_allowed)
			(footprints allowed)
		)
		(placement
			(enabled no)
			(sheetname "")
		)
		(fill
			(thermal_gap 0.5)
			(thermal_bridge_width 0.5)
			(island_removal_mode 0)
		)
		(polygon
			(pts
				(xy 294.974772 -211.525104) (xy 296.473372 -211.525104) (xy 296.473372 -212.045042) (xy 294.974772 -212.045042)
			)
		)
	)
	(zone
		(layer "In2.Cu")
		(hatch none 0.5)
		(connect_pads
			(clearance 0)
		)
		(min_thickness 0.25)
		(keepout
			(tracks not_allowed)
			(vias allowed)
			(pads allowed)
			(copperpour not_allowed)
			(footprints allowed)
		)
		(placement
			(enabled no)
			(sheetname "")
		)
		(fill
			(thermal_gap 0.5)
			(thermal_bridge_width 0.5)
			(island_removal_mode 0)
		)
		(polygon
			(pts
				(xy 28.50261 -305.875182) (xy 30.00121 -305.875182) (xy 30.00121 -306.39512) (xy 28.50261 -306.39512)
			)
		)
	)
	(zone
		(layer "In2.Cu")
		(hatch none 0.5)
		(connect_pads
			(clearance 0)
		)
		(min_thickness 0.25)
		(keepout
			(tracks not_allowed)
			(vias allowed)
			(pads allowed)
			(copperpour not_allowed)
			(footprints allowed)
		)
		(placement
			(enabled no)
			(sheetname "")
		)
		(fill
			(thermal_gap 0.5)
			(thermal_bridge_width 0.5)
			(island_removal_mode 0)
		)
		(polygon
			(pts
				(xy 186.310778 -233.625136) (xy 187.809378 -233.625136) (xy 187.809378 -234.145074) (xy 186.310778 -234.145074)
			)
		)
	)
	(zone
		(layer "In2.Cu")
		(hatch none 0.5)
		(connect_pads
			(clearance 0)
		)
		(min_thickness 0.25)
		(keepout
			(tracks not_allowed)
			(vias allowed)
			(pads allowed)
			(copperpour not_allowed)
			(footprints allowed)
		)
		(placement
			(enabled no)
			(sheetname "")
		)
		(fill
			(thermal_gap 0.5)
			(thermal_bridge_width 0.5)
			(island_removal_mode 0)
		)
		(polygon
			(pts
				(xy 47.034704 -207.275176) (xy 48.533304 -207.275176) (xy 48.533304 -207.795114) (xy 47.034704 -207.795114)
			)
		)
	)
	(zone
		(layer "In2.Cu")
		(hatch none 0.5)
		(connect_pads
			(clearance 0)
		)
		(min_thickness 0.25)
		(keepout
			(tracks not_allowed)
			(vias allowed)
			(pads allowed)
			(copperpour not_allowed)
			(footprints allowed)
		)
		(placement
			(enabled no)
			(sheetname "")
		)
		(fill
			(thermal_gap 0.5)
			(thermal_bridge_width 0.5)
			(island_removal_mode 0)
		)
		(polygon
			(pts
				(xy 36.046664 -305.875182) (xy 37.545264 -305.875182) (xy 37.545264 -306.39512) (xy 36.046664 -306.39512)
			)
		)
	)
	(zone
		(layer "In2.Cu")
		(hatch none 0.5)
		(connect_pads
			(clearance 0)
		)
		(min_thickness 0.25)
		(keepout
			(tracks not_allowed)
			(vias allowed)
			(pads allowed)
			(copperpour not_allowed)
			(footprints allowed)
		)
		(placement
			(enabled no)
			(sheetname "")
		)
		(fill
			(thermal_gap 0.5)
			(thermal_bridge_width 0.5)
			(island_removal_mode 0)
		)
		(polygon
			(pts
				(xy 426.706792 -235.325158) (xy 428.205392 -235.325158) (xy 428.205392 -235.845096) (xy 426.706792 -235.845096)
			)
		)
	)
	(zone
		(layer "In2.Cu")
		(hatch none 0.5)
		(connect_pads
			(clearance 0)
		)
		(min_thickness 0.25)
		(keepout
			(tracks allowed)
			(vias allowed)
			(pads allowed)
			(copperpour allowed)
			(footprints allowed)
		)
		(placement
			(enabled no)
			(sheetname "")
		)
		(fill
			(thermal_gap 0.5)
			(thermal_bridge_width 0.5)
			(island_removal_mode 0)
		)
		(polygon
			(pts
				(xy 385.41833 -180.967634) (xy 385.41833 -180.42128) (xy 385.97078 -180.42128) (xy 385.97078 -180.967634)
			)
		)
	)
	(zone
		(layer "In2.Cu")
		(hatch none 0.5)
		(connect_pads
			(clearance 0)
		)
		(min_thickness 0.25)
		(keepout
			(tracks not_allowed)
			(vias allowed)
			(pads allowed)
			(copperpour not_allowed)
			(footprints allowed)
		)
		(placement
			(enabled no)
			(sheetname "")
		)
		(fill
			(thermal_gap 0.5)
			(thermal_bridge_width 0.5)
			(island_removal_mode 0)
		)
		(polygon
			(pts
				(xy 268.898878 -285.475172) (xy 270.397478 -285.475172) (xy 270.397478 -285.99511) (xy 268.898878 -285.99511)
			)
		)
	)
	(zone
		(layer "In2.Cu")
		(hatch none 0.5)
		(connect_pads
			(clearance 0)
		)
		(min_thickness 0.25)
		(keepout
			(tracks not_allowed)
			(vias allowed)
			(pads allowed)
			(copperpour not_allowed)
			(footprints allowed)
		)
		(placement
			(enabled no)
			(sheetname "")
		)
		(fill
			(thermal_gap 0.5)
			(thermal_bridge_width 0.5)
			(island_removal_mode 0)
		)
		(polygon
			(pts
				(xy 445.894968 -312.67527) (xy 447.393568 -312.67527) (xy 447.393568 -313.195208) (xy 445.894968 -313.195208)
			)
		)
	)
	(zone
		(layer "In2.Cu")
		(hatch none 0.5)
		(connect_pads
			(clearance 0)
		)
		(min_thickness 0.25)
		(keepout
			(tracks not_allowed)
			(vias allowed)
			(pads allowed)
			(copperpour not_allowed)
			(footprints allowed)
		)
		(placement
			(enabled no)
			(sheetname "")
		)
		(fill
			(thermal_gap 0.5)
			(thermal_bridge_width 0.5)
			(island_removal_mode 0)
		)
		(polygon
			(pts
				(xy 201.398632 -199.625204) (xy 202.897232 -199.625204) (xy 202.897232 -200.145142) (xy 201.398632 -200.145142)
			)
		)
	)
	(zone
		(layer "In2.Cu")
		(hatch none 0.5)
		(connect_pads
			(clearance 0)
		)
		(min_thickness 0.25)
		(keepout
			(tracks not_allowed)
			(vias allowed)
			(pads allowed)
			(copperpour not_allowed)
			(footprints allowed)
		)
		(placement
			(enabled no)
			(sheetname "")
		)
		(fill
			(thermal_gap 0.5)
			(thermal_bridge_width 0.5)
			(island_removal_mode 0)
		)
		(polygon
			(pts
				(xy 28.50261 -238.725202) (xy 30.00121 -238.725202) (xy 30.00121 -239.24514) (xy 28.50261 -239.24514)
			)
		)
	)
	(zone
		(layer "In2.Cu")
		(hatch none 0.5)
		(connect_pads
			(clearance 0)
		)
		(min_thickness 0.25)
		(keepout
			(tracks not_allowed)
			(vias allowed)
			(pads allowed)
			(copperpour not_allowed)
			(footprints allowed)
		)
		(placement
			(enabled no)
			(sheetname "")
		)
		(fill
			(thermal_gap 0.5)
			(thermal_bridge_width 0.5)
			(island_removal_mode 0)
		)
		(polygon
			(pts
				(xy 287.430718 -293.125144) (xy 288.929318 -293.125144) (xy 288.929318 -293.645082) (xy 287.430718 -293.645082)
			)
		)
	)
	(zone
		(layer "In2.Cu")
		(hatch none 0.5)
		(connect_pads
			(clearance 0)
		)
		(min_thickness 0.25)
		(keepout
			(tracks not_allowed)
			(vias allowed)
			(pads allowed)
			(copperpour not_allowed)
			(footprints allowed)
		)
		(placement
			(enabled no)
			(sheetname "")
		)
		(fill
			(thermal_gap 0.5)
			(thermal_bridge_width 0.5)
			(island_removal_mode 0)
		)
		(polygon
			(pts
				(xy 175.322738 -221.725236) (xy 176.821338 -221.725236) (xy 176.821338 -222.245174) (xy 175.322738 -222.245174)
			)
		)
	)
	(zone
		(layer "In2.Cu")
		(hatch none 0.5)
		(connect_pads
			(clearance 0)
		)
		(min_thickness 0.25)
		(keepout
			(tracks not_allowed)
			(vias allowed)
			(pads allowed)
			(copperpour not_allowed)
			(footprints allowed)
		)
		(placement
			(enabled no)
			(sheetname "")
		)
		(fill
			(thermal_gap 0.5)
			(thermal_bridge_width 0.5)
			(island_removal_mode 0)
		)
		(polygon
			(pts
				(xy 449.3387 -268.475206) (xy 450.8373 -268.475206) (xy 450.8373 -268.995144) (xy 449.3387 -268.995144)
			)
		)
	)
	(zone
		(layer "In2.Cu")
		(hatch none 0.5)
		(connect_pads
			(clearance 0)
		)
		(min_thickness 0.25)
		(keepout
			(tracks not_allowed)
			(vias allowed)
			(pads allowed)
			(copperpour not_allowed)
			(footprints allowed)
		)
		(placement
			(enabled no)
			(sheetname "")
		)
		(fill
			(thermal_gap 0.5)
			(thermal_bridge_width 0.5)
			(island_removal_mode 0)
		)
		(polygon
			(pts
				(xy 453.438768 -260.825234) (xy 454.937368 -260.825234) (xy 454.937368 -261.345172) (xy 453.438768 -261.345172)
			)
		)
	)
	(zone
		(layer "In2.Cu")
		(hatch none 0.5)
		(connect_pads
			(clearance 0)
		)
		(min_thickness 0.25)
		(keepout
			(tracks not_allowed)
			(vias allowed)
			(pads allowed)
			(copperpour not_allowed)
			(footprints allowed)
		)
		(placement
			(enabled no)
			(sheetname "")
		)
		(fill
			(thermal_gap 0.5)
			(thermal_bridge_width 0.5)
			(island_removal_mode 0)
		)
		(polygon
			(pts
				(xy 16.858742 -306.72532) (xy 18.357342 -306.72532) (xy 18.357342 -307.245258) (xy 16.858742 -307.245258)
			)
		)
	)
	(zone
		(layer "In2.Cu")
		(hatch none 0.5)
		(connect_pads
			(clearance 0)
		)
		(min_thickness 0.25)
		(keepout
			(tracks not_allowed)
			(vias allowed)
			(pads allowed)
			(copperpour not_allowed)
			(footprints allowed)
		)
		(placement
			(enabled no)
			(sheetname "")
		)
		(fill
			(thermal_gap 0.5)
			(thermal_bridge_width 0.5)
			(island_removal_mode 0)
		)
		(polygon
			(pts
				(xy 268.898878 -310.975248) (xy 270.397478 -310.975248) (xy 270.397478 -311.495186) (xy 268.898878 -311.495186)
			)
		)
	)
	(zone
		(layer "In2.Cu")
		(hatch none 0.5)
		(connect_pads
			(clearance 0)
		)
		(min_thickness 0.25)
		(keepout
			(tracks not_allowed)
			(vias allowed)
			(pads allowed)
			(copperpour not_allowed)
			(footprints allowed)
		)
		(placement
			(enabled no)
			(sheetname "")
		)
		(fill
			(thermal_gap 0.5)
			(thermal_bridge_width 0.5)
			(island_removal_mode 0)
		)
		(polygon
			(pts
				(xy 276.442932 -293.975282) (xy 277.941532 -293.975282) (xy 277.941532 -294.49522) (xy 276.442932 -294.49522)
			)
		)
	)
	(zone
		(layer "In2.Cu")
		(hatch none 0.5)
		(connect_pads
			(clearance 0)
		)
		(min_thickness 0.25)
		(keepout
			(tracks not_allowed)
			(vias allowed)
			(pads allowed)
			(copperpour not_allowed)
			(footprints allowed)
		)
		(placement
			(enabled no)
			(sheetname "")
		)
		(fill
			(thermal_gap 0.5)
			(thermal_bridge_width 0.5)
			(island_removal_mode 0)
		)
		(polygon
			(pts
				(xy 20.95881 -290.575238) (xy 22.45741 -290.575238) (xy 22.45741 -291.095176) (xy 20.95881 -291.095176)
			)
		)
	)
	(zone
		(layer "In2.Cu")
		(hatch none 0.5)
		(connect_pads
			(clearance 0)
		)
		(min_thickness 0.25)
		(keepout
			(tracks not_allowed)
			(vias allowed)
			(pads allowed)
			(copperpour not_allowed)
			(footprints allowed)
		)
		(placement
			(enabled no)
			(sheetname "")
		)
		(fill
			(thermal_gap 0.5)
			(thermal_bridge_width 0.5)
			(island_removal_mode 0)
		)
		(polygon
			(pts
				(xy 302.518826 -278.675338) (xy 304.017426 -278.675338) (xy 304.017426 -279.195276) (xy 302.518826 -279.195276)
			)
		)
	)
	(zone
		(layer "In2.Cu")
		(hatch none 0.5)
		(connect_pads
			(clearance 0)
		)
		(min_thickness 0.25)
		(keepout
			(tracks not_allowed)
			(vias allowed)
			(pads allowed)
			(copperpour not_allowed)
			(footprints allowed)
		)
		(placement
			(enabled no)
			(sheetname "")
		)
		(fill
			(thermal_gap 0.5)
			(thermal_bridge_width 0.5)
			(island_removal_mode 0)
		)
		(polygon
			(pts
				(xy 294.974772 -293.125144) (xy 296.473372 -293.125144) (xy 296.473372 -293.645082) (xy 294.974772 -293.645082)
			)
		)
	)
	(zone
		(layer "In2.Cu")
		(hatch none 0.5)
		(connect_pads
			(clearance 0)
		)
		(min_thickness 0.25)
		(keepout
			(tracks not_allowed)
			(vias allowed)
			(pads allowed)
			(copperpour not_allowed)
			(footprints allowed)
		)
		(placement
			(enabled no)
			(sheetname "")
		)
		(fill
			(thermal_gap 0.5)
			(thermal_bridge_width 0.5)
			(island_removal_mode 0)
		)
		(polygon
			(pts
				(xy 299.07484 -234.475274) (xy 300.57344 -234.475274) (xy 300.57344 -234.995212) (xy 299.07484 -234.995212)
			)
		)
	)
	(zone
		(layer "In2.Cu")
		(hatch none 0.5)
		(connect_pads
			(clearance 0)
		)
		(min_thickness 0.25)
		(keepout
			(tracks not_allowed)
			(vias allowed)
			(pads allowed)
			(copperpour not_allowed)
			(footprints allowed)
		)
		(placement
			(enabled no)
			(sheetname "")
		)
		(fill
			(thermal_gap 0.5)
			(thermal_bridge_width 0.5)
			(island_removal_mode 0)
		)
		(polygon
			(pts
				(xy 294.974772 -224.275142) (xy 296.473372 -224.275142) (xy 296.473372 -224.79508) (xy 294.974772 -224.79508)
			)
		)
	)
	(zone
		(layer "In2.Cu")
		(hatch none 0.5)
		(connect_pads
			(clearance 0)
		)
		(min_thickness 0.25)
		(keepout
			(tracks not_allowed)
			(vias allowed)
			(pads allowed)
			(copperpour not_allowed)
			(footprints allowed)
		)
		(placement
			(enabled no)
			(sheetname "")
		)
		(fill
			(thermal_gap 0.5)
			(thermal_bridge_width 0.5)
			(island_removal_mode 0)
		)
		(polygon
			(pts
				(xy 20.95881 -293.975282) (xy 22.45741 -293.975282) (xy 22.45741 -294.49522) (xy 20.95881 -294.49522)
			)
		)
	)
	(zone
		(layer "In2.Cu")
		(hatch none 0.5)
		(connect_pads
			(clearance 0)
		)
		(min_thickness 0.25)
		(keepout
			(tracks allowed)
			(vias allowed)
			(pads allowed)
			(copperpour allowed)
			(footprints allowed)
		)
		(placement
			(enabled no)
			(sheetname "")
		)
		(fill
			(thermal_gap 0.5)
			(thermal_bridge_width 0.5)
			(island_removal_mode 0)
		)
		(polygon
			(pts
				(xy 302.90897 -349.854266) (xy 302.90897 -349.231966) (xy 303.46015 -349.231966) (xy 303.46015 -349.854266)
			)
		)
	)
	(zone
		(layer "In2.Cu")
		(hatch none 0.5)
		(connect_pads
			(clearance 0)
		)
		(min_thickness 0.25)
		(keepout
			(tracks not_allowed)
			(vias allowed)
			(pads allowed)
			(copperpour not_allowed)
			(footprints allowed)
		)
		(placement
			(enabled no)
			(sheetname "")
		)
		(fill
			(thermal_gap 0.5)
			(thermal_bridge_width 0.5)
			(island_removal_mode 0)
		)
		(polygon
			(pts
				(xy 51.134772 -240.425224) (xy 52.633372 -240.425224) (xy 52.633372 -240.945162) (xy 51.134772 -240.945162)
			)
		)
	)
	(zone
		(layer "In2.Cu")
		(hatch none 0.5)
		(connect_pads
			(clearance 0)
		)
		(min_thickness 0.25)
		(keepout
			(tracks not_allowed)
			(vias allowed)
			(pads allowed)
			(copperpour not_allowed)
			(footprints allowed)
		)
		(placement
			(enabled no)
			(sheetname "")
		)
		(fill
			(thermal_gap 0.5)
			(thermal_bridge_width 0.5)
			(island_removal_mode 0)
		)
		(polygon
			(pts
				(xy 453.438768 -226.825302) (xy 454.937368 -226.825302) (xy 454.937368 -227.34524) (xy 453.438768 -227.34524)
			)
		)
	)
	(zone
		(layer "In2.Cu")
		(hatch none 0.5)
		(connect_pads
			(clearance 0)
		)
		(min_thickness 0.25)
		(keepout
			(tracks not_allowed)
			(vias allowed)
			(pads allowed)
			(copperpour not_allowed)
			(footprints allowed)
		)
		(placement
			(enabled no)
			(sheetname "")
		)
		(fill
			(thermal_gap 0.5)
			(thermal_bridge_width 0.5)
			(island_removal_mode 0)
		)
		(polygon
			(pts
				(xy 291.530786 -250.625102) (xy 293.029386 -250.625102) (xy 293.029386 -251.14504) (xy 291.530786 -251.14504)
			)
		)
	)
	(zone
		(layer "In2.Cu")
		(hatch none 0.5)
		(connect_pads
			(clearance 0)
		)
		(min_thickness 0.25)
		(keepout
			(tracks not_allowed)
			(vias allowed)
			(pads allowed)
			(copperpour not_allowed)
			(footprints allowed)
		)
		(placement
			(enabled no)
			(sheetname "")
		)
		(fill
			(thermal_gap 0.5)
			(thermal_bridge_width 0.5)
			(island_removal_mode 0)
		)
		(polygon
			(pts
				(xy 276.442932 -301.625254) (xy 277.941532 -301.625254) (xy 277.941532 -302.145192) (xy 276.442932 -302.145192)
			)
		)
	)
	(zone
		(layer "In2.Cu")
		(hatch none 0.5)
		(connect_pads
			(clearance 0)
		)
		(min_thickness 0.25)
		(keepout
			(tracks not_allowed)
			(vias allowed)
			(pads allowed)
			(copperpour not_allowed)
			(footprints allowed)
		)
		(placement
			(enabled no)
			(sheetname "")
		)
		(fill
			(thermal_gap 0.5)
			(thermal_bridge_width 0.5)
			(island_removal_mode 0)
		)
		(polygon
			(pts
				(xy 299.07484 -240.425224) (xy 300.57344 -240.425224) (xy 300.57344 -240.945162) (xy 299.07484 -240.945162)
			)
		)
	)
	(zone
		(layer "In2.Cu")
		(hatch none 0.5)
		(connect_pads
			(clearance 0)
		)
		(min_thickness 0.25)
		(keepout
			(tracks not_allowed)
			(vias allowed)
			(pads allowed)
			(copperpour not_allowed)
			(footprints allowed)
		)
		(placement
			(enabled no)
			(sheetname "")
		)
		(fill
			(thermal_gap 0.5)
			(thermal_bridge_width 0.5)
			(island_removal_mode 0)
		)
		(polygon
			(pts
				(xy 291.530786 -237.875318) (xy 293.029386 -237.875318) (xy 293.029386 -238.395256) (xy 291.530786 -238.395256)
			)
		)
	)
	(zone
		(layer "In2.Cu")
		(hatch none 0.5)
		(connect_pads
			(clearance 0)
		)
		(min_thickness 0.25)
		(keepout
			(tracks not_allowed)
			(vias allowed)
			(pads allowed)
			(copperpour not_allowed)
			(footprints allowed)
		)
		(placement
			(enabled no)
			(sheetname "")
		)
		(fill
			(thermal_gap 0.5)
			(thermal_bridge_width 0.5)
			(island_removal_mode 0)
		)
		(polygon
			(pts
				(xy 193.854578 -272.725134) (xy 195.353178 -272.725134) (xy 195.353178 -273.245072) (xy 193.854578 -273.245072)
			)
		)
	)
	(zone
		(layer "In2.Cu")
		(hatch none 0.5)
		(connect_pads
			(clearance 0)
		)
		(min_thickness 0.25)
		(keepout
			(tracks not_allowed)
			(vias allowed)
			(pads allowed)
			(copperpour not_allowed)
			(footprints allowed)
		)
		(placement
			(enabled no)
			(sheetname "")
		)
		(fill
			(thermal_gap 0.5)
			(thermal_bridge_width 0.5)
			(island_removal_mode 0)
		)
		(polygon
			(pts
				(xy 193.854578 -220.025214) (xy 195.353178 -220.025214) (xy 195.353178 -220.545152) (xy 193.854578 -220.545152)
			)
		)
	)
	(zone
		(layer "In2.Cu")
		(hatch none 0.5)
		(connect_pads
			(clearance 0)
		)
		(min_thickness 0.25)
		(keepout
			(tracks not_allowed)
			(vias allowed)
			(pads allowed)
			(copperpour not_allowed)
			(footprints allowed)
		)
		(placement
			(enabled no)
			(sheetname "")
		)
		(fill
			(thermal_gap 0.5)
			(thermal_bridge_width 0.5)
			(island_removal_mode 0)
		)
		(polygon
			(pts
				(xy 294.974772 -261.675118) (xy 296.473372 -261.675118) (xy 296.473372 -262.195056) (xy 294.974772 -262.195056)
			)
		)
	)
	(zone
		(layer "In2.Cu")
		(hatch none 0.5)
		(connect_pads
			(clearance 0)
		)
		(min_thickness 0.25)
		(keepout
			(tracks not_allowed)
			(vias allowed)
			(pads allowed)
			(copperpour not_allowed)
			(footprints allowed)
		)
		(placement
			(enabled no)
			(sheetname "")
		)
		(fill
			(thermal_gap 0.5)
			(thermal_bridge_width 0.5)
			(island_removal_mode 0)
		)
		(polygon
			(pts
				(xy 40.34028 -425.506642)
				(arc
					(start 40.480488 -425.506642)
					(mid 40.55037 -425.477433)
					(end 40.57904 -425.407328)
				)
				(arc
					(start 40.57904 -425.106084)
					(mid 40.55037 -425.035979)
					(end 40.480488 -425.00677)
				)
				(xy 40.34028 -425.00677) (xy 40.34028 -425.066714)
				(arc
					(start 39.771066 -425.066714)
					(mid 39.734697 -425.023215)
					(end 39.680388 -425.00677)
				)
				(arc
					(start 39.420292 -425.00677)
					(mid 39.3659 -425.023089)
					(end 39.329614 -425.066714)
				)
				(xy 38.7604 -425.066714) (xy 38.7604 -425.00677)
				(arc
					(start 38.620192 -425.00677)
					(mid 38.55031 -425.035979)
					(end 38.52164 -425.106084)
				)
				(arc
					(start 38.52164 -425.407328)
					(mid 38.55031 -425.477433)
					(end 38.620192 -425.506642)
				)
				(xy 38.7604 -425.506642) (xy 38.7604 -425.446698)
				(arc
					(start 39.329614 -425.446698)
					(mid 39.365983 -425.490197)
					(end 39.420292 -425.506642)
				)
				(arc
					(start 39.680388 -425.506642)
					(mid 39.73478 -425.490323)
					(end 39.771066 -425.446698)
				)
				(xy 40.34028 -425.446698)
			)
		)
	)
	(zone
		(layer "In2.Cu")
		(hatch none 0.5)
		(connect_pads
			(clearance 0)
		)
		(min_thickness 0.25)
		(keepout
			(tracks allowed)
			(vias allowed)
			(pads allowed)
			(copperpour allowed)
			(footprints allowed)
		)
		(placement
			(enabled no)
			(sheetname "")
		)
		(fill
			(thermal_gap 0.5)
			(thermal_bridge_width 0.5)
			(island_removal_mode 0)
		)
		(polygon
			(pts
				(xy 101.82479 -343.610692) (xy 101.82479 -344.509852) (xy 101.59873 -344.509852) (xy 101.59873 -343.610692)
			)
		)
	)
	(zone
		(layer "In2.Cu")
		(hatch none 0.5)
		(connect_pads
			(clearance 0)
		)
		(min_thickness 0.25)
		(keepout
			(tracks not_allowed)
			(vias allowed)
			(pads allowed)
			(copperpour not_allowed)
			(footprints allowed)
		)
		(placement
			(enabled no)
			(sheetname "")
		)
		(fill
			(thermal_gap 0.5)
			(thermal_bridge_width 0.5)
			(island_removal_mode 0)
		)
		(polygon
			(pts
				(xy 438.350914 -200.475342) (xy 439.849514 -200.475342) (xy 439.849514 -200.99528) (xy 438.350914 -200.99528)
			)
		)
	)
	(zone
		(layer "In2.Cu")
		(hatch none 0.5)
		(connect_pads
			(clearance 0)
		)
		(min_thickness 0.25)
		(keepout
			(tracks not_allowed)
			(vias allowed)
			(pads allowed)
			(copperpour not_allowed)
			(footprints allowed)
		)
		(placement
			(enabled no)
			(sheetname "")
		)
		(fill
			(thermal_gap 0.5)
			(thermal_bridge_width 0.5)
			(island_removal_mode 0)
		)
		(polygon
			(pts
				(xy 423.262806 -248.925334) (xy 424.761406 -248.925334) (xy 424.761406 -249.445272) (xy 423.262806 -249.445272)
			)
		)
	)
	(zone
		(layer "In2.Cu")
		(hatch none 0.5)
		(connect_pads
			(clearance 0)
		)
		(min_thickness 0.25)
		(keepout
			(tracks not_allowed)
			(vias allowed)
			(pads allowed)
			(copperpour not_allowed)
			(footprints allowed)
		)
		(placement
			(enabled no)
			(sheetname "")
		)
		(fill
			(thermal_gap 0.5)
			(thermal_bridge_width 0.5)
			(island_removal_mode 0)
		)
		(polygon
			(pts
				(xy 51.134772 -290.575238) (xy 52.633372 -290.575238) (xy 52.633372 -291.095176) (xy 51.134772 -291.095176)
			)
		)
	)
	(zone
		(layer "In2.Cu")
		(hatch none 0.5)
		(connect_pads
			(clearance 0)
		)
		(min_thickness 0.25)
		(keepout
			(tracks not_allowed)
			(vias allowed)
			(pads allowed)
			(copperpour not_allowed)
			(footprints allowed)
		)
		(placement
			(enabled no)
			(sheetname "")
		)
		(fill
			(thermal_gap 0.5)
			(thermal_bridge_width 0.5)
			(island_removal_mode 0)
		)
		(polygon
			(pts
				(xy 167.778684 -298.22521) (xy 169.277284 -298.22521) (xy 169.277284 -298.745148) (xy 167.778684 -298.745148)
			)
		)
	)
	(zone
		(layer "In2.Cu")
		(hatch none 0.5)
		(connect_pads
			(clearance 0)
		)
		(min_thickness 0.25)
		(keepout
			(tracks not_allowed)
			(vias allowed)
			(pads allowed)
			(copperpour not_allowed)
			(footprints allowed)
		)
		(placement
			(enabled no)
			(sheetname "")
		)
		(fill
			(thermal_gap 0.5)
			(thermal_bridge_width 0.5)
			(island_removal_mode 0)
		)
		(polygon
			(pts
				(xy 167.778684 -228.525324) (xy 169.277284 -228.525324) (xy 169.277284 -229.045262) (xy 167.778684 -229.045262)
			)
		)
	)
	(zone
		(layer "In2.Cu")
		(hatch none 0.5)
		(connect_pads
			(clearance 0)
		)
		(min_thickness 0.25)
		(keepout
			(tracks not_allowed)
			(vias allowed)
			(pads allowed)
			(copperpour not_allowed)
			(footprints allowed)
		)
		(placement
			(enabled no)
			(sheetname "")
		)
		(fill
			(thermal_gap 0.5)
			(thermal_bridge_width 0.5)
			(island_removal_mode 0)
		)
		(polygon
			(pts
				(xy 197.954646 -200.475342) (xy 199.453246 -200.475342) (xy 199.453246 -200.99528) (xy 197.954646 -200.99528)
			)
		)
	)
	(zone
		(layer "In2.Cu")
		(hatch none 0.5)
		(connect_pads
			(clearance 0)
		)
		(min_thickness 0.25)
		(keepout
			(tracks not_allowed)
			(vias allowed)
			(pads allowed)
			(copperpour not_allowed)
			(footprints allowed)
		)
		(placement
			(enabled no)
			(sheetname "")
		)
		(fill
			(thermal_gap 0.5)
			(thermal_bridge_width 0.5)
			(island_removal_mode 0)
		)
		(polygon
			(pts
				(xy 438.350914 -298.22521) (xy 439.849514 -298.22521) (xy 439.849514 -298.745148) (xy 438.350914 -298.745148)
			)
		)
	)
	(zone
		(layer "In2.Cu")
		(hatch none 0.5)
		(connect_pads
			(clearance 0)
		)
		(min_thickness 0.25)
		(keepout
			(tracks not_allowed)
			(vias allowed)
			(pads allowed)
			(copperpour not_allowed)
			(footprints allowed)
		)
		(placement
			(enabled no)
			(sheetname "")
		)
		(fill
			(thermal_gap 0.5)
			(thermal_bridge_width 0.5)
			(island_removal_mode 0)
		)
		(polygon
			(pts
				(xy 193.854578 -210.67522) (xy 195.353178 -210.67522) (xy 195.353178 -211.195158) (xy 193.854578 -211.195158)
			)
		)
	)
	(zone
		(layer "In2.Cu")
		(hatch none 0.5)
		(connect_pads
			(clearance 0)
		)
		(min_thickness 0.25)
		(keepout
			(tracks not_allowed)
			(vias allowed)
			(pads allowed)
			(copperpour not_allowed)
			(footprints allowed)
		)
		(placement
			(enabled no)
			(sheetname "")
		)
		(fill
			(thermal_gap 0.5)
			(thermal_bridge_width 0.5)
			(island_removal_mode 0)
		)
		(polygon
			(pts
				(xy 36.046664 -228.525324) (xy 37.545264 -228.525324) (xy 37.545264 -229.045262) (xy 36.046664 -229.045262)
			)
		)
	)
	(zone
		(layer "In2.Cu")
		(hatch none 0.5)
		(connect_pads
			(clearance 0)
		)
		(min_thickness 0.25)
		(keepout
			(tracks not_allowed)
			(vias allowed)
			(pads allowed)
			(copperpour not_allowed)
			(footprints allowed)
		)
		(placement
			(enabled no)
			(sheetname "")
		)
		(fill
			(thermal_gap 0.5)
			(thermal_bridge_width 0.5)
			(island_removal_mode 0)
		)
		(polygon
			(pts
				(xy 426.706792 -224.275142) (xy 428.205392 -224.275142) (xy 428.205392 -224.79508) (xy 426.706792 -224.79508)
			)
		)
	)
	(zone
		(layer "In2.Cu")
		(hatch none 0.5)
		(connect_pads
			(clearance 0)
		)
		(min_thickness 0.25)
		(keepout
			(tracks not_allowed)
			(vias allowed)
			(pads allowed)
			(copperpour not_allowed)
			(footprints allowed)
		)
		(placement
			(enabled no)
			(sheetname "")
		)
		(fill
			(thermal_gap 0.5)
			(thermal_bridge_width 0.5)
			(island_removal_mode 0)
		)
		(polygon
			(pts
				(xy 186.310778 -254.025146) (xy 187.809378 -254.025146) (xy 187.809378 -254.545084) (xy 186.310778 -254.545084)
			)
		)
	)
	(zone
		(layer "In2.Cu")
		(hatch none 0.5)
		(connect_pads
			(clearance 0)
		)
		(min_thickness 0.25)
		(keepout
			(tracks not_allowed)
			(vias allowed)
			(pads allowed)
			(copperpour not_allowed)
			(footprints allowed)
		)
		(placement
			(enabled no)
			(sheetname "")
		)
		(fill
			(thermal_gap 0.5)
			(thermal_bridge_width 0.5)
			(island_removal_mode 0)
		)
		(polygon
			(pts
				(xy 167.778684 -234.475274) (xy 169.277284 -234.475274) (xy 169.277284 -234.995212) (xy 167.778684 -234.995212)
			)
		)
	)
	(zone
		(layer "In2.Cu")
		(hatch none 0.5)
		(connect_pads
			(clearance 0)
		)
		(min_thickness 0.25)
		(keepout
			(tracks not_allowed)
			(vias allowed)
			(pads allowed)
			(copperpour not_allowed)
			(footprints allowed)
		)
		(placement
			(enabled no)
			(sheetname "")
		)
		(fill
			(thermal_gap 0.5)
			(thermal_bridge_width 0.5)
			(island_removal_mode 0)
		)
		(polygon
			(pts
				(xy 58.678826 -223.425258) (xy 60.177426 -223.425258) (xy 60.177426 -223.945196) (xy 58.678826 -223.945196)
			)
		)
	)
	(zone
		(layer "In2.Cu")
		(hatch none 0.5)
		(connect_pads
			(clearance 0)
		)
		(min_thickness 0.25)
		(keepout
			(tracks not_allowed)
			(vias allowed)
			(pads allowed)
			(copperpour not_allowed)
			(footprints allowed)
		)
		(placement
			(enabled no)
			(sheetname "")
		)
		(fill
			(thermal_gap 0.5)
			(thermal_bridge_width 0.5)
			(island_removal_mode 0)
		)
		(polygon
			(pts
				(xy 299.07484 -226.825302) (xy 300.57344 -226.825302) (xy 300.57344 -227.34524) (xy 299.07484 -227.34524)
			)
		)
	)
	(zone
		(layer "In2.Cu")
		(hatch none 0.5)
		(connect_pads
			(clearance 0)
		)
		(min_thickness 0.25)
		(keepout
			(tracks not_allowed)
			(vias allowed)
			(pads allowed)
			(copperpour not_allowed)
			(footprints allowed)
		)
		(placement
			(enabled no)
			(sheetname "")
		)
		(fill
			(thermal_gap 0.5)
			(thermal_bridge_width 0.5)
			(island_removal_mode 0)
		)
		(polygon
			(pts
				(xy 20.95881 -316.925198) (xy 22.45741 -316.925198) (xy 22.45741 -317.445136) (xy 20.95881 -317.445136)
			)
		)
	)
	(zone
		(layer "In2.Cu")
		(hatch none 0.5)
		(connect_pads
			(clearance 0)
		)
		(min_thickness 0.25)
		(keepout
			(tracks not_allowed)
			(vias allowed)
			(pads allowed)
			(copperpour not_allowed)
			(footprints allowed)
		)
		(placement
			(enabled no)
			(sheetname "")
		)
		(fill
			(thermal_gap 0.5)
			(thermal_bridge_width 0.5)
			(island_removal_mode 0)
		)
		(polygon
			(pts
				(xy 175.322738 -204.72527) (xy 176.821338 -204.72527) (xy 176.821338 -205.245208) (xy 175.322738 -205.245208)
			)
		)
	)
	(zone
		(layer "In2.Cu")
		(hatch none 0.5)
		(connect_pads
			(clearance 0)
		)
		(min_thickness 0.25)
		(keepout
			(tracks not_allowed)
			(vias allowed)
			(pads allowed)
			(copperpour not_allowed)
			(footprints allowed)
		)
		(placement
			(enabled no)
			(sheetname "")
		)
		(fill
			(thermal_gap 0.5)
			(thermal_bridge_width 0.5)
			(island_removal_mode 0)
		)
		(polygon
			(pts
				(xy 28.50261 -275.275294) (xy 30.00121 -275.275294) (xy 30.00121 -275.795232) (xy 28.50261 -275.795232)
			)
		)
	)
	(zone
		(layer "In2.Cu")
		(hatch none 0.5)
		(connect_pads
			(clearance 0)
		)
		(min_thickness 0.25)
		(keepout
			(tracks not_allowed)
			(vias allowed)
			(pads allowed)
			(copperpour not_allowed)
			(footprints allowed)
		)
		(placement
			(enabled no)
			(sheetname "")
		)
		(fill
			(thermal_gap 0.5)
			(thermal_bridge_width 0.5)
			(island_removal_mode 0)
		)
		(polygon
			(pts
				(xy 287.430718 -311.825132) (xy 288.929318 -311.825132) (xy 288.929318 -312.34507) (xy 287.430718 -312.34507)
			)
		)
	)
	(zone
		(layer "In2.Cu")
		(hatch none 0.5)
		(connect_pads
			(clearance 0)
		)
		(min_thickness 0.25)
		(keepout
			(tracks not_allowed)
			(vias allowed)
			(pads allowed)
			(copperpour not_allowed)
			(footprints allowed)
		)
		(placement
			(enabled no)
			(sheetname "")
		)
		(fill
			(thermal_gap 0.5)
			(thermal_bridge_width 0.5)
			(island_removal_mode 0)
		)
		(polygon
			(pts
				(xy 279.886664 -237.02518) (xy 281.385264 -237.02518) (xy 281.385264 -237.545118) (xy 279.886664 -237.545118)
			)
		)
	)
	(zone
		(layer "In2.Cu")
		(hatch none 0.5)
		(connect_pads
			(clearance 0)
		)
		(min_thickness 0.25)
		(keepout
			(tracks not_allowed)
			(vias allowed)
			(pads allowed)
			(copperpour not_allowed)
			(footprints allowed)
		)
		(placement
			(enabled no)
			(sheetname "")
		)
		(fill
			(thermal_gap 0.5)
			(thermal_bridge_width 0.5)
			(island_removal_mode 0)
		)
		(polygon
			(pts
				(xy 291.530786 -303.325276) (xy 293.029386 -303.325276) (xy 293.029386 -303.845214) (xy 291.530786 -303.845214)
			)
		)
	)
	(zone
		(layer "In2.Cu")
		(hatch none 0.5)
		(connect_pads
			(clearance 0)
		)
		(min_thickness 0.25)
		(keepout
			(tracks not_allowed)
			(vias allowed)
			(pads allowed)
			(copperpour not_allowed)
			(footprints allowed)
		)
		(placement
			(enabled no)
			(sheetname "")
		)
		(fill
			(thermal_gap 0.5)
			(thermal_bridge_width 0.5)
			(island_removal_mode 0)
		)
		(polygon
			(pts
				(xy 291.530786 -208.125314) (xy 293.029386 -208.125314) (xy 293.029386 -208.645252) (xy 291.530786 -208.645252)
			)
		)
	)
	(zone
		(layer "In2.Cu")
		(hatch none 0.5)
		(connect_pads
			(clearance 0)
		)
		(min_thickness 0.25)
		(keepout
			(tracks not_allowed)
			(vias allowed)
			(pads allowed)
			(copperpour not_allowed)
			(footprints allowed)
		)
		(placement
			(enabled no)
			(sheetname "")
		)
		(fill
			(thermal_gap 0.5)
			(thermal_bridge_width 0.5)
			(island_removal_mode 0)
		)
		(polygon
			(pts
				(xy 31.946596 -294.825166) (xy 33.445196 -294.825166) (xy 33.445196 -295.345104) (xy 31.946596 -295.345104)
			)
		)
	)
	(zone
		(layer "In2.Cu")
		(hatch none 0.5)
		(connect_pads
			(clearance 0)
		)
		(min_thickness 0.25)
		(keepout
			(tracks not_allowed)
			(vias allowed)
			(pads allowed)
			(copperpour not_allowed)
			(footprints allowed)
		)
		(placement
			(enabled no)
			(sheetname "")
		)
		(fill
			(thermal_gap 0.5)
			(thermal_bridge_width 0.5)
			(island_removal_mode 0)
		)
		(polygon
			(pts
				(xy 186.310778 -220.875098) (xy 187.809378 -220.875098) (xy 187.809378 -221.395036) (xy 186.310778 -221.395036)
			)
		)
	)
	(zone
		(layer "In2.Cu")
		(hatch none 0.5)
		(connect_pads
			(clearance 0)
		)
		(min_thickness 0.25)
		(keepout
			(tracks not_allowed)
			(vias allowed)
			(pads allowed)
			(copperpour not_allowed)
			(footprints allowed)
		)
		(placement
			(enabled no)
			(sheetname "")
		)
		(fill
			(thermal_gap 0.5)
			(thermal_bridge_width 0.5)
			(island_removal_mode 0)
		)
		(polygon
			(pts
				(xy 163.678616 -197.925182) (xy 165.177216 -197.925182) (xy 165.177216 -198.44512) (xy 163.678616 -198.44512)
			)
		)
	)
	(zone
		(layer "In2.Cu")
		(hatch none 0.5)
		(connect_pads
			(clearance 0)
		)
		(min_thickness 0.25)
		(keepout
			(tracks not_allowed)
			(vias allowed)
			(pads allowed)
			(copperpour not_allowed)
			(footprints allowed)
		)
		(placement
			(enabled no)
			(sheetname "")
		)
		(fill
			(thermal_gap 0.5)
			(thermal_bridge_width 0.5)
			(island_removal_mode 0)
		)
		(polygon
			(pts
				(xy 299.07484 -201.325226) (xy 300.57344 -201.325226) (xy 300.57344 -201.845164) (xy 299.07484 -201.845164)
			)
		)
	)
	(zone
		(layer "In2.Cu")
		(hatch none 0.5)
		(connect_pads
			(clearance 0)
		)
		(min_thickness 0.25)
		(keepout
			(tracks not_allowed)
			(vias allowed)
			(pads allowed)
			(copperpour not_allowed)
			(footprints allowed)
		)
		(placement
			(enabled no)
			(sheetname "")
		)
		(fill
			(thermal_gap 0.5)
			(thermal_bridge_width 0.5)
			(island_removal_mode 0)
		)
		(polygon
			(pts
				(xy 268.898878 -254.025146) (xy 270.397478 -254.025146) (xy 270.397478 -254.545084) (xy 268.898878 -254.545084)
			)
		)
	)
	(zone
		(layer "In2.Cu")
		(hatch none 0.5)
		(connect_pads
			(clearance 0)
		)
		(min_thickness 0.25)
		(keepout
			(tracks not_allowed)
			(vias allowed)
			(pads allowed)
			(copperpour not_allowed)
			(footprints allowed)
		)
		(placement
			(enabled no)
			(sheetname "")
		)
		(fill
			(thermal_gap 0.5)
			(thermal_bridge_width 0.5)
			(island_removal_mode 0)
		)
		(polygon
			(pts
				(xy 426.706792 -295.675304) (xy 428.205392 -295.675304) (xy 428.205392 -296.195242) (xy 426.706792 -296.195242)
			)
		)
	)
	(zone
		(layer "In2.Cu")
		(hatch none 0.5)
		(connect_pads
			(clearance 0)
		)
		(min_thickness 0.25)
		(keepout
			(tracks not_allowed)
			(vias allowed)
			(pads allowed)
			(copperpour not_allowed)
			(footprints allowed)
		)
		(placement
			(enabled no)
			(sheetname "")
		)
		(fill
			(thermal_gap 0.5)
			(thermal_bridge_width 0.5)
			(island_removal_mode 0)
		)
		(polygon
			(pts
				(xy 171.22267 -241.275108) (xy 172.72127 -241.275108) (xy 172.72127 -241.795046) (xy 171.22267 -241.795046)
			)
		)
	)
	(zone
		(layer "In2.Cu")
		(hatch none 0.5)
		(connect_pads
			(clearance 0)
		)
		(min_thickness 0.25)
		(keepout
			(tracks not_allowed)
			(vias allowed)
			(pads allowed)
			(copperpour not_allowed)
			(footprints allowed)
		)
		(placement
			(enabled no)
			(sheetname "")
		)
		(fill
			(thermal_gap 0.5)
			(thermal_bridge_width 0.5)
			(island_removal_mode 0)
		)
		(polygon
			(pts
				(xy 430.80686 -277.8252) (xy 432.30546 -277.8252) (xy 432.30546 -278.345138) (xy 430.80686 -278.345138)
			)
		)
	)
	(zone
		(layer "In2.Cu")
		(hatch none 0.5)
		(connect_pads
			(clearance 0)
		)
		(min_thickness 0.25)
		(keepout
			(tracks not_allowed)
			(vias allowed)
			(pads allowed)
			(copperpour not_allowed)
			(footprints allowed)
		)
		(placement
			(enabled no)
			(sheetname "")
		)
		(fill
			(thermal_gap 0.5)
			(thermal_bridge_width 0.5)
			(island_removal_mode 0)
		)
		(polygon
			(pts
				(xy 276.442932 -250.625102) (xy 277.941532 -250.625102) (xy 277.941532 -251.14504) (xy 276.442932 -251.14504)
			)
		)
	)
	(zone
		(layer "In2.Cu")
		(hatch none 0.5)
		(connect_pads
			(clearance 0)
		)
		(min_thickness 0.25)
		(keepout
			(tracks not_allowed)
			(vias allowed)
			(pads allowed)
			(copperpour not_allowed)
			(footprints allowed)
		)
		(placement
			(enabled no)
			(sheetname "")
		)
		(fill
			(thermal_gap 0.5)
			(thermal_bridge_width 0.5)
			(island_removal_mode 0)
		)
		(polygon
			(pts
				(arc
					(start 20.904708 -16.442436)
					(mid 20.927026 -16.496318)
					(end 20.980908 -16.518636)
				)
				(arc
					(start 21.176488 -16.518636)
					(mid 21.198364 -16.515504)
					(end 21.218398 -16.50619)
				)
				(arc
					(start 21.512022 -16.313658)
					(mid 21.553678 -16.301256)
					(end 21.595334 -16.313658)
				)
				(arc
					(start 21.890228 -16.50619)
					(mid 21.910152 -16.515426)
					(end 21.931884 -16.518636)
				)
				(arc
					(start 22.126448 -16.518636)
					(mid 22.18033 -16.496318)
					(end 22.202648 -16.442436)
				)
				(arc
					(start 22.202648 -15.756636)
					(mid 22.18033 -15.702754)
					(end 22.126448 -15.680436)
				)
				(arc
					(start 21.931884 -15.680436)
					(mid 21.91014 -15.683604)
					(end 21.890228 -15.692882)
				)
				(arc
					(start 21.594064 -15.885668)
					(mid 21.55238 -15.89789)
					(end 21.510752 -15.885414)
				)
				(arc
					(start 21.217128 -15.692882)
					(mid 21.197204 -15.683646)
					(end 21.175472 -15.680436)
				)
				(arc
					(start 20.980908 -15.680436)
					(mid 20.927026 -15.702754)
					(end 20.904708 -15.756636)
				)
			)
		)
	)
	(zone
		(layer "In2.Cu")
		(hatch none 0.5)
		(connect_pads
			(clearance 0)
		)
		(min_thickness 0.25)
		(keepout
			(tracks not_allowed)
			(vias allowed)
			(pads allowed)
			(copperpour not_allowed)
			(footprints allowed)
		)
		(placement
			(enabled no)
			(sheetname "")
		)
		(fill
			(thermal_gap 0.5)
			(thermal_bridge_width 0.5)
			(island_removal_mode 0)
		)
		(polygon
			(pts
				(xy 434.250846 -210.67522) (xy 435.749446 -210.67522) (xy 435.749446 -211.195158) (xy 434.250846 -211.195158)
			)
		)
	)
	(zone
		(layer "In2.Cu")
		(hatch none 0.5)
		(connect_pads
			(clearance 0)
		)
		(min_thickness 0.25)
		(keepout
			(tracks not_allowed)
			(vias allowed)
			(pads allowed)
			(copperpour not_allowed)
			(footprints allowed)
		)
		(placement
			(enabled no)
			(sheetname "")
		)
		(fill
			(thermal_gap 0.5)
			(thermal_bridge_width 0.5)
			(island_removal_mode 0)
		)
		(polygon
			(pts
				(xy 163.678616 -276.125178) (xy 165.177216 -276.125178) (xy 165.177216 -276.645116) (xy 163.678616 -276.645116)
			)
		)
	)
	(zone
		(layer "In2.Cu")
		(hatch none 0.5)
		(connect_pads
			(clearance 0)
		)
		(min_thickness 0.25)
		(keepout
			(tracks not_allowed)
			(vias allowed)
			(pads allowed)
			(copperpour not_allowed)
			(footprints allowed)
		)
		(placement
			(enabled no)
			(sheetname "")
		)
		(fill
			(thermal_gap 0.5)
			(thermal_bridge_width 0.5)
			(island_removal_mode 0)
		)
		(polygon
			(pts
				(xy 167.778684 -269.325344) (xy 169.277284 -269.325344) (xy 169.277284 -269.845282) (xy 167.778684 -269.845282)
			)
		)
	)
	(zone
		(layer "In2.Cu")
		(hatch none 0.5)
		(connect_pads
			(clearance 0)
		)
		(min_thickness 0.25)
		(keepout
			(tracks not_allowed)
			(vias allowed)
			(pads allowed)
			(copperpour not_allowed)
			(footprints allowed)
		)
		(placement
			(enabled no)
			(sheetname "")
		)
		(fill
			(thermal_gap 0.5)
			(thermal_bridge_width 0.5)
			(island_removal_mode 0)
		)
		(polygon
			(pts
				(xy 201.398632 -224.275142) (xy 202.897232 -224.275142) (xy 202.897232 -224.79508) (xy 201.398632 -224.79508)
			)
		)
	)
	(zone
		(layer "In2.Cu")
		(hatch none 0.5)
		(connect_pads
			(clearance 0)
		)
		(min_thickness 0.25)
		(keepout
			(tracks not_allowed)
			(vias allowed)
			(pads allowed)
			(copperpour not_allowed)
			(footprints allowed)
		)
		(placement
			(enabled no)
			(sheetname "")
		)
		(fill
			(thermal_gap 0.5)
			(thermal_bridge_width 0.5)
			(island_removal_mode 0)
		)
		(polygon
			(pts
				(xy 272.342864 -283.77515) (xy 273.841464 -283.77515) (xy 273.841464 -284.295088) (xy 272.342864 -284.295088)
			)
		)
	)
	(zone
		(layer "In2.Cu")
		(hatch none 0.5)
		(connect_pads
			(clearance 0)
		)
		(min_thickness 0.25)
		(keepout
			(tracks not_allowed)
			(vias allowed)
			(pads allowed)
			(copperpour not_allowed)
			(footprints allowed)
		)
		(placement
			(enabled no)
			(sheetname "")
		)
		(fill
			(thermal_gap 0.5)
			(thermal_bridge_width 0.5)
			(island_removal_mode 0)
		)
		(polygon
			(pts
				(xy 197.954646 -206.425292) (xy 199.453246 -206.425292) (xy 199.453246 -206.94523) (xy 197.954646 -206.94523)
			)
		)
	)
	(zone
		(layer "In2.Cu")
		(hatch none 0.5)
		(connect_pads
			(clearance 0)
		)
		(min_thickness 0.25)
		(keepout
			(tracks not_allowed)
			(vias allowed)
			(pads allowed)
			(copperpour not_allowed)
			(footprints allowed)
		)
		(placement
			(enabled no)
			(sheetname "")
		)
		(fill
			(thermal_gap 0.5)
			(thermal_bridge_width 0.5)
			(island_removal_mode 0)
		)
		(polygon
			(pts
				(xy 279.886664 -201.325226) (xy 281.385264 -201.325226) (xy 281.385264 -201.845164) (xy 279.886664 -201.845164)
			)
		)
	)
	(zone
		(layer "In2.Cu")
		(hatch none 0.5)
		(connect_pads
			(clearance 0)
		)
		(min_thickness 0.25)
		(keepout
			(tracks not_allowed)
			(vias allowed)
			(pads allowed)
			(copperpour not_allowed)
			(footprints allowed)
		)
		(placement
			(enabled no)
			(sheetname "")
		)
		(fill
			(thermal_gap 0.5)
			(thermal_bridge_width 0.5)
			(island_removal_mode 0)
		)
		(polygon
			(pts
				(xy 186.310778 -239.57534) (xy 187.809378 -239.57534) (xy 187.809378 -240.095278) (xy 186.310778 -240.095278)
			)
		)
	)
	(zone
		(layer "In2.Cu")
		(hatch none 0.5)
		(connect_pads
			(clearance 0)
		)
		(min_thickness 0.25)
		(keepout
			(tracks not_allowed)
			(vias allowed)
			(pads allowed)
			(copperpour not_allowed)
			(footprints allowed)
		)
		(placement
			(enabled no)
			(sheetname "")
		)
		(fill
			(thermal_gap 0.5)
			(thermal_bridge_width 0.5)
			(island_removal_mode 0)
		)
		(polygon
			(pts
				(xy 190.410846 -282.925266) (xy 191.909446 -282.925266) (xy 191.909446 -283.445204) (xy 190.410846 -283.445204)
			)
		)
	)
	(zone
		(layer "In2.Cu")
		(hatch none 0.5)
		(connect_pads
			(clearance 0)
		)
		(min_thickness 0.25)
		(keepout
			(tracks not_allowed)
			(vias allowed)
			(pads allowed)
			(copperpour not_allowed)
			(footprints allowed)
		)
		(placement
			(enabled no)
			(sheetname "")
		)
		(fill
			(thermal_gap 0.5)
			(thermal_bridge_width 0.5)
			(island_removal_mode 0)
		)
		(polygon
			(pts
				(xy 28.50261 -203.025248) (xy 30.00121 -203.025248) (xy 30.00121 -203.545186) (xy 28.50261 -203.545186)
			)
		)
	)
	(zone
		(layer "In2.Cu")
		(hatch none 0.5)
		(connect_pads
			(clearance 0)
		)
		(min_thickness 0.25)
		(keepout
			(tracks not_allowed)
			(vias allowed)
			(pads allowed)
			(copperpour not_allowed)
			(footprints allowed)
		)
		(placement
			(enabled no)
			(sheetname "")
		)
		(fill
			(thermal_gap 0.5)
			(thermal_bridge_width 0.5)
			(island_removal_mode 0)
		)
		(polygon
			(pts
				(xy 299.07484 -316.925198) (xy 300.57344 -316.925198) (xy 300.57344 -317.445136) (xy 299.07484 -317.445136)
			)
		)
	)
	(zone
		(layer "In2.Cu")
		(hatch none 0.5)
		(connect_pads
			(clearance 0)
		)
		(min_thickness 0.25)
		(keepout
			(tracks not_allowed)
			(vias allowed)
			(pads allowed)
			(copperpour not_allowed)
			(footprints allowed)
		)
		(placement
			(enabled no)
			(sheetname "")
		)
		(fill
			(thermal_gap 0.5)
			(thermal_bridge_width 0.5)
			(island_removal_mode 0)
		)
		(polygon
			(pts
				(xy 175.322738 -240.425224) (xy 176.821338 -240.425224) (xy 176.821338 -240.945162) (xy 175.322738 -240.945162)
			)
		)
	)
	(zone
		(layer "In2.Cu")
		(hatch none 0.5)
		(connect_pads
			(clearance 0)
		)
		(min_thickness 0.25)
		(keepout
			(tracks not_allowed)
			(vias allowed)
			(pads allowed)
			(copperpour not_allowed)
			(footprints allowed)
		)
		(placement
			(enabled no)
			(sheetname "")
		)
		(fill
			(thermal_gap 0.5)
			(thermal_bridge_width 0.5)
			(island_removal_mode 0)
		)
		(polygon
			(pts
				(xy 299.07484 -237.875318) (xy 300.57344 -237.875318) (xy 300.57344 -238.395256) (xy 299.07484 -238.395256)
			)
		)
	)
	(zone
		(layer "In2.Cu")
		(hatch none 0.5)
		(connect_pads
			(clearance 0)
		)
		(min_thickness 0.25)
		(keepout
			(tracks not_allowed)
			(vias allowed)
			(pads allowed)
			(copperpour not_allowed)
			(footprints allowed)
		)
		(placement
			(enabled no)
			(sheetname "")
		)
		(fill
			(thermal_gap 0.5)
			(thermal_bridge_width 0.5)
			(island_removal_mode 0)
		)
		(polygon
			(pts
				(xy 28.50261 -285.475172) (xy 30.00121 -285.475172) (xy 30.00121 -285.99511) (xy 28.50261 -285.99511)
			)
		)
	)
	(zone
		(layer "In2.Cu")
		(hatch none 0.5)
		(connect_pads
			(clearance 0)
		)
		(min_thickness 0.25)
		(keepout
			(tracks not_allowed)
			(vias allowed)
			(pads allowed)
			(copperpour not_allowed)
			(footprints allowed)
		)
		(placement
			(enabled no)
			(sheetname "")
		)
		(fill
			(thermal_gap 0.5)
			(thermal_bridge_width 0.5)
			(island_removal_mode 0)
		)
		(polygon
			(pts
				(xy 175.322738 -282.925266) (xy 176.821338 -282.925266) (xy 176.821338 -283.445204) (xy 175.322738 -283.445204)
			)
		)
	)
	(zone
		(layer "In2.Cu")
		(hatch none 0.5)
		(connect_pads
			(clearance 0)
		)
		(min_thickness 0.25)
		(keepout
			(tracks not_allowed)
			(vias allowed)
			(pads allowed)
			(copperpour not_allowed)
			(footprints allowed)
		)
		(placement
			(enabled no)
			(sheetname "")
		)
		(fill
			(thermal_gap 0.5)
			(thermal_bridge_width 0.5)
			(island_removal_mode 0)
		)
		(polygon
			(pts
				(xy 291.530786 -264.225278) (xy 293.029386 -264.225278) (xy 293.029386 -264.745216) (xy 291.530786 -264.745216)
			)
		)
	)
	(zone
		(layer "In2.Cu")
		(hatch none 0.5)
		(connect_pads
			(clearance 0)
		)
		(min_thickness 0.25)
		(keepout
			(tracks not_allowed)
			(vias allowed)
			(pads allowed)
			(copperpour not_allowed)
			(footprints allowed)
		)
		(placement
			(enabled no)
			(sheetname "")
		)
		(fill
			(thermal_gap 0.5)
			(thermal_bridge_width 0.5)
			(island_removal_mode 0)
		)
		(polygon
			(pts
				(xy 306.618894 -198.77532) (xy 308.117494 -198.77532) (xy 308.117494 -199.295258) (xy 306.618894 -199.295258)
			)
		)
	)
	(zone
		(layer "In2.Cu")
		(hatch none 0.5)
		(connect_pads
			(clearance 0)
		)
		(min_thickness 0.25)
		(keepout
			(tracks not_allowed)
			(vias allowed)
			(pads allowed)
			(copperpour not_allowed)
			(footprints allowed)
		)
		(placement
			(enabled no)
			(sheetname "")
		)
		(fill
			(thermal_gap 0.5)
			(thermal_bridge_width 0.5)
			(island_removal_mode 0)
		)
		(polygon
			(pts
				(xy 423.262806 -242.125246) (xy 424.761406 -242.125246) (xy 424.761406 -242.645184) (xy 423.262806 -242.645184)
			)
		)
	)
	(zone
		(layer "In2.Cu")
		(hatch none 0.5)
		(connect_pads
			(clearance 0)
		)
		(min_thickness 0.25)
		(keepout
			(tracks not_allowed)
			(vias allowed)
			(pads allowed)
			(copperpour not_allowed)
			(footprints allowed)
		)
		(placement
			(enabled no)
			(sheetname "")
		)
		(fill
			(thermal_gap 0.5)
			(thermal_bridge_width 0.5)
			(island_removal_mode 0)
		)
		(polygon
			(pts
				(xy 306.618894 -229.375208) (xy 308.117494 -229.375208) (xy 308.117494 -229.895146) (xy 306.618894 -229.895146)
			)
		)
	)
	(zone
		(layer "In2.Cu")
		(hatch none 0.5)
		(connect_pads
			(clearance 0)
		)
		(min_thickness 0.25)
		(keepout
			(tracks not_allowed)
			(vias allowed)
			(pads allowed)
			(copperpour not_allowed)
			(footprints allowed)
		)
		(placement
			(enabled no)
			(sheetname "")
		)
		(fill
			(thermal_gap 0.5)
			(thermal_bridge_width 0.5)
			(island_removal_mode 0)
		)
		(polygon
			(pts
				(xy 190.410846 -292.27526) (xy 191.909446 -292.27526) (xy 191.909446 -292.795198) (xy 190.410846 -292.795198)
			)
		)
	)
	(zone
		(layer "In2.Cu")
		(hatch none 0.5)
		(connect_pads
			(clearance 0)
		)
		(min_thickness 0.25)
		(keepout
			(tracks not_allowed)
			(vias allowed)
			(pads allowed)
			(copperpour not_allowed)
			(footprints allowed)
		)
		(placement
			(enabled no)
			(sheetname "")
		)
		(fill
			(thermal_gap 0.5)
			(thermal_bridge_width 0.5)
			(island_removal_mode 0)
		)
		(polygon
			(pts
				(xy 190.410846 -234.475274) (xy 191.909446 -234.475274) (xy 191.909446 -234.995212) (xy 190.410846 -234.995212)
			)
		)
	)
	(zone
		(layer "In2.Cu")
		(hatch none 0.5)
		(connect_pads
			(clearance 0)
		)
		(min_thickness 0.25)
		(keepout
			(tracks not_allowed)
			(vias allowed)
			(pads allowed)
			(copperpour not_allowed)
			(footprints allowed)
		)
		(placement
			(enabled no)
			(sheetname "")
		)
		(fill
			(thermal_gap 0.5)
			(thermal_bridge_width 0.5)
			(island_removal_mode 0)
		)
		(polygon
			(pts
				(xy 20.95881 -243.825268) (xy 22.45741 -243.825268) (xy 22.45741 -244.345206) (xy 20.95881 -244.345206)
			)
		)
	)
	(zone
		(layer "In2.Cu")
		(hatch none 0.5)
		(connect_pads
			(clearance 0)
		)
		(min_thickness 0.25)
		(keepout
			(tracks not_allowed)
			(vias allowed)
			(pads allowed)
			(copperpour not_allowed)
			(footprints allowed)
		)
		(placement
			(enabled no)
			(sheetname "")
		)
		(fill
			(thermal_gap 0.5)
			(thermal_bridge_width 0.5)
			(island_removal_mode 0)
		)
		(polygon
			(pts
				(xy 302.518826 -214.925148) (xy 304.017426 -214.925148) (xy 304.017426 -215.445086) (xy 302.518826 -215.445086)
			)
		)
	)
	(zone
		(layer "In2.Cu")
		(hatch none 0.5)
		(connect_pads
			(clearance 0)
		)
		(min_thickness 0.25)
		(keepout
			(tracks not_allowed)
			(vias allowed)
			(pads allowed)
			(copperpour not_allowed)
			(footprints allowed)
		)
		(placement
			(enabled no)
			(sheetname "")
		)
		(fill
			(thermal_gap 0.5)
			(thermal_bridge_width 0.5)
			(island_removal_mode 0)
		)
		(polygon
			(pts
				(xy 411.618684 -297.375326) (xy 413.117284 -297.375326) (xy 413.117284 -297.895264) (xy 411.618684 -297.895264)
			)
		)
	)
	(zone
		(layer "In2.Cu")
		(hatch none 0.5)
		(connect_pads
			(clearance 0)
		)
		(min_thickness 0.25)
		(keepout
			(tracks not_allowed)
			(vias allowed)
			(pads allowed)
			(copperpour not_allowed)
			(footprints allowed)
		)
		(placement
			(enabled no)
			(sheetname "")
		)
		(fill
			(thermal_gap 0.5)
			(thermal_bridge_width 0.5)
			(island_removal_mode 0)
		)
		(polygon
			(pts
				(xy 36.046664 -294.825166) (xy 37.545264 -294.825166) (xy 37.545264 -295.345104) (xy 36.046664 -295.345104)
			)
		)
	)
	(zone
		(layer "In2.Cu")
		(hatch none 0.5)
		(connect_pads
			(clearance 0)
		)
		(min_thickness 0.25)
		(keepout
			(tracks allowed)
			(vias allowed)
			(pads allowed)
			(copperpour allowed)
			(footprints allowed)
		)
		(placement
			(enabled no)
			(sheetname "")
		)
		(fill
			(thermal_gap 0.5)
			(thermal_bridge_width 0.5)
			(island_removal_mode 0)
		)
		(polygon
			(pts
				(xy 40.31361 -349.859092) (xy 40.31361 -349.236792) (xy 40.86479 -349.236792) (xy 40.86479 -349.859092)
			)
		)
	)
	(zone
		(layer "In2.Cu")
		(hatch none 0.5)
		(connect_pads
			(clearance 0)
		)
		(min_thickness 0.25)
		(keepout
			(tracks not_allowed)
			(vias allowed)
			(pads allowed)
			(copperpour not_allowed)
			(footprints allowed)
		)
		(placement
			(enabled no)
			(sheetname "")
		)
		(fill
			(thermal_gap 0.5)
			(thermal_bridge_width 0.5)
			(island_removal_mode 0)
		)
		(polygon
			(pts
				(xy 415.718752 -198.77532) (xy 417.217352 -198.77532) (xy 417.217352 -199.295258) (xy 415.718752 -199.295258)
			)
		)
	)
	(zone
		(layer "In2.Cu")
		(hatch none 0.5)
		(connect_pads
			(clearance 0)
		)
		(min_thickness 0.25)
		(keepout
			(tracks not_allowed)
			(vias allowed)
			(pads allowed)
			(copperpour not_allowed)
			(footprints allowed)
		)
		(placement
			(enabled no)
			(sheetname "")
		)
		(fill
			(thermal_gap 0.5)
			(thermal_bridge_width 0.5)
			(island_removal_mode 0)
		)
		(polygon
			(pts
				(xy 434.250846 -248.075196) (xy 435.749446 -248.075196) (xy 435.749446 -248.595134) (xy 434.250846 -248.595134)
			)
		)
	)
	(zone
		(layer "In2.Cu")
		(hatch none 0.5)
		(connect_pads
			(clearance 0)
		)
		(min_thickness 0.25)
		(keepout
			(tracks not_allowed)
			(vias allowed)
			(pads allowed)
			(copperpour not_allowed)
			(footprints allowed)
		)
		(placement
			(enabled no)
			(sheetname "")
		)
		(fill
			(thermal_gap 0.5)
			(thermal_bridge_width 0.5)
			(island_removal_mode 0)
		)
		(polygon
			(pts
				(xy 171.22267 -302.475138) (xy 172.72127 -302.475138) (xy 172.72127 -302.995076) (xy 171.22267 -302.995076)
			)
		)
	)
	(zone
		(layer "In2.Cu")
		(hatch none 0.5)
		(connect_pads
			(clearance 0)
		)
		(min_thickness 0.25)
		(keepout
			(tracks not_allowed)
			(vias allowed)
			(pads allowed)
			(copperpour not_allowed)
			(footprints allowed)
		)
		(placement
			(enabled no)
			(sheetname "")
		)
		(fill
			(thermal_gap 0.5)
			(thermal_bridge_width 0.5)
			(island_removal_mode 0)
		)
		(polygon
			(pts
				(arc
					(start 115.662456 -408.923998)
					(mid 115.68238 -408.933234)
					(end 115.704112 -408.936444)
				)
				(arc
					(start 115.898676 -408.936444)
					(mid 115.952558 -408.914126)
					(end 115.974876 -408.860244)
				)
				(arc
					(start 115.974876 -408.174444)
					(mid 115.952558 -408.120562)
					(end 115.898676 -408.098244)
				)
				(arc
					(start 115.704112 -408.098244)
					(mid 115.682368 -408.101412)
					(end 115.662456 -408.11069)
				)
				(arc
					(start 115.366292 -408.303476)
					(mid 115.324608 -408.315698)
					(end 115.28298 -408.303222)
				)
				(arc
					(start 114.989356 -408.11069)
					(mid 114.969432 -408.101454)
					(end 114.9477 -408.098244)
				)
				(arc
					(start 114.753136 -408.098244)
					(mid 114.699254 -408.120562)
					(end 114.676936 -408.174444)
				)
				(arc
					(start 114.676936 -408.860244)
					(mid 114.699254 -408.914126)
					(end 114.753136 -408.936444)
				)
				(arc
					(start 114.94897 -408.936444)
					(mid 114.970714 -408.933276)
					(end 114.990626 -408.923998)
				)
				(arc
					(start 115.28425 -408.731466)
					(mid 115.325906 -408.719064)
					(end 115.367562 -408.731466)
				)
			)
		)
	)
	(zone
		(layer "In2.Cu")
		(hatch none 0.5)
		(connect_pads
			(clearance 0)
		)
		(min_thickness 0.25)
		(keepout
			(tracks not_allowed)
			(vias allowed)
			(pads allowed)
			(copperpour not_allowed)
			(footprints allowed)
		)
		(placement
			(enabled no)
			(sheetname "")
		)
		(fill
			(thermal_gap 0.5)
			(thermal_bridge_width 0.5)
			(island_removal_mode 0)
		)
		(polygon
			(pts
				(xy 193.854578 -297.375326) (xy 195.353178 -297.375326) (xy 195.353178 -297.895264) (xy 193.854578 -297.895264)
			)
		)
	)
	(zone
		(layer "In2.Cu")
		(hatch none 0.5)
		(connect_pads
			(clearance 0)
		)
		(min_thickness 0.25)
		(keepout
			(tracks not_allowed)
			(vias allowed)
			(pads allowed)
			(copperpour not_allowed)
			(footprints allowed)
		)
		(placement
			(enabled no)
			(sheetname "")
		)
		(fill
			(thermal_gap 0.5)
			(thermal_bridge_width 0.5)
			(island_removal_mode 0)
		)
		(polygon
			(pts
				(xy 441.7949 -229.375208) (xy 443.2935 -229.375208) (xy 443.2935 -229.895146) (xy 441.7949 -229.895146)
			)
		)
	)
	(zone
		(layer "In2.Cu")
		(hatch none 0.5)
		(connect_pads
			(clearance 0)
		)
		(min_thickness 0.25)
		(keepout
			(tracks not_allowed)
			(vias allowed)
			(pads allowed)
			(copperpour not_allowed)
			(footprints allowed)
		)
		(placement
			(enabled no)
			(sheetname "")
		)
		(fill
			(thermal_gap 0.5)
			(thermal_bridge_width 0.5)
			(island_removal_mode 0)
		)
		(polygon
			(pts
				(xy 268.898878 -208.125314) (xy 270.397478 -208.125314) (xy 270.397478 -208.645252) (xy 268.898878 -208.645252)
			)
		)
	)
	(zone
		(layer "In2.Cu")
		(hatch none 0.5)
		(connect_pads
			(clearance 0)
		)
		(min_thickness 0.25)
		(keepout
			(tracks not_allowed)
			(vias allowed)
			(pads allowed)
			(copperpour not_allowed)
			(footprints allowed)
		)
		(placement
			(enabled no)
			(sheetname "")
		)
		(fill
			(thermal_gap 0.5)
			(thermal_bridge_width 0.5)
			(island_removal_mode 0)
		)
		(polygon
			(pts
				(xy 175.322738 -219.17533) (xy 176.821338 -219.17533) (xy 176.821338 -219.695268) (xy 175.322738 -219.695268)
			)
		)
	)
	(zone
		(layer "In2.Cu")
		(hatch none 0.5)
		(connect_pads
			(clearance 0)
		)
		(min_thickness 0.25)
		(keepout
			(tracks allowed)
			(vias allowed)
			(pads allowed)
			(copperpour allowed)
			(footprints allowed)
		)
		(placement
			(enabled no)
			(sheetname "")
		)
		(fill
			(thermal_gap 0.5)
			(thermal_bridge_width 0.5)
			(island_removal_mode 0)
		)
		(polygon
			(pts
				(xy 75.761596 -338.21497) (xy 75.761596 -337.59267) (xy 76.312776 -337.59267) (xy 76.312776 -338.21497)
			)
		)
	)
	(zone
		(layer "In2.Cu")
		(hatch none 0.5)
		(connect_pads
			(clearance 0)
		)
		(min_thickness 0.25)
		(keepout
			(tracks not_allowed)
			(vias allowed)
			(pads allowed)
			(copperpour not_allowed)
			(footprints allowed)
		)
		(placement
			(enabled no)
			(sheetname "")
		)
		(fill
			(thermal_gap 0.5)
			(thermal_bridge_width 0.5)
			(island_removal_mode 0)
		)
		(polygon
			(pts
				(xy 426.706792 -253.175262) (xy 428.205392 -253.175262) (xy 428.205392 -253.6952) (xy 426.706792 -253.6952)
			)
		)
	)
	(zone
		(layer "In2.Cu")
		(hatch none 0.5)
		(connect_pads
			(clearance 0)
		)
		(min_thickness 0.25)
		(keepout
			(tracks not_allowed)
			(vias allowed)
			(pads allowed)
			(copperpour not_allowed)
			(footprints allowed)
		)
		(placement
			(enabled no)
			(sheetname "")
		)
		(fill
			(thermal_gap 0.5)
			(thermal_bridge_width 0.5)
			(island_removal_mode 0)
		)
		(polygon
			(pts
				(xy 15.01013 -107.821476) (xy 15.276068 -107.821476) (xy 15.276068 -107.88142)
				(arc
					(start 15.416276 -107.88142)
					(mid 15.486158 -107.852211)
					(end 15.514828 -107.782106)
				)
				(arc
					(start 15.514828 -107.480862)
					(mid 15.486158 -107.410757)
					(end 15.416276 -107.381548)
				)
				(xy 15.276068 -107.381548) (xy 15.276068 -107.441492) (xy 15.01013 -107.441492)
			)
		)
	)
	(zone
		(layer "In2.Cu")
		(hatch none 0.5)
		(connect_pads
			(clearance 0)
		)
		(min_thickness 0.25)
		(keepout
			(tracks not_allowed)
			(vias allowed)
			(pads allowed)
			(copperpour not_allowed)
			(footprints allowed)
		)
		(placement
			(enabled no)
			(sheetname "")
		)
		(fill
			(thermal_gap 0.5)
			(thermal_bridge_width 0.5)
			(island_removal_mode 0)
		)
		(polygon
			(pts
				(xy 190.410846 -237.875318) (xy 191.909446 -237.875318) (xy 191.909446 -238.395256) (xy 190.410846 -238.395256)
			)
		)
	)
	(zone
		(layer "In2.Cu")
		(hatch none 0.5)
		(connect_pads
			(clearance 0)
		)
		(min_thickness 0.25)
		(keepout
			(tracks not_allowed)
			(vias allowed)
			(pads allowed)
			(copperpour not_allowed)
			(footprints allowed)
		)
		(placement
			(enabled no)
			(sheetname "")
		)
		(fill
			(thermal_gap 0.5)
			(thermal_bridge_width 0.5)
			(island_removal_mode 0)
		)
		(polygon
			(pts
				(xy 423.262806 -277.8252) (xy 424.761406 -277.8252) (xy 424.761406 -278.345138) (xy 423.262806 -278.345138)
			)
		)
	)
	(zone
		(layer "In2.Cu")
		(hatch none 0.5)
		(connect_pads
			(clearance 0)
		)
		(min_thickness 0.25)
		(keepout
			(tracks not_allowed)
			(vias allowed)
			(pads allowed)
			(copperpour not_allowed)
			(footprints allowed)
		)
		(placement
			(enabled no)
			(sheetname "")
		)
		(fill
			(thermal_gap 0.5)
			(thermal_bridge_width 0.5)
			(island_removal_mode 0)
		)
		(polygon
			(pts
				(xy 283.986732 -262.525256) (xy 285.485332 -262.525256) (xy 285.485332 -263.045194) (xy 283.986732 -263.045194)
			)
		)
	)
	(zone
		(layer "In2.Cu")
		(hatch none 0.5)
		(connect_pads
			(clearance 0)
		)
		(min_thickness 0.25)
		(keepout
			(tracks not_allowed)
			(vias allowed)
			(pads allowed)
			(copperpour not_allowed)
			(footprints allowed)
		)
		(placement
			(enabled no)
			(sheetname "")
		)
		(fill
			(thermal_gap 0.5)
			(thermal_bridge_width 0.5)
			(island_removal_mode 0)
		)
		(polygon
			(pts
				(xy 276.442932 -273.575272) (xy 277.941532 -273.575272) (xy 277.941532 -274.09521) (xy 276.442932 -274.09521)
			)
		)
	)
	(zone
		(layer "In2.Cu")
		(hatch none 0.5)
		(connect_pads
			(clearance 0)
		)
		(min_thickness 0.25)
		(keepout
			(tracks not_allowed)
			(vias allowed)
			(pads allowed)
			(copperpour not_allowed)
			(footprints allowed)
		)
		(placement
			(enabled no)
			(sheetname "")
		)
		(fill
			(thermal_gap 0.5)
			(thermal_bridge_width 0.5)
			(island_removal_mode 0)
		)
		(polygon
			(pts
				(xy 171.22267 -272.725134) (xy 172.72127 -272.725134) (xy 172.72127 -273.245072) (xy 171.22267 -273.245072)
			)
		)
	)
	(zone
		(layer "In2.Cu")
		(hatch none 0.5)
		(connect_pads
			(clearance 0)
		)
		(min_thickness 0.25)
		(keepout
			(tracks not_allowed)
			(vias allowed)
			(pads allowed)
			(copperpour not_allowed)
			(footprints allowed)
		)
		(placement
			(enabled no)
			(sheetname "")
		)
		(fill
			(thermal_gap 0.5)
			(thermal_bridge_width 0.5)
			(island_removal_mode 0)
		)
		(polygon
			(pts
				(xy 51.134772 -260.825234) (xy 52.633372 -260.825234) (xy 52.633372 -261.345172) (xy 51.134772 -261.345172)
			)
		)
	)
	(zone
		(layer "In2.Cu")
		(hatch none 0.5)
		(connect_pads
			(clearance 0)
		)
		(min_thickness 0.25)
		(keepout
			(tracks not_allowed)
			(vias allowed)
			(pads allowed)
			(copperpour not_allowed)
			(footprints allowed)
		)
		(placement
			(enabled no)
			(sheetname "")
		)
		(fill
			(thermal_gap 0.5)
			(thermal_bridge_width 0.5)
			(island_removal_mode 0)
		)
		(polygon
			(pts
				(xy 291.530786 -234.475274) (xy 293.029386 -234.475274) (xy 293.029386 -234.995212) (xy 291.530786 -234.995212)
			)
		)
	)
	(zone
		(layer "In2.Cu")
		(hatch none 0.5)
		(connect_pads
			(clearance 0)
		)
		(min_thickness 0.25)
		(keepout
			(tracks not_allowed)
			(vias allowed)
			(pads allowed)
			(copperpour not_allowed)
			(footprints allowed)
		)
		(placement
			(enabled no)
			(sheetname "")
		)
		(fill
			(thermal_gap 0.5)
			(thermal_bridge_width 0.5)
			(island_removal_mode 0)
		)
		(polygon
			(pts
				(xy 171.22267 -203.875132) (xy 172.72127 -203.875132) (xy 172.72127 -204.39507) (xy 171.22267 -204.39507)
			)
		)
	)
	(zone
		(layer "In2.Cu")
		(hatch none 0.5)
		(connect_pads
			(clearance 0)
		)
		(min_thickness 0.25)
		(keepout
			(tracks not_allowed)
			(vias allowed)
			(pads allowed)
			(copperpour not_allowed)
			(footprints allowed)
		)
		(placement
			(enabled no)
			(sheetname "")
		)
		(fill
			(thermal_gap 0.5)
			(thermal_bridge_width 0.5)
			(island_removal_mode 0)
		)
		(polygon
			(pts
				(xy 441.7949 -218.325192) (xy 443.2935 -218.325192) (xy 443.2935 -218.84513) (xy 441.7949 -218.84513)
			)
		)
	)
	(zone
		(layer "In2.Cu")
		(hatch none 0.5)
		(connect_pads
			(clearance 0)
		)
		(min_thickness 0.25)
		(keepout
			(tracks not_allowed)
			(vias allowed)
			(pads allowed)
			(copperpour not_allowed)
			(footprints allowed)
		)
		(placement
			(enabled no)
			(sheetname "")
		)
		(fill
			(thermal_gap 0.5)
			(thermal_bridge_width 0.5)
			(island_removal_mode 0)
		)
		(polygon
			(pts
				(xy 287.430718 -313.525154) (xy 288.929318 -313.525154) (xy 288.929318 -314.045092) (xy 287.430718 -314.045092)
			)
		)
	)
	(zone
		(layer "In2.Cu")
		(hatch none 0.5)
		(connect_pads
			(clearance 0)
		)
		(min_thickness 0.25)
		(keepout
			(tracks not_allowed)
			(vias allowed)
			(pads allowed)
			(copperpour not_allowed)
			(footprints allowed)
		)
		(placement
			(enabled no)
			(sheetname "")
		)
		(fill
			(thermal_gap 0.5)
			(thermal_bridge_width 0.5)
			(island_removal_mode 0)
		)
		(polygon
			(pts
				(xy 16.858742 -310.12511) (xy 18.357342 -310.12511) (xy 18.357342 -310.645048) (xy 16.858742 -310.645048)
			)
		)
	)
	(zone
		(layer "In2.Cu")
		(hatch none 0.5)
		(connect_pads
			(clearance 0)
		)
		(min_thickness 0.25)
		(keepout
			(tracks not_allowed)
			(vias allowed)
			(pads allowed)
			(copperpour not_allowed)
			(footprints allowed)
		)
		(placement
			(enabled no)
			(sheetname "")
		)
		(fill
			(thermal_gap 0.5)
			(thermal_bridge_width 0.5)
			(island_removal_mode 0)
		)
		(polygon
			(pts
				(xy 12.53617 -106.69397)
				(arc
					(start 12.53617 -106.834178)
					(mid 12.565379 -106.90406)
					(end 12.635484 -106.93273)
				)
				(arc
					(start 12.936728 -106.93273)
					(mid 13.006833 -106.90406)
					(end 13.036042 -106.834178)
				)
				(xy 13.036042 -106.69397) (xy 12.976098 -106.69397)
				(arc
					(start 12.976098 -106.124756)
					(mid 13.019597 -106.088387)
					(end 13.036042 -106.034078)
				)
				(arc
					(start 13.036042 -105.773982)
					(mid 13.019723 -105.71959)
					(end 12.976098 -105.683304)
				)
				(xy 12.976098 -105.11409) (xy 13.036042 -105.11409)
				(arc
					(start 13.036042 -104.973882)
					(mid 13.006833 -104.904)
					(end 12.936728 -104.87533)
				)
				(arc
					(start 12.635484 -104.87533)
					(mid 12.565379 -104.904)
					(end 12.53617 -104.973882)
				)
				(xy 12.53617 -105.11409) (xy 12.596114 -105.11409)
				(arc
					(start 12.596114 -105.683304)
					(mid 12.552615 -105.719673)
					(end 12.53617 -105.773982)
				)
				(arc
					(start 12.53617 -106.034078)
					(mid 12.552489 -106.08847)
					(end 12.596114 -106.124756)
				)
				(xy 12.596114 -106.69397)
			)
		)
	)
	(zone
		(layer "In2.Cu")
		(hatch none 0.5)
		(connect_pads
			(clearance 0)
		)
		(min_thickness 0.25)
		(keepout
			(tracks not_allowed)
			(vias allowed)
			(pads allowed)
			(copperpour not_allowed)
			(footprints allowed)
		)
		(placement
			(enabled no)
			(sheetname "")
		)
		(fill
			(thermal_gap 0.5)
			(thermal_bridge_width 0.5)
			(island_removal_mode 0)
		)
		(polygon
			(pts
				(xy 175.322738 -214.075264) (xy 176.821338 -214.075264) (xy 176.821338 -214.595202) (xy 175.322738 -214.595202)
			)
		)
	)
	(zone
		(layer "In2.Cu")
		(hatch none 0.5)
		(connect_pads
			(clearance 0)
		)
		(min_thickness 0.25)
		(keepout
			(tracks not_allowed)
			(vias allowed)
			(pads allowed)
			(copperpour not_allowed)
			(footprints allowed)
		)
		(placement
			(enabled no)
			(sheetname "")
		)
		(fill
			(thermal_gap 0.5)
			(thermal_bridge_width 0.5)
			(island_removal_mode 0)
		)
		(polygon
			(pts
				(xy 449.3387 -205.575154) (xy 450.8373 -205.575154) (xy 450.8373 -206.095092) (xy 449.3387 -206.095092)
			)
		)
	)
	(zone
		(layer "In2.Cu")
		(hatch none 0.5)
		(connect_pads
			(clearance 0)
		)
		(min_thickness 0.25)
		(keepout
			(tracks not_allowed)
			(vias allowed)
			(pads allowed)
			(copperpour not_allowed)
			(footprints allowed)
		)
		(placement
			(enabled no)
			(sheetname "")
		)
		(fill
			(thermal_gap 0.5)
			(thermal_bridge_width 0.5)
			(island_removal_mode 0)
		)
		(polygon
			(pts
				(xy 201.398632 -202.17511) (xy 202.897232 -202.17511) (xy 202.897232 -202.695048) (xy 201.398632 -202.695048)
			)
		)
	)
	(zone
		(layer "In2.Cu")
		(hatch none 0.5)
		(connect_pads
			(clearance 0)
		)
		(min_thickness 0.25)
		(keepout
			(tracks not_allowed)
			(vias allowed)
			(pads allowed)
			(copperpour not_allowed)
			(footprints allowed)
		)
		(placement
			(enabled no)
			(sheetname "")
		)
		(fill
			(thermal_gap 0.5)
			(thermal_bridge_width 0.5)
			(island_removal_mode 0)
		)
		(polygon
			(pts
				(xy 51.134772 -225.12528) (xy 52.633372 -225.12528) (xy 52.633372 -225.645218) (xy 51.134772 -225.645218)
			)
		)
	)
	(zone
		(layer "In2.Cu")
		(hatch none 0.5)
		(connect_pads
			(clearance 0)
		)
		(min_thickness 0.25)
		(keepout
			(tracks not_allowed)
			(vias allowed)
			(pads allowed)
			(copperpour not_allowed)
			(footprints allowed)
		)
		(placement
			(enabled no)
			(sheetname "")
		)
		(fill
			(thermal_gap 0.5)
			(thermal_bridge_width 0.5)
			(island_removal_mode 0)
		)
		(polygon
			(pts
				(xy 268.898878 -236.175296) (xy 270.397478 -236.175296) (xy 270.397478 -236.695234) (xy 268.898878 -236.695234)
			)
		)
	)
	(zone
		(layer "In2.Cu")
		(hatch none 0.5)
		(connect_pads
			(clearance 0)
		)
		(min_thickness 0.25)
		(keepout
			(tracks not_allowed)
			(vias allowed)
			(pads allowed)
			(copperpour not_allowed)
			(footprints allowed)
		)
		(placement
			(enabled no)
			(sheetname "")
		)
		(fill
			(thermal_gap 0.5)
			(thermal_bridge_width 0.5)
			(island_removal_mode 0)
		)
		(polygon
			(pts
				(xy 201.398632 -276.125178) (xy 202.897232 -276.125178) (xy 202.897232 -276.645116) (xy 201.398632 -276.645116)
			)
		)
	)
	(zone
		(layer "In2.Cu")
		(hatch none 0.5)
		(connect_pads
			(clearance 0)
		)
		(min_thickness 0.25)
		(keepout
			(tracks not_allowed)
			(vias allowed)
			(pads allowed)
			(copperpour not_allowed)
			(footprints allowed)
		)
		(placement
			(enabled no)
			(sheetname "")
		)
		(fill
			(thermal_gap 0.5)
			(thermal_bridge_width 0.5)
			(island_removal_mode 0)
		)
		(polygon
			(pts
				(xy 24.402542 -278.675338) (xy 25.901142 -278.675338) (xy 25.901142 -279.195276) (xy 24.402542 -279.195276)
			)
		)
	)
	(zone
		(layer "In2.Cu")
		(hatch none 0.5)
		(connect_pads
			(clearance 0)
		)
		(min_thickness 0.25)
		(keepout
			(tracks not_allowed)
			(vias allowed)
			(pads allowed)
			(copperpour not_allowed)
			(footprints allowed)
		)
		(placement
			(enabled no)
			(sheetname "")
		)
		(fill
			(thermal_gap 0.5)
			(thermal_bridge_width 0.5)
			(island_removal_mode 0)
		)
		(polygon
			(pts
				(xy 54.578758 -203.875132) (xy 56.077358 -203.875132) (xy 56.077358 -204.39507) (xy 54.578758 -204.39507)
			)
		)
	)
	(zone
		(layer "In2.Cu")
		(hatch none 0.5)
		(connect_pads
			(clearance 0)
		)
		(min_thickness 0.25)
		(keepout
			(tracks not_allowed)
			(vias allowed)
			(pads allowed)
			(copperpour not_allowed)
			(footprints allowed)
		)
		(placement
			(enabled no)
			(sheetname "")
		)
		(fill
			(thermal_gap 0.5)
			(thermal_bridge_width 0.5)
			(island_removal_mode 0)
		)
		(polygon
			(pts
				(xy 445.894968 -310.975248) (xy 447.393568 -310.975248) (xy 447.393568 -311.495186) (xy 445.894968 -311.495186)
			)
		)
	)
	(zone
		(layer "In2.Cu")
		(hatch none 0.5)
		(connect_pads
			(clearance 0)
		)
		(min_thickness 0.25)
		(keepout
			(tracks not_allowed)
			(vias allowed)
			(pads allowed)
			(copperpour not_allowed)
			(footprints allowed)
		)
		(placement
			(enabled no)
			(sheetname "")
		)
		(fill
			(thermal_gap 0.5)
			(thermal_bridge_width 0.5)
			(island_removal_mode 0)
		)
		(polygon
			(pts
				(xy 190.410846 -264.225278) (xy 191.909446 -264.225278) (xy 191.909446 -264.745216) (xy 190.410846 -264.745216)
			)
		)
	)
	(zone
		(layer "In2.Cu")
		(hatch none 0.5)
		(connect_pads
			(clearance 0)
		)
		(min_thickness 0.25)
		(keepout
			(tracks not_allowed)
			(vias allowed)
			(pads allowed)
			(copperpour not_allowed)
			(footprints allowed)
		)
		(placement
			(enabled no)
			(sheetname "")
		)
		(fill
			(thermal_gap 0.5)
			(thermal_bridge_width 0.5)
			(island_removal_mode 0)
		)
		(polygon
			(pts
				(xy 167.778684 -217.475308) (xy 169.277284 -217.475308) (xy 169.277284 -217.995246) (xy 167.778684 -217.995246)
			)
		)
	)
	(zone
		(layer "In2.Cu")
		(hatch none 0.5)
		(connect_pads
			(clearance 0)
		)
		(min_thickness 0.25)
		(keepout
			(tracks allowed)
			(vias allowed)
			(pads allowed)
			(copperpour allowed)
			(footprints allowed)
		)
		(placement
			(enabled no)
			(sheetname "")
		)
		(fill
			(thermal_gap 0.5)
			(thermal_bridge_width 0.5)
			(island_removal_mode 0)
		)
		(polygon
			(pts
				(xy 93.64091 -338.741512) (xy 93.64091 -339.600032) (xy 93.40469 -339.600032) (xy 93.40469 -338.741512)
			)
		)
	)
	(zone
		(layer "In2.Cu")
		(hatch none 0.5)
		(connect_pads
			(clearance 0)
		)
		(min_thickness 0.25)
		(keepout
			(tracks not_allowed)
			(vias allowed)
			(pads allowed)
			(copperpour not_allowed)
			(footprints allowed)
		)
		(placement
			(enabled no)
			(sheetname "")
		)
		(fill
			(thermal_gap 0.5)
			(thermal_bridge_width 0.5)
			(island_removal_mode 0)
		)
		(polygon
			(pts
				(xy 186.310778 -222.57512) (xy 187.809378 -222.57512) (xy 187.809378 -223.095058) (xy 186.310778 -223.095058)
			)
		)
	)
	(zone
		(layer "In2.Cu")
		(hatch none 0.5)
		(connect_pads
			(clearance 0)
		)
		(min_thickness 0.25)
		(keepout
			(tracks not_allowed)
			(vias allowed)
			(pads allowed)
			(copperpour not_allowed)
			(footprints allowed)
		)
		(placement
			(enabled no)
			(sheetname "")
		)
		(fill
			(thermal_gap 0.5)
			(thermal_bridge_width 0.5)
			(island_removal_mode 0)
		)
		(polygon
			(pts
				(xy 294.974772 -266.775184) (xy 296.473372 -266.775184) (xy 296.473372 -267.295122) (xy 294.974772 -267.295122)
			)
		)
	)
	(zone
		(layer "In2.Cu")
		(hatch none 0.5)
		(connect_pads
			(clearance 0)
		)
		(min_thickness 0.25)
		(keepout
			(tracks not_allowed)
			(vias allowed)
			(pads allowed)
			(copperpour not_allowed)
			(footprints allowed)
		)
		(placement
			(enabled no)
			(sheetname "")
		)
		(fill
			(thermal_gap 0.5)
			(thermal_bridge_width 0.5)
			(island_removal_mode 0)
		)
		(polygon
			(pts
				(xy 299.07484 -273.575272) (xy 300.57344 -273.575272) (xy 300.57344 -274.09521) (xy 299.07484 -274.09521)
			)
		)
	)
	(zone
		(layer "In2.Cu")
		(hatch none 0.5)
		(connect_pads
			(clearance 0)
		)
		(min_thickness 0.25)
		(keepout
			(tracks not_allowed)
			(vias allowed)
			(pads allowed)
			(copperpour not_allowed)
			(footprints allowed)
		)
		(placement
			(enabled no)
			(sheetname "")
		)
		(fill
			(thermal_gap 0.5)
			(thermal_bridge_width 0.5)
			(island_removal_mode 0)
		)
		(polygon
			(pts
				(xy 20.95881 -201.325226) (xy 22.45741 -201.325226) (xy 22.45741 -201.845164) (xy 20.95881 -201.845164)
			)
		)
	)
	(zone
		(layer "In2.Cu")
		(hatch none 0.5)
		(connect_pads
			(clearance 0)
		)
		(min_thickness 0.25)
		(keepout
			(tracks not_allowed)
			(vias allowed)
			(pads allowed)
			(copperpour not_allowed)
			(footprints allowed)
		)
		(placement
			(enabled no)
			(sheetname "")
		)
		(fill
			(thermal_gap 0.5)
			(thermal_bridge_width 0.5)
			(island_removal_mode 0)
		)
		(polygon
			(pts
				(xy 287.430718 -288.025332) (xy 288.929318 -288.025332) (xy 288.929318 -288.54527) (xy 287.430718 -288.54527)
			)
		)
	)
	(zone
		(layer "In2.Cu")
		(hatch none 0.5)
		(connect_pads
			(clearance 0)
		)
		(min_thickness 0.25)
		(keepout
			(tracks not_allowed)
			(vias allowed)
			(pads allowed)
			(copperpour not_allowed)
			(footprints allowed)
		)
		(placement
			(enabled no)
			(sheetname "")
		)
		(fill
			(thermal_gap 0.5)
			(thermal_bridge_width 0.5)
			(island_removal_mode 0)
		)
		(polygon
			(pts
				(xy 175.322738 -265.9253) (xy 176.821338 -265.9253) (xy 176.821338 -266.445238) (xy 175.322738 -266.445238)
			)
		)
	)
	(zone
		(layer "In2.Cu")
		(hatch none 0.5)
		(connect_pads
			(clearance 0)
		)
		(min_thickness 0.25)
		(keepout
			(tracks not_allowed)
			(vias allowed)
			(pads allowed)
			(copperpour not_allowed)
			(footprints allowed)
		)
		(placement
			(enabled no)
			(sheetname "")
		)
		(fill
			(thermal_gap 0.5)
			(thermal_bridge_width 0.5)
			(island_removal_mode 0)
		)
		(polygon
			(pts
				(xy 171.22267 -289.725354) (xy 172.72127 -289.725354) (xy 172.72127 -290.245292) (xy 171.22267 -290.245292)
			)
		)
	)
	(zone
		(layer "In2.Cu")
		(hatch none 0.5)
		(connect_pads
			(clearance 0)
		)
		(min_thickness 0.25)
		(keepout
			(tracks not_allowed)
			(vias allowed)
			(pads allowed)
			(copperpour not_allowed)
			(footprints allowed)
		)
		(placement
			(enabled no)
			(sheetname "")
		)
		(fill
			(thermal_gap 0.5)
			(thermal_bridge_width 0.5)
			(island_removal_mode 0)
		)
		(polygon
			(pts
				(xy 423.262806 -276.125178) (xy 424.761406 -276.125178) (xy 424.761406 -276.645116) (xy 423.262806 -276.645116)
			)
		)
	)
	(zone
		(layer "In2.Cu")
		(hatch none 0.5)
		(connect_pads
			(clearance 0)
		)
		(min_thickness 0.25)
		(keepout
			(tracks not_allowed)
			(vias allowed)
			(pads allowed)
			(copperpour not_allowed)
			(footprints allowed)
		)
		(placement
			(enabled no)
			(sheetname "")
		)
		(fill
			(thermal_gap 0.5)
			(thermal_bridge_width 0.5)
			(island_removal_mode 0)
		)
		(polygon
			(pts
				(xy 434.250846 -300.775116) (xy 435.749446 -300.775116) (xy 435.749446 -301.295054) (xy 434.250846 -301.295054)
			)
		)
	)
	(zone
		(layer "In2.Cu")
		(hatch none 0.5)
		(connect_pads
			(clearance 0)
		)
		(min_thickness 0.25)
		(keepout
			(tracks not_allowed)
			(vias allowed)
			(pads allowed)
			(copperpour not_allowed)
			(footprints allowed)
		)
		(placement
			(enabled no)
			(sheetname "")
		)
		(fill
			(thermal_gap 0.5)
			(thermal_bridge_width 0.5)
			(island_removal_mode 0)
		)
		(polygon
			(pts
				(xy 441.7949 -282.075128) (xy 443.2935 -282.075128) (xy 443.2935 -282.595066) (xy 441.7949 -282.595066)
			)
		)
	)
	(zone
		(layer "In2.Cu")
		(hatch none 0.5)
		(connect_pads
			(clearance 0)
		)
		(min_thickness 0.25)
		(keepout
			(tracks not_allowed)
			(vias allowed)
			(pads allowed)
			(copperpour not_allowed)
			(footprints allowed)
		)
		(placement
			(enabled no)
			(sheetname "")
		)
		(fill
			(thermal_gap 0.5)
			(thermal_bridge_width 0.5)
			(island_removal_mode 0)
		)
		(polygon
			(pts
				(xy 171.22267 -218.325192) (xy 172.72127 -218.325192) (xy 172.72127 -218.84513) (xy 171.22267 -218.84513)
			)
		)
	)
	(zone
		(layer "In2.Cu")
		(hatch none 0.5)
		(connect_pads
			(clearance 0)
		)
		(min_thickness 0.25)
		(keepout
			(tracks not_allowed)
			(vias allowed)
			(pads allowed)
			(copperpour not_allowed)
			(footprints allowed)
		)
		(placement
			(enabled no)
			(sheetname "")
		)
		(fill
			(thermal_gap 0.5)
			(thermal_bridge_width 0.5)
			(island_removal_mode 0)
		)
		(polygon
			(pts
				(xy 411.618684 -306.72532) (xy 413.117284 -306.72532) (xy 413.117284 -307.245258) (xy 411.618684 -307.245258)
			)
		)
	)
	(zone
		(layer "In2.Cu")
		(hatch none 0.5)
		(connect_pads
			(clearance 0)
		)
		(min_thickness 0.25)
		(keepout
			(tracks not_allowed)
			(vias allowed)
			(pads allowed)
			(copperpour not_allowed)
			(footprints allowed)
		)
		(placement
			(enabled no)
			(sheetname "")
		)
		(fill
			(thermal_gap 0.5)
			(thermal_bridge_width 0.5)
			(island_removal_mode 0)
		)
		(polygon
			(pts
				(xy 193.854578 -282.075128) (xy 195.353178 -282.075128) (xy 195.353178 -282.595066) (xy 193.854578 -282.595066)
			)
		)
	)
	(zone
		(layer "In2.Cu")
		(hatch none 0.5)
		(connect_pads
			(clearance 0)
		)
		(min_thickness 0.25)
		(keepout
			(tracks not_allowed)
			(vias allowed)
			(pads allowed)
			(copperpour not_allowed)
			(footprints allowed)
		)
		(placement
			(enabled no)
			(sheetname "")
		)
		(fill
			(thermal_gap 0.5)
			(thermal_bridge_width 0.5)
			(island_removal_mode 0)
		)
		(polygon
			(pts
				(xy 20.95881 -270.175228) (xy 22.45741 -270.175228) (xy 22.45741 -270.695166) (xy 20.95881 -270.695166)
			)
		)
	)
	(zone
		(layer "In2.Cu")
		(hatch none 0.5)
		(connect_pads
			(clearance 0)
		)
		(min_thickness 0.25)
		(keepout
			(tracks not_allowed)
			(vias allowed)
			(pads allowed)
			(copperpour not_allowed)
			(footprints allowed)
		)
		(placement
			(enabled no)
			(sheetname "")
		)
		(fill
			(thermal_gap 0.5)
			(thermal_bridge_width 0.5)
			(island_removal_mode 0)
		)
		(polygon
			(pts
				(arc
					(start 301.485046 -379.360684)
					(mid 301.50497 -379.36992)
					(end 301.526702 -379.37313)
				)
				(arc
					(start 301.721266 -379.37313)
					(mid 301.775148 -379.350812)
					(end 301.797466 -379.29693)
				)
				(arc
					(start 301.797466 -378.61113)
					(mid 301.775148 -378.557248)
					(end 301.721266 -378.53493)
				)
				(arc
					(start 301.526702 -378.53493)
					(mid 301.504958 -378.538098)
					(end 301.485046 -378.547376)
				)
				(arc
					(start 301.188882 -378.740162)
					(mid 301.147198 -378.752384)
					(end 301.10557 -378.739908)
				)
				(arc
					(start 300.811946 -378.547376)
					(mid 300.792022 -378.53814)
					(end 300.77029 -378.53493)
				)
				(arc
					(start 300.575726 -378.53493)
					(mid 300.521844 -378.557248)
					(end 300.499526 -378.61113)
				)
				(arc
					(start 300.499526 -379.29693)
					(mid 300.521844 -379.350812)
					(end 300.575726 -379.37313)
				)
				(arc
					(start 300.77156 -379.37313)
					(mid 300.793304 -379.369962)
					(end 300.813216 -379.360684)
				)
				(arc
					(start 301.10684 -379.168152)
					(mid 301.148496 -379.15575)
					(end 301.190152 -379.168152)
				)
			)
		)
	)
	(zone
		(layer "In2.Cu")
		(hatch none 0.5)
		(connect_pads
			(clearance 0)
		)
		(min_thickness 0.25)
		(keepout
			(tracks not_allowed)
			(vias allowed)
			(pads allowed)
			(copperpour not_allowed)
			(footprints allowed)
		)
		(placement
			(enabled no)
			(sheetname "")
		)
		(fill
			(thermal_gap 0.5)
			(thermal_bridge_width 0.5)
			(island_removal_mode 0)
		)
		(polygon
			(pts
				(xy 24.402542 -280.375106) (xy 25.901142 -280.375106) (xy 25.901142 -280.895044) (xy 24.402542 -280.895044)
			)
		)
	)
	(zone
		(layer "In2.Cu")
		(hatch none 0.5)
		(connect_pads
			(clearance 0)
		)
		(min_thickness 0.25)
		(keepout
			(tracks not_allowed)
			(vias allowed)
			(pads allowed)
			(copperpour not_allowed)
			(footprints allowed)
		)
		(placement
			(enabled no)
			(sheetname "")
		)
		(fill
			(thermal_gap 0.5)
			(thermal_bridge_width 0.5)
			(island_removal_mode 0)
		)
		(polygon
			(pts
				(xy 58.678826 -303.325276) (xy 60.177426 -303.325276) (xy 60.177426 -303.845214) (xy 58.678826 -303.845214)
			)
		)
	)
	(zone
		(layer "In2.Cu")
		(hatch none 0.5)
		(connect_pads
			(clearance 0)
		)
		(min_thickness 0.25)
		(keepout
			(tracks not_allowed)
			(vias allowed)
			(pads allowed)
			(copperpour not_allowed)
			(footprints allowed)
		)
		(placement
			(enabled no)
			(sheetname "")
		)
		(fill
			(thermal_gap 0.5)
			(thermal_bridge_width 0.5)
			(island_removal_mode 0)
		)
		(polygon
			(pts
				(xy 430.80686 -208.125314) (xy 432.30546 -208.125314) (xy 432.30546 -208.645252) (xy 430.80686 -208.645252)
			)
		)
	)
	(zone
		(layer "In2.Cu")
		(hatch none 0.5)
		(connect_pads
			(clearance 0)
		)
		(min_thickness 0.25)
		(keepout
			(tracks not_allowed)
			(vias allowed)
			(pads allowed)
			(copperpour not_allowed)
			(footprints allowed)
		)
		(placement
			(enabled no)
			(sheetname "")
		)
		(fill
			(thermal_gap 0.5)
			(thermal_bridge_width 0.5)
			(island_removal_mode 0)
		)
		(polygon
			(pts
				(xy 291.530786 -298.22521) (xy 293.029386 -298.22521) (xy 293.029386 -298.745148) (xy 291.530786 -298.745148)
			)
		)
	)
	(zone
		(layer "In2.Cu")
		(hatch none 0.5)
		(connect_pads
			(clearance 0)
		)
		(min_thickness 0.25)
		(keepout
			(tracks not_allowed)
			(vias allowed)
			(pads allowed)
			(copperpour not_allowed)
			(footprints allowed)
		)
		(placement
			(enabled no)
			(sheetname "")
		)
		(fill
			(thermal_gap 0.5)
			(thermal_bridge_width 0.5)
			(island_removal_mode 0)
		)
		(polygon
			(pts
				(xy 415.718752 -307.575204) (xy 417.217352 -307.575204) (xy 417.217352 -308.095142) (xy 415.718752 -308.095142)
			)
		)
	)
	(zone
		(layer "In2.Cu")
		(hatch none 0.5)
		(connect_pads
			(clearance 0)
		)
		(min_thickness 0.25)
		(keepout
			(tracks not_allowed)
			(vias allowed)
			(pads allowed)
			(copperpour not_allowed)
			(footprints allowed)
		)
		(placement
			(enabled no)
			(sheetname "")
		)
		(fill
			(thermal_gap 0.5)
			(thermal_bridge_width 0.5)
			(island_removal_mode 0)
		)
		(polygon
			(pts
				(xy 201.398632 -278.675338) (xy 202.897232 -278.675338) (xy 202.897232 -279.195276) (xy 201.398632 -279.195276)
			)
		)
	)
	(zone
		(layer "In2.Cu")
		(hatch none 0.5)
		(connect_pads
			(clearance 0)
		)
		(min_thickness 0.25)
		(keepout
			(tracks not_allowed)
			(vias allowed)
			(pads allowed)
			(copperpour not_allowed)
			(footprints allowed)
		)
		(placement
			(enabled no)
			(sheetname "")
		)
		(fill
			(thermal_gap 0.5)
			(thermal_bridge_width 0.5)
			(island_removal_mode 0)
		)
		(polygon
			(pts
				(xy 16.858742 -230.225346) (xy 18.357342 -230.225346) (xy 18.357342 -230.745284) (xy 16.858742 -230.745284)
			)
		)
	)
	(zone
		(layer "In2.Cu")
		(hatch none 0.5)
		(connect_pads
			(clearance 0)
		)
		(min_thickness 0.25)
		(keepout
			(tracks not_allowed)
			(vias allowed)
			(pads allowed)
			(copperpour not_allowed)
			(footprints allowed)
		)
		(placement
			(enabled no)
			(sheetname "")
		)
		(fill
			(thermal_gap 0.5)
			(thermal_bridge_width 0.5)
			(island_removal_mode 0)
		)
		(polygon
			(pts
				(xy 193.854578 -231.925114) (xy 195.353178 -231.925114) (xy 195.353178 -232.445052) (xy 193.854578 -232.445052)
			)
		)
	)
	(zone
		(layer "In2.Cu")
		(hatch none 0.5)
		(connect_pads
			(clearance 0)
		)
		(min_thickness 0.25)
		(keepout
			(tracks not_allowed)
			(vias allowed)
			(pads allowed)
			(copperpour not_allowed)
			(footprints allowed)
		)
		(placement
			(enabled no)
			(sheetname "")
		)
		(fill
			(thermal_gap 0.5)
			(thermal_bridge_width 0.5)
			(island_removal_mode 0)
		)
		(polygon
			(pts
				(xy 302.518826 -282.075128) (xy 304.017426 -282.075128) (xy 304.017426 -282.595066) (xy 302.518826 -282.595066)
			)
		)
	)
	(zone
		(layer "In2.Cu")
		(hatch none 0.5)
		(connect_pads
			(clearance 0)
		)
		(min_thickness 0.25)
		(keepout
			(tracks not_allowed)
			(vias allowed)
			(pads allowed)
			(copperpour not_allowed)
			(footprints allowed)
		)
		(placement
			(enabled no)
			(sheetname "")
		)
		(fill
			(thermal_gap 0.5)
			(thermal_bridge_width 0.5)
			(island_removal_mode 0)
		)
		(polygon
			(pts
				(xy 20.95881 -279.525222) (xy 22.45741 -279.525222) (xy 22.45741 -280.04516) (xy 20.95881 -280.04516)
			)
		)
	)
	(zone
		(layer "In2.Cu")
		(hatch none 0.5)
		(connect_pads
			(clearance 0)
		)
		(min_thickness 0.25)
		(keepout
			(tracks not_allowed)
			(vias allowed)
			(pads allowed)
			(copperpour not_allowed)
			(footprints allowed)
		)
		(placement
			(enabled no)
			(sheetname "")
		)
		(fill
			(thermal_gap 0.5)
			(thermal_bridge_width 0.5)
			(island_removal_mode 0)
		)
		(polygon
			(pts
				(xy 201.398632 -283.77515) (xy 202.897232 -283.77515) (xy 202.897232 -284.295088) (xy 201.398632 -284.295088)
			)
		)
	)
	(zone
		(layer "In2.Cu")
		(hatch none 0.5)
		(connect_pads
			(clearance 0)
		)
		(min_thickness 0.25)
		(keepout
			(tracks not_allowed)
			(vias allowed)
			(pads allowed)
			(copperpour not_allowed)
			(footprints allowed)
		)
		(placement
			(enabled no)
			(sheetname "")
		)
		(fill
			(thermal_gap 0.5)
			(thermal_bridge_width 0.5)
			(island_removal_mode 0)
		)
		(polygon
			(pts
				(xy 163.678616 -278.675338) (xy 165.177216 -278.675338) (xy 165.177216 -279.195276) (xy 163.678616 -279.195276)
			)
		)
	)
	(zone
		(layer "In2.Cu")
		(hatch none 0.5)
		(connect_pads
			(clearance 0)
		)
		(min_thickness 0.25)
		(keepout
			(tracks not_allowed)
			(vias allowed)
			(pads allowed)
			(copperpour not_allowed)
			(footprints allowed)
		)
		(placement
			(enabled no)
			(sheetname "")
		)
		(fill
			(thermal_gap 0.5)
			(thermal_bridge_width 0.5)
			(island_removal_mode 0)
		)
		(polygon
			(pts
				(xy 186.310778 -300.775116) (xy 187.809378 -300.775116) (xy 187.809378 -301.295054) (xy 186.310778 -301.295054)
			)
		)
	)
	(zone
		(layer "In2.Cu")
		(hatch none 0.5)
		(connect_pads
			(clearance 0)
		)
		(min_thickness 0.25)
		(keepout
			(tracks not_allowed)
			(vias allowed)
			(pads allowed)
			(copperpour not_allowed)
			(footprints allowed)
		)
		(placement
			(enabled no)
			(sheetname "")
		)
		(fill
			(thermal_gap 0.5)
			(thermal_bridge_width 0.5)
			(island_removal_mode 0)
		)
		(polygon
			(pts
				(xy 302.518826 -218.325192) (xy 304.017426 -218.325192) (xy 304.017426 -218.84513) (xy 302.518826 -218.84513)
			)
		)
	)
	(zone
		(layer "In2.Cu")
		(hatch none 0.5)
		(connect_pads
			(clearance 0)
		)
		(min_thickness 0.25)
		(keepout
			(tracks not_allowed)
			(vias allowed)
			(pads allowed)
			(copperpour not_allowed)
			(footprints allowed)
		)
		(placement
			(enabled no)
			(sheetname "")
		)
		(fill
			(thermal_gap 0.5)
			(thermal_bridge_width 0.5)
			(island_removal_mode 0)
		)
		(polygon
			(pts
				(xy 171.22267 -285.475172) (xy 172.72127 -285.475172) (xy 172.72127 -285.99511) (xy 171.22267 -285.99511)
			)
		)
	)
	(zone
		(layer "In2.Cu")
		(hatch none 0.5)
		(connect_pads
			(clearance 0)
		)
		(min_thickness 0.25)
		(keepout
			(tracks not_allowed)
			(vias allowed)
			(pads allowed)
			(copperpour not_allowed)
			(footprints allowed)
		)
		(placement
			(enabled no)
			(sheetname "")
		)
		(fill
			(thermal_gap 0.5)
			(thermal_bridge_width 0.5)
			(island_removal_mode 0)
		)
		(polygon
			(pts
				(xy 423.262806 -204.72527) (xy 424.761406 -204.72527) (xy 424.761406 -205.245208) (xy 423.262806 -205.245208)
			)
		)
	)
	(zone
		(layer "In2.Cu")
		(hatch none 0.5)
		(connect_pads
			(clearance 0)
		)
		(min_thickness 0.25)
		(keepout
			(tracks not_allowed)
			(vias allowed)
			(pads allowed)
			(copperpour not_allowed)
			(footprints allowed)
		)
		(placement
			(enabled no)
			(sheetname "")
		)
		(fill
			(thermal_gap 0.5)
			(thermal_bridge_width 0.5)
			(island_removal_mode 0)
		)
		(polygon
			(pts
				(arc
					(start 357.86187 -388.647178)
					(mid 357.852634 -388.667102)
					(end 357.849424 -388.688834)
				)
				(arc
					(start 357.849424 -388.883398)
					(mid 357.871742 -388.93728)
					(end 357.925624 -388.959598)
				)
				(arc
					(start 358.611424 -388.959598)
					(mid 358.665306 -388.93728)
					(end 358.687624 -388.883398)
				)
				(arc
					(start 358.687624 -388.688834)
					(mid 358.684456 -388.66709)
					(end 358.675178 -388.647178)
				)
				(arc
					(start 358.482392 -388.351014)
					(mid 358.47017 -388.30933)
					(end 358.482646 -388.267702)
				)
				(arc
					(start 358.675178 -387.974078)
					(mid 358.684414 -387.954154)
					(end 358.687624 -387.932422)
				)
				(arc
					(start 358.687624 -387.737858)
					(mid 358.665306 -387.683976)
					(end 358.611424 -387.661658)
				)
				(arc
					(start 357.925624 -387.661658)
					(mid 357.871742 -387.683976)
					(end 357.849424 -387.737858)
				)
				(arc
					(start 357.849424 -387.933692)
					(mid 357.852592 -387.955436)
					(end 357.86187 -387.975348)
				)
				(arc
					(start 358.054402 -388.268972)
					(mid 358.066804 -388.310628)
					(end 358.054402 -388.352284)
				)
			)
		)
	)
	(zone
		(layer "In2.Cu")
		(hatch none 0.5)
		(connect_pads
			(clearance 0)
		)
		(min_thickness 0.25)
		(keepout
			(tracks not_allowed)
			(vias allowed)
			(pads allowed)
			(copperpour not_allowed)
			(footprints allowed)
		)
		(placement
			(enabled no)
			(sheetname "")
		)
		(fill
			(thermal_gap 0.5)
			(thermal_bridge_width 0.5)
			(island_removal_mode 0)
		)
		(polygon
			(pts
				(xy 163.678616 -229.375208) (xy 165.177216 -229.375208) (xy 165.177216 -229.895146) (xy 163.678616 -229.895146)
			)
		)
	)
	(zone
		(layer "In2.Cu")
		(hatch none 0.5)
		(connect_pads
			(clearance 0)
		)
		(min_thickness 0.25)
		(keepout
			(tracks not_allowed)
			(vias allowed)
			(pads allowed)
			(copperpour not_allowed)
			(footprints allowed)
		)
		(placement
			(enabled no)
			(sheetname "")
		)
		(fill
			(thermal_gap 0.5)
			(thermal_bridge_width 0.5)
			(island_removal_mode 0)
		)
		(polygon
			(pts
				(xy 31.946596 -222.57512) (xy 33.445196 -222.57512) (xy 33.445196 -223.095058) (xy 31.946596 -223.095058)
			)
		)
	)
	(zone
		(layer "In2.Cu")
		(hatch none 0.5)
		(connect_pads
			(clearance 0)
		)
		(min_thickness 0.25)
		(keepout
			(tracks not_allowed)
			(vias allowed)
			(pads allowed)
			(copperpour not_allowed)
			(footprints allowed)
		)
		(placement
			(enabled no)
			(sheetname "")
		)
		(fill
			(thermal_gap 0.5)
			(thermal_bridge_width 0.5)
			(island_removal_mode 0)
		)
		(polygon
			(pts
				(xy 294.974772 -294.825166) (xy 296.473372 -294.825166) (xy 296.473372 -295.345104) (xy 294.974772 -295.345104)
			)
		)
	)
	(zone
		(layer "In2.Cu")
		(hatch none 0.5)
		(connect_pads
			(clearance 0)
		)
		(min_thickness 0.25)
		(keepout
			(tracks not_allowed)
			(vias allowed)
			(pads allowed)
			(copperpour not_allowed)
			(footprints allowed)
		)
		(placement
			(enabled no)
			(sheetname "")
		)
		(fill
			(thermal_gap 0.5)
			(thermal_bridge_width 0.5)
			(island_removal_mode 0)
		)
		(polygon
			(pts
				(arc
					(start 49.150524 -16.442436)
					(mid 49.172842 -16.496318)
					(end 49.226724 -16.518636)
				)
				(arc
					(start 49.422304 -16.518636)
					(mid 49.44418 -16.515504)
					(end 49.464214 -16.50619)
				)
				(arc
					(start 49.757838 -16.313658)
					(mid 49.799494 -16.301256)
					(end 49.84115 -16.313658)
				)
				(arc
					(start 50.136044 -16.50619)
					(mid 50.155968 -16.515426)
					(end 50.1777 -16.518636)
				)
				(arc
					(start 50.372264 -16.518636)
					(mid 50.426146 -16.496318)
					(end 50.448464 -16.442436)
				)
				(arc
					(start 50.448464 -15.756636)
					(mid 50.426146 -15.702754)
					(end 50.372264 -15.680436)
				)
				(arc
					(start 50.1777 -15.680436)
					(mid 50.155956 -15.683604)
					(end 50.136044 -15.692882)
				)
				(arc
					(start 49.83988 -15.885668)
					(mid 49.798196 -15.89789)
					(end 49.756568 -15.885414)
				)
				(arc
					(start 49.462944 -15.692882)
					(mid 49.44302 -15.683646)
					(end 49.421288 -15.680436)
				)
				(arc
					(start 49.226724 -15.680436)
					(mid 49.172842 -15.702754)
					(end 49.150524 -15.756636)
				)
			)
		)
	)
	(zone
		(layer "In2.Cu")
		(hatch none 0.5)
		(connect_pads
			(clearance 0)
		)
		(min_thickness 0.25)
		(keepout
			(tracks not_allowed)
			(vias allowed)
			(pads allowed)
			(copperpour not_allowed)
			(footprints allowed)
		)
		(placement
			(enabled no)
			(sheetname "")
		)
		(fill
			(thermal_gap 0.5)
			(thermal_bridge_width 0.5)
			(island_removal_mode 0)
		)
		(polygon
			(pts
				(xy 449.3387 -274.425156) (xy 450.8373 -274.425156) (xy 450.8373 -274.945094) (xy 449.3387 -274.945094)
			)
		)
	)
	(zone
		(layer "In2.Cu")
		(hatch none 0.5)
		(connect_pads
			(clearance 0)
		)
		(min_thickness 0.25)
		(keepout
			(tracks not_allowed)
			(vias allowed)
			(pads allowed)
			(copperpour not_allowed)
			(footprints allowed)
		)
		(placement
			(enabled no)
			(sheetname "")
		)
		(fill
			(thermal_gap 0.5)
			(thermal_bridge_width 0.5)
			(island_removal_mode 0)
		)
		(polygon
			(pts
				(xy 16.858742 -302.475138) (xy 18.357342 -302.475138) (xy 18.357342 -302.995076) (xy 16.858742 -302.995076)
			)
		)
	)
	(zone
		(layer "In2.Cu")
		(hatch none 0.5)
		(connect_pads
			(clearance 0)
		)
		(min_thickness 0.25)
		(keepout
			(tracks not_allowed)
			(vias allowed)
			(pads allowed)
			(copperpour not_allowed)
			(footprints allowed)
		)
		(placement
			(enabled no)
			(sheetname "")
		)
		(fill
			(thermal_gap 0.5)
			(thermal_bridge_width 0.5)
			(island_removal_mode 0)
		)
		(polygon
			(pts
				(xy 302.518826 -302.475138) (xy 304.017426 -302.475138) (xy 304.017426 -302.995076) (xy 302.518826 -302.995076)
			)
		)
	)
	(zone
		(layer "In2.Cu")
		(hatch none 0.5)
		(connect_pads
			(clearance 0)
		)
		(min_thickness 0.25)
		(keepout
			(tracks not_allowed)
			(vias allowed)
			(pads allowed)
			(copperpour not_allowed)
			(footprints allowed)
		)
		(placement
			(enabled no)
			(sheetname "")
		)
		(fill
			(thermal_gap 0.5)
			(thermal_bridge_width 0.5)
			(island_removal_mode 0)
		)
		(polygon
			(pts
				(xy 287.430718 -286.32531) (xy 288.929318 -286.32531) (xy 288.929318 -286.845248) (xy 287.430718 -286.845248)
			)
		)
	)
	(zone
		(layer "In2.Cu")
		(hatch none 0.5)
		(connect_pads
			(clearance 0)
		)
		(min_thickness 0.25)
		(keepout
			(tracks not_allowed)
			(vias allowed)
			(pads allowed)
			(copperpour not_allowed)
			(footprints allowed)
		)
		(placement
			(enabled no)
			(sheetname "")
		)
		(fill
			(thermal_gap 0.5)
			(thermal_bridge_width 0.5)
			(island_removal_mode 0)
		)
		(polygon
			(pts
				(xy 299.07484 -281.225244) (xy 300.57344 -281.225244) (xy 300.57344 -281.745182) (xy 299.07484 -281.745182)
			)
		)
	)
	(zone
		(layer "In2.Cu")
		(hatch none 0.5)
		(connect_pads
			(clearance 0)
		)
		(min_thickness 0.25)
		(keepout
			(tracks not_allowed)
			(vias allowed)
			(pads allowed)
			(copperpour not_allowed)
			(footprints allowed)
		)
		(placement
			(enabled no)
			(sheetname "")
		)
		(fill
			(thermal_gap 0.5)
			(thermal_bridge_width 0.5)
			(island_removal_mode 0)
		)
		(polygon
			(pts
				(xy 54.578758 -302.475138) (xy 56.077358 -302.475138) (xy 56.077358 -302.995076) (xy 54.578758 -302.995076)
			)
		)
	)
	(zone
		(layer "In2.Cu")
		(hatch none 0.5)
		(connect_pads
			(clearance 0)
		)
		(min_thickness 0.25)
		(keepout
			(tracks not_allowed)
			(vias allowed)
			(pads allowed)
			(copperpour not_allowed)
			(footprints allowed)
		)
		(placement
			(enabled no)
			(sheetname "")
		)
		(fill
			(thermal_gap 0.5)
			(thermal_bridge_width 0.5)
			(island_removal_mode 0)
		)
		(polygon
			(pts
				(xy 171.22267 -282.075128) (xy 172.72127 -282.075128) (xy 172.72127 -282.595066) (xy 171.22267 -282.595066)
			)
		)
	)
	(zone
		(layer "In2.Cu")
		(hatch none 0.5)
		(connect_pads
			(clearance 0)
		)
		(min_thickness 0.25)
		(keepout
			(tracks allowed)
			(vias allowed)
			(pads allowed)
			(copperpour allowed)
			(footprints allowed)
		)
		(placement
			(enabled no)
			(sheetname "")
		)
		(fill
			(thermal_gap 0.5)
			(thermal_bridge_width 0.5)
			(island_removal_mode 0)
		)
		(polygon
			(pts
				(xy 68.52793 -338.703412) (xy 68.52793 -339.533992) (xy 68.37045 -339.533992) (xy 68.37045 -338.703412)
			)
		)
	)
	(zone
		(layer "In2.Cu")
		(hatch none 0.5)
		(connect_pads
			(clearance 0)
		)
		(min_thickness 0.25)
		(keepout
			(tracks not_allowed)
			(vias allowed)
			(pads allowed)
			(copperpour not_allowed)
			(footprints allowed)
		)
		(placement
			(enabled no)
			(sheetname "")
		)
		(fill
			(thermal_gap 0.5)
			(thermal_bridge_width 0.5)
			(island_removal_mode 0)
		)
		(polygon
			(pts
				(xy 390.181592 -23.50389) (xy 390.181592 -22.077172) (xy 390.842246 -22.077172) (xy 390.842246 -23.50389)
			)
		)
	)
	(zone
		(layer "In2.Cu")
		(hatch none 0.5)
		(connect_pads
			(clearance 0)
		)
		(min_thickness 0.25)
		(keepout
			(tracks not_allowed)
			(vias allowed)
			(pads allowed)
			(copperpour not_allowed)
			(footprints allowed)
		)
		(placement
			(enabled no)
			(sheetname "")
		)
		(fill
			(thermal_gap 0.5)
			(thermal_bridge_width 0.5)
			(island_removal_mode 0)
		)
		(polygon
			(pts
				(xy 20.95881 -212.375242) (xy 22.45741 -212.375242) (xy 22.45741 -212.89518) (xy 20.95881 -212.89518)
			)
		)
	)
	(zone
		(layer "In2.Cu")
		(hatch none 0.5)
		(connect_pads
			(clearance 0)
		)
		(min_thickness 0.25)
		(keepout
			(tracks not_allowed)
			(vias allowed)
			(pads allowed)
			(copperpour not_allowed)
			(footprints allowed)
		)
		(placement
			(enabled no)
			(sheetname "")
		)
		(fill
			(thermal_gap 0.5)
			(thermal_bridge_width 0.5)
			(island_removal_mode 0)
		)
		(polygon
			(pts
				(xy 36.046664 -304.17516) (xy 37.545264 -304.17516) (xy 37.545264 -304.695098) (xy 36.046664 -304.695098)
			)
		)
	)
	(zone
		(layer "In2.Cu")
		(hatch none 0.5)
		(connect_pads
			(clearance 0)
		)
		(min_thickness 0.25)
		(keepout
			(tracks not_allowed)
			(vias allowed)
			(pads allowed)
			(copperpour not_allowed)
			(footprints allowed)
		)
		(placement
			(enabled no)
			(sheetname "")
		)
		(fill
			(thermal_gap 0.5)
			(thermal_bridge_width 0.5)
			(island_removal_mode 0)
		)
		(polygon
			(pts
				(xy 186.310778 -272.725134) (xy 187.809378 -272.725134) (xy 187.809378 -273.245072) (xy 186.310778 -273.245072)
			)
		)
	)
	(zone
		(layer "In2.Cu")
		(hatch none 0.5)
		(connect_pads
			(clearance 0)
		)
		(min_thickness 0.25)
		(keepout
			(tracks allowed)
			(vias allowed)
			(pads allowed)
			(copperpour allowed)
			(footprints allowed)
		)
		(placement
			(enabled no)
			(sheetname "")
		)
		(fill
			(thermal_gap 0.5)
			(thermal_bridge_width 0.5)
			(island_removal_mode 0)
		)
		(polygon
			(pts
				(xy 319.77457 -337.396582) (xy 319.77457 -336.774282) (xy 320.32575 -336.774282) (xy 320.32575 -337.396582)
			)
		)
	)
	(zone
		(layer "In2.Cu")
		(hatch none 0.5)
		(connect_pads
			(clearance 0)
		)
		(min_thickness 0.25)
		(keepout
			(tracks not_allowed)
			(vias allowed)
			(pads allowed)
			(copperpour not_allowed)
			(footprints allowed)
		)
		(placement
			(enabled no)
			(sheetname "")
		)
		(fill
			(thermal_gap 0.5)
			(thermal_bridge_width 0.5)
			(island_removal_mode 0)
		)
		(polygon
			(pts
				(xy 445.894968 -217.475308) (xy 447.393568 -217.475308) (xy 447.393568 -217.995246) (xy 445.894968 -217.995246)
			)
		)
	)
	(zone
		(layer "In2.Cu")
		(hatch none 0.5)
		(connect_pads
			(clearance 0)
		)
		(min_thickness 0.25)
		(keepout
			(tracks not_allowed)
			(vias allowed)
			(pads allowed)
			(copperpour not_allowed)
			(footprints allowed)
		)
		(placement
			(enabled no)
			(sheetname "")
		)
		(fill
			(thermal_gap 0.5)
			(thermal_bridge_width 0.5)
			(island_removal_mode 0)
		)
		(polygon
			(pts
				(xy 411.618684 -203.875132) (xy 413.117284 -203.875132) (xy 413.117284 -204.39507) (xy 411.618684 -204.39507)
			)
		)
	)
	(zone
		(layer "In2.Cu")
		(hatch none 0.5)
		(connect_pads
			(clearance 0)
		)
		(min_thickness 0.25)
		(keepout
			(tracks not_allowed)
			(vias allowed)
			(pads allowed)
			(copperpour not_allowed)
			(footprints allowed)
		)
		(placement
			(enabled no)
			(sheetname "")
		)
		(fill
			(thermal_gap 0.5)
			(thermal_bridge_width 0.5)
			(island_removal_mode 0)
		)
		(polygon
			(pts
				(xy 441.7949 -230.225346) (xy 443.2935 -230.225346) (xy 443.2935 -230.745284) (xy 441.7949 -230.745284)
			)
		)
	)
	(zone
		(layer "In2.Cu")
		(hatch none 0.5)
		(connect_pads
			(clearance 0)
		)
		(min_thickness 0.25)
		(keepout
			(tracks not_allowed)
			(vias allowed)
			(pads allowed)
			(copperpour not_allowed)
			(footprints allowed)
		)
		(placement
			(enabled no)
			(sheetname "")
		)
		(fill
			(thermal_gap 0.5)
			(thermal_bridge_width 0.5)
			(island_removal_mode 0)
		)
		(polygon
			(pts
				(xy 411.618684 -268.475206) (xy 413.117284 -268.475206) (xy 413.117284 -268.995144) (xy 411.618684 -268.995144)
			)
		)
	)
	(zone
		(layer "In2.Cu")
		(hatch none 0.5)
		(connect_pads
			(clearance 0)
		)
		(min_thickness 0.25)
		(keepout
			(tracks not_allowed)
			(vias allowed)
			(pads allowed)
			(copperpour not_allowed)
			(footprints allowed)
		)
		(placement
			(enabled no)
			(sheetname "")
		)
		(fill
			(thermal_gap 0.5)
			(thermal_bridge_width 0.5)
			(island_removal_mode 0)
		)
		(polygon
			(pts
				(xy 294.974772 -251.47524) (xy 296.473372 -251.47524) (xy 296.473372 -251.995178) (xy 294.974772 -251.995178)
			)
		)
	)
	(zone
		(layer "In2.Cu")
		(hatch none 0.5)
		(connect_pads
			(clearance 0)
		)
		(min_thickness 0.25)
		(keepout
			(tracks not_allowed)
			(vias allowed)
			(pads allowed)
			(copperpour not_allowed)
			(footprints allowed)
		)
		(placement
			(enabled no)
			(sheetname "")
		)
		(fill
			(thermal_gap 0.5)
			(thermal_bridge_width 0.5)
			(island_removal_mode 0)
		)
		(polygon
			(pts
				(xy 453.438768 -215.775286) (xy 454.937368 -215.775286) (xy 454.937368 -216.295224) (xy 453.438768 -216.295224)
			)
		)
	)
	(zone
		(layer "In2.Cu")
		(hatch none 0.5)
		(connect_pads
			(clearance 0)
		)
		(min_thickness 0.25)
		(keepout
			(tracks not_allowed)
			(vias allowed)
			(pads allowed)
			(copperpour not_allowed)
			(footprints allowed)
		)
		(placement
			(enabled no)
			(sheetname "")
		)
		(fill
			(thermal_gap 0.5)
			(thermal_bridge_width 0.5)
			(island_removal_mode 0)
		)
		(polygon
			(pts
				(xy 287.430718 -297.375326) (xy 288.929318 -297.375326) (xy 288.929318 -297.895264) (xy 287.430718 -297.895264)
			)
		)
	)
	(zone
		(layer "In2.Cu")
		(hatch none 0.5)
		(connect_pads
			(clearance 0)
		)
		(min_thickness 0.25)
		(keepout
			(tracks not_allowed)
			(vias allowed)
			(pads allowed)
			(copperpour not_allowed)
			(footprints allowed)
		)
		(placement
			(enabled no)
			(sheetname "")
		)
		(fill
			(thermal_gap 0.5)
			(thermal_bridge_width 0.5)
			(island_removal_mode 0)
		)
		(polygon
			(pts
				(xy 276.442932 -276.125178) (xy 277.941532 -276.125178) (xy 277.941532 -276.645116) (xy 276.442932 -276.645116)
			)
		)
	)
	(zone
		(layer "In2.Cu")
		(hatch none 0.5)
		(connect_pads
			(clearance 0)
		)
		(min_thickness 0.25)
		(keepout
			(tracks not_allowed)
			(vias allowed)
			(pads allowed)
			(copperpour not_allowed)
			(footprints allowed)
		)
		(placement
			(enabled no)
			(sheetname "")
		)
		(fill
			(thermal_gap 0.5)
			(thermal_bridge_width 0.5)
			(island_removal_mode 0)
		)
		(polygon
			(pts
				(xy 411.618684 -294.825166) (xy 413.117284 -294.825166) (xy 413.117284 -295.345104) (xy 411.618684 -295.345104)
			)
		)
	)
	(zone
		(layer "In2.Cu")
		(hatch none 0.5)
		(connect_pads
			(clearance 0)
		)
		(min_thickness 0.25)
		(keepout
			(tracks not_allowed)
			(vias allowed)
			(pads allowed)
			(copperpour not_allowed)
			(footprints allowed)
		)
		(placement
			(enabled no)
			(sheetname "")
		)
		(fill
			(thermal_gap 0.5)
			(thermal_bridge_width 0.5)
			(island_removal_mode 0)
		)
		(polygon
			(pts
				(xy 272.342864 -222.57512) (xy 273.841464 -222.57512) (xy 273.841464 -223.095058) (xy 272.342864 -223.095058)
			)
		)
	)
	(zone
		(layer "In2.Cu")
		(hatch none 0.5)
		(connect_pads
			(clearance 0)
		)
		(min_thickness 0.25)
		(keepout
			(tracks not_allowed)
			(vias allowed)
			(pads allowed)
			(copperpour not_allowed)
			(footprints allowed)
		)
		(placement
			(enabled no)
			(sheetname "")
		)
		(fill
			(thermal_gap 0.5)
			(thermal_bridge_width 0.5)
			(island_removal_mode 0)
		)
		(polygon
			(pts
				(xy 201.398632 -293.125144) (xy 202.897232 -293.125144) (xy 202.897232 -293.645082) (xy 201.398632 -293.645082)
			)
		)
	)
	(zone
		(layer "In2.Cu")
		(hatch none 0.5)
		(connect_pads
			(clearance 0)
		)
		(min_thickness 0.25)
		(keepout
			(tracks not_allowed)
			(vias allowed)
			(pads allowed)
			(copperpour not_allowed)
			(footprints allowed)
		)
		(placement
			(enabled no)
			(sheetname "")
		)
		(fill
			(thermal_gap 0.5)
			(thermal_bridge_width 0.5)
			(island_removal_mode 0)
		)
		(polygon
			(pts
				(xy 58.678826 -313.525154) (xy 60.177426 -313.525154) (xy 60.177426 -314.045092) (xy 58.678826 -314.045092)
			)
		)
	)
	(zone
		(layer "In2.Cu")
		(hatch none 0.5)
		(connect_pads
			(clearance 0)
		)
		(min_thickness 0.25)
		(keepout
			(tracks not_allowed)
			(vias allowed)
			(pads allowed)
			(copperpour not_allowed)
			(footprints allowed)
		)
		(placement
			(enabled no)
			(sheetname "")
		)
		(fill
			(thermal_gap 0.5)
			(thermal_bridge_width 0.5)
			(island_removal_mode 0)
		)
		(polygon
			(pts
				(xy 197.954646 -242.125246) (xy 199.453246 -242.125246) (xy 199.453246 -242.645184) (xy 197.954646 -242.645184)
			)
		)
	)
	(zone
		(layer "In2.Cu")
		(hatch none 0.5)
		(connect_pads
			(clearance 0)
		)
		(min_thickness 0.25)
		(keepout
			(tracks not_allowed)
			(vias allowed)
			(pads allowed)
			(copperpour not_allowed)
			(footprints allowed)
		)
		(placement
			(enabled no)
			(sheetname "")
		)
		(fill
			(thermal_gap 0.5)
			(thermal_bridge_width 0.5)
			(island_removal_mode 0)
		)
		(polygon
			(pts
				(xy 415.718752 -287.175194) (xy 417.217352 -287.175194) (xy 417.217352 -287.695132) (xy 415.718752 -287.695132)
			)
		)
	)
	(zone
		(layer "In2.Cu")
		(hatch none 0.5)
		(connect_pads
			(clearance 0)
		)
		(min_thickness 0.25)
		(keepout
			(tracks not_allowed)
			(vias allowed)
			(pads allowed)
			(copperpour not_allowed)
			(footprints allowed)
		)
		(placement
			(enabled no)
			(sheetname "")
		)
		(fill
			(thermal_gap 0.5)
			(thermal_bridge_width 0.5)
			(island_removal_mode 0)
		)
		(polygon
			(pts
				(xy 171.22267 -306.72532) (xy 172.72127 -306.72532) (xy 172.72127 -307.245258) (xy 171.22267 -307.245258)
			)
		)
	)
	(zone
		(layer "In2.Cu")
		(hatch none 0.5)
		(connect_pads
			(clearance 0)
		)
		(min_thickness 0.25)
		(keepout
			(tracks not_allowed)
			(vias allowed)
			(pads allowed)
			(copperpour not_allowed)
			(footprints allowed)
		)
		(placement
			(enabled no)
			(sheetname "")
		)
		(fill
			(thermal_gap 0.5)
			(thermal_bridge_width 0.5)
			(island_removal_mode 0)
		)
		(polygon
			(pts
				(xy 54.578758 -274.425156) (xy 56.077358 -274.425156) (xy 56.077358 -274.945094) (xy 54.578758 -274.945094)
			)
		)
	)
	(zone
		(layer "In2.Cu")
		(hatch none 0.5)
		(connect_pads
			(clearance 0)
		)
		(min_thickness 0.25)
		(keepout
			(tracks not_allowed)
			(vias allowed)
			(pads allowed)
			(copperpour not_allowed)
			(footprints allowed)
		)
		(placement
			(enabled no)
			(sheetname "")
		)
		(fill
			(thermal_gap 0.5)
			(thermal_bridge_width 0.5)
			(island_removal_mode 0)
		)
		(polygon
			(pts
				(xy 28.50261 -242.125246) (xy 30.00121 -242.125246) (xy 30.00121 -242.645184) (xy 28.50261 -242.645184)
			)
		)
	)
	(zone
		(layer "In2.Cu")
		(hatch none 0.5)
		(connect_pads
			(clearance 0)
		)
		(min_thickness 0.25)
		(keepout
			(tracks not_allowed)
			(vias allowed)
			(pads allowed)
			(copperpour not_allowed)
			(footprints allowed)
		)
		(placement
			(enabled no)
			(sheetname "")
		)
		(fill
			(thermal_gap 0.5)
			(thermal_bridge_width 0.5)
			(island_removal_mode 0)
		)
		(polygon
			(pts
				(xy 51.134772 -299.925232) (xy 52.633372 -299.925232) (xy 52.633372 -300.44517) (xy 51.134772 -300.44517)
			)
		)
	)
	(zone
		(layer "In2.Cu")
		(hatch none 0.5)
		(connect_pads
			(clearance 0)
		)
		(min_thickness 0.25)
		(keepout
			(tracks not_allowed)
			(vias allowed)
			(pads allowed)
			(copperpour not_allowed)
			(footprints allowed)
		)
		(placement
			(enabled no)
			(sheetname "")
		)
		(fill
			(thermal_gap 0.5)
			(thermal_bridge_width 0.5)
			(island_removal_mode 0)
		)
		(polygon
			(pts
				(xy 423.262806 -303.325276) (xy 424.761406 -303.325276) (xy 424.761406 -303.845214) (xy 423.262806 -303.845214)
			)
		)
	)
	(zone
		(layer "In2.Cu")
		(hatch none 0.5)
		(connect_pads
			(clearance 0)
		)
		(min_thickness 0.25)
		(keepout
			(tracks not_allowed)
			(vias allowed)
			(pads allowed)
			(copperpour not_allowed)
			(footprints allowed)
		)
		(placement
			(enabled no)
			(sheetname "")
		)
		(fill
			(thermal_gap 0.5)
			(thermal_bridge_width 0.5)
			(island_removal_mode 0)
		)
		(polygon
			(pts
				(xy 51.134772 -228.525324) (xy 52.633372 -228.525324) (xy 52.633372 -229.045262) (xy 51.134772 -229.045262)
			)
		)
	)
	(zone
		(layer "In2.Cu")
		(hatch none 0.5)
		(connect_pads
			(clearance 0)
		)
		(min_thickness 0.25)
		(keepout
			(tracks not_allowed)
			(vias allowed)
			(pads allowed)
			(copperpour not_allowed)
			(footprints allowed)
		)
		(placement
			(enabled no)
			(sheetname "")
		)
		(fill
			(thermal_gap 0.5)
			(thermal_bridge_width 0.5)
			(island_removal_mode 0)
		)
		(polygon
			(pts
				(xy 268.898878 -243.825268) (xy 270.397478 -243.825268) (xy 270.397478 -244.345206) (xy 268.898878 -244.345206)
			)
		)
	)
	(zone
		(layer "In2.Cu")
		(hatch none 0.5)
		(connect_pads
			(clearance 0)
		)
		(min_thickness 0.25)
		(keepout
			(tracks not_allowed)
			(vias allowed)
			(pads allowed)
			(copperpour not_allowed)
			(footprints allowed)
		)
		(placement
			(enabled no)
			(sheetname "")
		)
		(fill
			(thermal_gap 0.5)
			(thermal_bridge_width 0.5)
			(island_removal_mode 0)
		)
		(polygon
			(pts
				(xy 193.854578 -237.02518) (xy 195.353178 -237.02518) (xy 195.353178 -237.545118) (xy 193.854578 -237.545118)
			)
		)
	)
	(zone
		(layer "In2.Cu")
		(hatch none 0.5)
		(connect_pads
			(clearance 0)
		)
		(min_thickness 0.25)
		(keepout
			(tracks not_allowed)
			(vias allowed)
			(pads allowed)
			(copperpour not_allowed)
			(footprints allowed)
		)
		(placement
			(enabled no)
			(sheetname "")
		)
		(fill
			(thermal_gap 0.5)
			(thermal_bridge_width 0.5)
			(island_removal_mode 0)
		)
		(polygon
			(pts
				(xy 419.162738 -231.925114) (xy 420.661338 -231.925114) (xy 420.661338 -232.445052) (xy 419.162738 -232.445052)
			)
		)
	)
	(zone
		(layer "In2.Cu")
		(hatch none 0.5)
		(connect_pads
			(clearance 0)
		)
		(min_thickness 0.25)
		(keepout
			(tracks not_allowed)
			(vias allowed)
			(pads allowed)
			(copperpour not_allowed)
			(footprints allowed)
		)
		(placement
			(enabled no)
			(sheetname "")
		)
		(fill
			(thermal_gap 0.5)
			(thermal_bridge_width 0.5)
			(island_removal_mode 0)
		)
		(polygon
			(pts
				(xy 449.3387 -288.025332) (xy 450.8373 -288.025332) (xy 450.8373 -288.54527) (xy 449.3387 -288.54527)
			)
		)
	)
	(zone
		(layer "In2.Cu")
		(hatch none 0.5)
		(connect_pads
			(clearance 0)
		)
		(min_thickness 0.25)
		(keepout
			(tracks not_allowed)
			(vias allowed)
			(pads allowed)
			(copperpour not_allowed)
			(footprints allowed)
		)
		(placement
			(enabled no)
			(sheetname "")
		)
		(fill
			(thermal_gap 0.5)
			(thermal_bridge_width 0.5)
			(island_removal_mode 0)
		)
		(polygon
			(pts
				(xy 445.894968 -236.175296) (xy 447.393568 -236.175296) (xy 447.393568 -236.695234) (xy 445.894968 -236.695234)
			)
		)
	)
	(zone
		(layer "In2.Cu")
		(hatch none 0.5)
		(connect_pads
			(clearance 0)
		)
		(min_thickness 0.25)
		(keepout
			(tracks not_allowed)
			(vias allowed)
			(pads allowed)
			(copperpour not_allowed)
			(footprints allowed)
		)
		(placement
			(enabled no)
			(sheetname "")
		)
		(fill
			(thermal_gap 0.5)
			(thermal_bridge_width 0.5)
			(island_removal_mode 0)
		)
		(polygon
			(pts
				(xy 272.342864 -317.775336) (xy 273.841464 -317.775336) (xy 273.841464 -318.295274) (xy 272.342864 -318.295274)
			)
		)
	)
	(zone
		(layer "In2.Cu")
		(hatch none 0.5)
		(connect_pads
			(clearance 0)
		)
		(min_thickness 0.25)
		(keepout
			(tracks not_allowed)
			(vias allowed)
			(pads allowed)
			(copperpour not_allowed)
			(footprints allowed)
		)
		(placement
			(enabled no)
			(sheetname "")
		)
		(fill
			(thermal_gap 0.5)
			(thermal_bridge_width 0.5)
			(island_removal_mode 0)
		)
		(polygon
			(pts
				(xy 197.954646 -245.52529) (xy 199.453246 -245.52529) (xy 199.453246 -246.045228) (xy 197.954646 -246.045228)
			)
		)
	)
	(zone
		(layer "In2.Cu")
		(hatch none 0.5)
		(connect_pads
			(clearance 0)
		)
		(min_thickness 0.25)
		(keepout
			(tracks not_allowed)
			(vias allowed)
			(pads allowed)
			(copperpour not_allowed)
			(footprints allowed)
		)
		(placement
			(enabled no)
			(sheetname "")
		)
		(fill
			(thermal_gap 0.5)
			(thermal_bridge_width 0.5)
			(island_removal_mode 0)
		)
		(polygon
			(pts
				(xy 16.858742 -288.025332) (xy 18.357342 -288.025332) (xy 18.357342 -288.54527) (xy 16.858742 -288.54527)
			)
		)
	)
	(zone
		(layer "In2.Cu")
		(hatch none 0.5)
		(connect_pads
			(clearance 0)
		)
		(min_thickness 0.25)
		(keepout
			(tracks not_allowed)
			(vias allowed)
			(pads allowed)
			(copperpour not_allowed)
			(footprints allowed)
		)
		(placement
			(enabled no)
			(sheetname "")
		)
		(fill
			(thermal_gap 0.5)
			(thermal_bridge_width 0.5)
			(island_removal_mode 0)
		)
		(polygon
			(pts
				(xy 445.894968 -232.775252) (xy 447.393568 -232.775252) (xy 447.393568 -233.29519) (xy 445.894968 -233.29519)
			)
		)
	)
	(zone
		(layer "In2.Cu")
		(hatch none 0.5)
		(connect_pads
			(clearance 0)
		)
		(min_thickness 0.25)
		(keepout
			(tracks not_allowed)
			(vias allowed)
			(pads allowed)
			(copperpour not_allowed)
			(footprints allowed)
		)
		(placement
			(enabled no)
			(sheetname "")
		)
		(fill
			(thermal_gap 0.5)
			(thermal_bridge_width 0.5)
			(island_removal_mode 0)
		)
		(polygon
			(pts
				(xy 51.134772 -307.575204) (xy 52.633372 -307.575204) (xy 52.633372 -308.095142) (xy 51.134772 -308.095142)
			)
		)
	)
	(zone
		(layer "In2.Cu")
		(hatch none 0.5)
		(connect_pads
			(clearance 0)
		)
		(min_thickness 0.25)
		(keepout
			(tracks not_allowed)
			(vias allowed)
			(pads allowed)
			(copperpour not_allowed)
			(footprints allowed)
		)
		(placement
			(enabled no)
			(sheetname "")
		)
		(fill
			(thermal_gap 0.5)
			(thermal_bridge_width 0.5)
			(island_removal_mode 0)
		)
		(polygon
			(pts
				(xy 16.858742 -308.425342) (xy 18.357342 -308.425342) (xy 18.357342 -308.94528) (xy 16.858742 -308.94528)
			)
		)
	)
	(zone
		(layer "In2.Cu")
		(hatch none 0.5)
		(connect_pads
			(clearance 0)
		)
		(min_thickness 0.25)
		(keepout
			(tracks not_allowed)
			(vias allowed)
			(pads allowed)
			(copperpour not_allowed)
			(footprints allowed)
		)
		(placement
			(enabled no)
			(sheetname "")
		)
		(fill
			(thermal_gap 0.5)
			(thermal_bridge_width 0.5)
			(island_removal_mode 0)
		)
		(polygon
			(pts
				(xy 197.954646 -307.575204) (xy 199.453246 -307.575204) (xy 199.453246 -308.095142) (xy 197.954646 -308.095142)
			)
		)
	)
	(zone
		(layer "In2.Cu")
		(hatch none 0.5)
		(connect_pads
			(clearance 0)
		)
		(min_thickness 0.25)
		(keepout
			(tracks not_allowed)
			(vias allowed)
			(pads allowed)
			(copperpour not_allowed)
			(footprints allowed)
		)
		(placement
			(enabled no)
			(sheetname "")
		)
		(fill
			(thermal_gap 0.5)
			(thermal_bridge_width 0.5)
			(island_removal_mode 0)
		)
		(polygon
			(pts
				(xy 31.946596 -305.025298) (xy 33.445196 -305.025298) (xy 33.445196 -305.545236) (xy 31.946596 -305.545236)
			)
		)
	)
	(zone
		(layer "In2.Cu")
		(hatch none 0.5)
		(connect_pads
			(clearance 0)
		)
		(min_thickness 0.25)
		(keepout
			(tracks not_allowed)
			(vias allowed)
			(pads allowed)
			(copperpour not_allowed)
			(footprints allowed)
		)
		(placement
			(enabled no)
			(sheetname "")
		)
		(fill
			(thermal_gap 0.5)
			(thermal_bridge_width 0.5)
			(island_removal_mode 0)
		)
		(polygon
			(pts
				(xy 415.718752 -248.925334) (xy 417.217352 -248.925334) (xy 417.217352 -249.445272) (xy 415.718752 -249.445272)
			)
		)
	)
	(zone
		(layer "In2.Cu")
		(hatch none 0.5)
		(connect_pads
			(clearance 0)
		)
		(min_thickness 0.25)
		(keepout
			(tracks not_allowed)
			(vias allowed)
			(pads allowed)
			(copperpour not_allowed)
			(footprints allowed)
		)
		(placement
			(enabled no)
			(sheetname "")
		)
		(fill
			(thermal_gap 0.5)
			(thermal_bridge_width 0.5)
			(island_removal_mode 0)
		)
		(polygon
			(pts
				(xy 197.954646 -250.625102) (xy 199.453246 -250.625102) (xy 199.453246 -251.14504) (xy 197.954646 -251.14504)
			)
		)
	)
	(zone
		(layer "In2.Cu")
		(hatch none 0.5)
		(connect_pads
			(clearance 0)
		)
		(min_thickness 0.25)
		(keepout
			(tracks not_allowed)
			(vias allowed)
			(pads allowed)
			(copperpour not_allowed)
			(footprints allowed)
		)
		(placement
			(enabled no)
			(sheetname "")
		)
		(fill
			(thermal_gap 0.5)
			(thermal_bridge_width 0.5)
			(island_removal_mode 0)
		)
		(polygon
			(pts
				(xy 411.618684 -266.775184) (xy 413.117284 -266.775184) (xy 413.117284 -267.295122) (xy 411.618684 -267.295122)
			)
		)
	)
	(zone
		(layer "In2.Cu")
		(hatch none 0.5)
		(connect_pads
			(clearance 0)
		)
		(min_thickness 0.25)
		(keepout
			(tracks not_allowed)
			(vias allowed)
			(pads allowed)
			(copperpour not_allowed)
			(footprints allowed)
		)
		(placement
			(enabled no)
			(sheetname "")
		)
		(fill
			(thermal_gap 0.5)
			(thermal_bridge_width 0.5)
			(island_removal_mode 0)
		)
		(polygon
			(pts
				(xy 279.886664 -208.975198) (xy 281.385264 -208.975198) (xy 281.385264 -209.495136) (xy 279.886664 -209.495136)
			)
		)
	)
	(zone
		(layer "In2.Cu")
		(hatch none 0.5)
		(connect_pads
			(clearance 0)
		)
		(min_thickness 0.25)
		(keepout
			(tracks not_allowed)
			(vias allowed)
			(pads allowed)
			(copperpour not_allowed)
			(footprints allowed)
		)
		(placement
			(enabled no)
			(sheetname "")
		)
		(fill
			(thermal_gap 0.5)
			(thermal_bridge_width 0.5)
			(island_removal_mode 0)
		)
		(polygon
			(pts
				(xy 47.034704 -241.275108) (xy 48.533304 -241.275108) (xy 48.533304 -241.795046) (xy 47.034704 -241.795046)
			)
		)
	)
	(zone
		(layer "In2.Cu")
		(hatch none 0.5)
		(connect_pads
			(clearance 0)
		)
		(min_thickness 0.25)
		(keepout
			(tracks not_allowed)
			(vias allowed)
			(pads allowed)
			(copperpour not_allowed)
			(footprints allowed)
		)
		(placement
			(enabled no)
			(sheetname "")
		)
		(fill
			(thermal_gap 0.5)
			(thermal_bridge_width 0.5)
			(island_removal_mode 0)
		)
		(polygon
			(pts
				(xy 434.250846 -276.125178) (xy 435.749446 -276.125178) (xy 435.749446 -276.645116) (xy 434.250846 -276.645116)
			)
		)
	)
	(zone
		(layer "In2.Cu")
		(hatch none 0.5)
		(connect_pads
			(clearance 0)
		)
		(min_thickness 0.25)
		(keepout
			(tracks not_allowed)
			(vias allowed)
			(pads allowed)
			(copperpour not_allowed)
			(footprints allowed)
		)
		(placement
			(enabled no)
			(sheetname "")
		)
		(fill
			(thermal_gap 0.5)
			(thermal_bridge_width 0.5)
			(island_removal_mode 0)
		)
		(polygon
			(pts
				(xy 24.402542 -313.525154) (xy 25.901142 -313.525154) (xy 25.901142 -314.045092) (xy 24.402542 -314.045092)
			)
		)
	)
	(zone
		(layer "In2.Cu")
		(hatch none 0.5)
		(connect_pads
			(clearance 0)
		)
		(min_thickness 0.25)
		(keepout
			(tracks not_allowed)
			(vias allowed)
			(pads allowed)
			(copperpour not_allowed)
			(footprints allowed)
		)
		(placement
			(enabled no)
			(sheetname "")
		)
		(fill
			(thermal_gap 0.5)
			(thermal_bridge_width 0.5)
			(island_removal_mode 0)
		)
		(polygon
			(pts
				(xy 193.854578 -261.675118) (xy 195.353178 -261.675118) (xy 195.353178 -262.195056) (xy 193.854578 -262.195056)
			)
		)
	)
	(zone
		(layer "In2.Cu")
		(hatch none 0.5)
		(connect_pads
			(clearance 0)
		)
		(min_thickness 0.25)
		(keepout
			(tracks not_allowed)
			(vias allowed)
			(pads allowed)
			(copperpour not_allowed)
			(footprints allowed)
		)
		(placement
			(enabled no)
			(sheetname "")
		)
		(fill
			(thermal_gap 0.5)
			(thermal_bridge_width 0.5)
			(island_removal_mode 0)
		)
		(polygon
			(pts
				(xy 36.046664 -275.275294) (xy 37.545264 -275.275294) (xy 37.545264 -275.795232) (xy 36.046664 -275.795232)
			)
		)
	)
	(zone
		(layer "In2.Cu")
		(hatch none 0.5)
		(connect_pads
			(clearance 0)
		)
		(min_thickness 0.25)
		(keepout
			(tracks not_allowed)
			(vias allowed)
			(pads allowed)
			(copperpour not_allowed)
			(footprints allowed)
		)
		(placement
			(enabled no)
			(sheetname "")
		)
		(fill
			(thermal_gap 0.5)
			(thermal_bridge_width 0.5)
			(island_removal_mode 0)
		)
		(polygon
			(pts
				(xy 279.886664 -316.075314) (xy 281.385264 -316.075314) (xy 281.385264 -316.595252) (xy 279.886664 -316.595252)
			)
		)
	)
	(zone
		(layer "In2.Cu")
		(hatch none 0.5)
		(connect_pads
			(clearance 0)
		)
		(min_thickness 0.25)
		(keepout
			(tracks not_allowed)
			(vias allowed)
			(pads allowed)
			(copperpour not_allowed)
			(footprints allowed)
		)
		(placement
			(enabled no)
			(sheetname "")
		)
		(fill
			(thermal_gap 0.5)
			(thermal_bridge_width 0.5)
			(island_removal_mode 0)
		)
		(polygon
			(pts
				(xy 272.342864 -316.075314) (xy 273.841464 -316.075314) (xy 273.841464 -316.595252) (xy 272.342864 -316.595252)
			)
		)
	)
	(zone
		(layer "In2.Cu")
		(hatch none 0.5)
		(connect_pads
			(clearance 0)
		)
		(min_thickness 0.25)
		(keepout
			(tracks not_allowed)
			(vias allowed)
			(pads allowed)
			(copperpour not_allowed)
			(footprints allowed)
		)
		(placement
			(enabled no)
			(sheetname "")
		)
		(fill
			(thermal_gap 0.5)
			(thermal_bridge_width 0.5)
			(island_removal_mode 0)
		)
		(polygon
			(pts
				(xy 276.442932 -225.12528) (xy 277.941532 -225.12528) (xy 277.941532 -225.645218) (xy 276.442932 -225.645218)
			)
		)
	)
	(zone
		(layer "In2.Cu")
		(hatch none 0.5)
		(connect_pads
			(clearance 0)
		)
		(min_thickness 0.25)
		(keepout
			(tracks not_allowed)
			(vias allowed)
			(pads allowed)
			(copperpour not_allowed)
			(footprints allowed)
		)
		(placement
			(enabled no)
			(sheetname "")
		)
		(fill
			(thermal_gap 0.5)
			(thermal_bridge_width 0.5)
			(island_removal_mode 0)
		)
		(polygon
			(pts
				(xy 58.678826 -215.775286) (xy 60.177426 -215.775286) (xy 60.177426 -216.295224) (xy 58.678826 -216.295224)
			)
		)
	)
	(zone
		(layer "In2.Cu")
		(hatch none 0.5)
		(connect_pads
			(clearance 0)
		)
		(min_thickness 0.25)
		(keepout
			(tracks not_allowed)
			(vias allowed)
			(pads allowed)
			(copperpour not_allowed)
			(footprints allowed)
		)
		(placement
			(enabled no)
			(sheetname "")
		)
		(fill
			(thermal_gap 0.5)
			(thermal_bridge_width 0.5)
			(island_removal_mode 0)
		)
		(polygon
			(pts
				(xy 453.438768 -298.22521) (xy 454.937368 -298.22521) (xy 454.937368 -298.745148) (xy 453.438768 -298.745148)
			)
		)
	)
	(zone
		(layer "In2.Cu")
		(hatch none 0.5)
		(connect_pads
			(clearance 0)
		)
		(min_thickness 0.25)
		(keepout
			(tracks not_allowed)
			(vias allowed)
			(pads allowed)
			(copperpour not_allowed)
			(footprints allowed)
		)
		(placement
			(enabled no)
			(sheetname "")
		)
		(fill
			(thermal_gap 0.5)
			(thermal_bridge_width 0.5)
			(island_removal_mode 0)
		)
		(polygon
			(pts
				(xy 31.946596 -201.325226) (xy 33.445196 -201.325226) (xy 33.445196 -201.845164) (xy 31.946596 -201.845164)
			)
		)
	)
	(zone
		(layer "In2.Cu")
		(hatch none 0.5)
		(connect_pads
			(clearance 0)
		)
		(min_thickness 0.25)
		(keepout
			(tracks not_allowed)
			(vias allowed)
			(pads allowed)
			(copperpour not_allowed)
			(footprints allowed)
		)
		(placement
			(enabled no)
			(sheetname "")
		)
		(fill
			(thermal_gap 0.5)
			(thermal_bridge_width 0.5)
			(island_removal_mode 0)
		)
		(polygon
			(pts
				(xy 283.986732 -305.875182) (xy 285.485332 -305.875182) (xy 285.485332 -306.39512) (xy 283.986732 -306.39512)
			)
		)
	)
	(zone
		(layer "In2.Cu")
		(hatch none 0.5)
		(connect_pads
			(clearance 0)
		)
		(min_thickness 0.25)
		(keepout
			(tracks not_allowed)
			(vias allowed)
			(pads allowed)
			(copperpour not_allowed)
			(footprints allowed)
		)
		(placement
			(enabled no)
			(sheetname "")
		)
		(fill
			(thermal_gap 0.5)
			(thermal_bridge_width 0.5)
			(island_removal_mode 0)
		)
		(polygon
			(pts
				(xy 415.718752 -309.275226) (xy 417.217352 -309.275226) (xy 417.217352 -309.795164) (xy 415.718752 -309.795164)
			)
		)
	)
	(zone
		(layer "In2.Cu")
		(hatch none 0.5)
		(connect_pads
			(clearance 0)
		)
		(min_thickness 0.25)
		(keepout
			(tracks not_allowed)
			(vias allowed)
			(pads allowed)
			(copperpour not_allowed)
			(footprints allowed)
		)
		(placement
			(enabled no)
			(sheetname "")
		)
		(fill
			(thermal_gap 0.5)
			(thermal_bridge_width 0.5)
			(island_removal_mode 0)
		)
		(polygon
			(pts
				(xy 449.3387 -306.72532) (xy 450.8373 -306.72532) (xy 450.8373 -307.245258) (xy 449.3387 -307.245258)
			)
		)
	)
	(zone
		(layer "In2.Cu")
		(hatch none 0.5)
		(connect_pads
			(clearance 0)
		)
		(min_thickness 0.25)
		(keepout
			(tracks not_allowed)
			(vias allowed)
			(pads allowed)
			(copperpour not_allowed)
			(footprints allowed)
		)
		(placement
			(enabled no)
			(sheetname "")
		)
		(fill
			(thermal_gap 0.5)
			(thermal_bridge_width 0.5)
			(island_removal_mode 0)
		)
		(polygon
			(pts
				(xy 197.954646 -197.075298) (xy 199.453246 -197.075298) (xy 199.453246 -197.595236) (xy 197.954646 -197.595236)
			)
		)
	)
	(zone
		(layer "In2.Cu")
		(hatch none 0.5)
		(connect_pads
			(clearance 0)
		)
		(min_thickness 0.25)
		(keepout
			(tracks not_allowed)
			(vias allowed)
			(pads allowed)
			(copperpour not_allowed)
			(footprints allowed)
		)
		(placement
			(enabled no)
			(sheetname "")
		)
		(fill
			(thermal_gap 0.5)
			(thermal_bridge_width 0.5)
			(island_removal_mode 0)
		)
		(polygon
			(pts
				(xy 47.034704 -300.775116) (xy 48.533304 -300.775116) (xy 48.533304 -301.295054) (xy 47.034704 -301.295054)
			)
		)
	)
	(zone
		(layer "In2.Cu")
		(hatch none 0.5)
		(connect_pads
			(clearance 0)
		)
		(min_thickness 0.25)
		(keepout
			(tracks not_allowed)
			(vias allowed)
			(pads allowed)
			(copperpour not_allowed)
			(footprints allowed)
		)
		(placement
			(enabled no)
			(sheetname "")
		)
		(fill
			(thermal_gap 0.5)
			(thermal_bridge_width 0.5)
			(island_removal_mode 0)
		)
		(polygon
			(pts
				(xy 294.974772 -213.225126) (xy 296.473372 -213.225126) (xy 296.473372 -213.745064) (xy 294.974772 -213.745064)
			)
		)
	)
	(zone
		(layer "In2.Cu")
		(hatch none 0.5)
		(connect_pads
			(clearance 0)
		)
		(min_thickness 0.25)
		(keepout
			(tracks not_allowed)
			(vias allowed)
			(pads allowed)
			(copperpour not_allowed)
			(footprints allowed)
		)
		(placement
			(enabled no)
			(sheetname "")
		)
		(fill
			(thermal_gap 0.5)
			(thermal_bridge_width 0.5)
			(island_removal_mode 0)
		)
		(polygon
			(pts
				(xy 294.974772 -254.025146) (xy 296.473372 -254.025146) (xy 296.473372 -254.545084) (xy 294.974772 -254.545084)
			)
		)
	)
	(zone
		(layer "In2.Cu")
		(hatch none 0.5)
		(connect_pads
			(clearance 0)
		)
		(min_thickness 0.25)
		(keepout
			(tracks not_allowed)
			(vias allowed)
			(pads allowed)
			(copperpour not_allowed)
			(footprints allowed)
		)
		(placement
			(enabled no)
			(sheetname "")
		)
		(fill
			(thermal_gap 0.5)
			(thermal_bridge_width 0.5)
			(island_removal_mode 0)
		)
		(polygon
			(pts
				(xy 276.442932 -229.375208) (xy 277.941532 -229.375208) (xy 277.941532 -229.895146) (xy 276.442932 -229.895146)
			)
		)
	)
	(zone
		(layer "In2.Cu")
		(hatch none 0.5)
		(connect_pads
			(clearance 0)
		)
		(min_thickness 0.25)
		(keepout
			(tracks not_allowed)
			(vias allowed)
			(pads allowed)
			(copperpour not_allowed)
			(footprints allowed)
		)
		(placement
			(enabled no)
			(sheetname "")
		)
		(fill
			(thermal_gap 0.5)
			(thermal_bridge_width 0.5)
			(island_removal_mode 0)
		)
		(polygon
			(pts
				(xy 453.438768 -285.475172) (xy 454.937368 -285.475172) (xy 454.937368 -285.99511) (xy 453.438768 -285.99511)
			)
		)
	)
	(zone
		(layer "In2.Cu")
		(hatch none 0.5)
		(connect_pads
			(clearance 0)
		)
		(min_thickness 0.25)
		(keepout
			(tracks not_allowed)
			(vias allowed)
			(pads allowed)
			(copperpour not_allowed)
			(footprints allowed)
		)
		(placement
			(enabled no)
			(sheetname "")
		)
		(fill
			(thermal_gap 0.5)
			(thermal_bridge_width 0.5)
			(island_removal_mode 0)
		)
		(polygon
			(pts
				(xy 299.07484 -271.87525) (xy 300.57344 -271.87525) (xy 300.57344 -272.395188) (xy 299.07484 -272.395188)
			)
		)
	)
	(zone
		(layer "In2.Cu")
		(hatch none 0.5)
		(connect_pads
			(clearance 0)
		)
		(min_thickness 0.25)
		(keepout
			(tracks not_allowed)
			(vias allowed)
			(pads allowed)
			(copperpour not_allowed)
			(footprints allowed)
		)
		(placement
			(enabled no)
			(sheetname "")
		)
		(fill
			(thermal_gap 0.5)
			(thermal_bridge_width 0.5)
			(island_removal_mode 0)
		)
		(polygon
			(pts
				(xy 175.322738 -236.175296) (xy 176.821338 -236.175296) (xy 176.821338 -236.695234) (xy 175.322738 -236.695234)
			)
		)
	)
	(zone
		(layer "In2.Cu")
		(hatch none 0.5)
		(connect_pads
			(clearance 0)
		)
		(min_thickness 0.25)
		(keepout
			(tracks not_allowed)
			(vias allowed)
			(pads allowed)
			(copperpour not_allowed)
			(footprints allowed)
		)
		(placement
			(enabled no)
			(sheetname "")
		)
		(fill
			(thermal_gap 0.5)
			(thermal_bridge_width 0.5)
			(island_removal_mode 0)
		)
		(polygon
			(pts
				(xy 163.678616 -272.725134) (xy 165.177216 -272.725134) (xy 165.177216 -273.245072) (xy 163.678616 -273.245072)
			)
		)
	)
	(zone
		(layer "In2.Cu")
		(hatch none 0.5)
		(connect_pads
			(clearance 0)
		)
		(min_thickness 0.25)
		(keepout
			(tracks not_allowed)
			(vias allowed)
			(pads allowed)
			(copperpour not_allowed)
			(footprints allowed)
		)
		(placement
			(enabled no)
			(sheetname "")
		)
		(fill
			(thermal_gap 0.5)
			(thermal_bridge_width 0.5)
			(island_removal_mode 0)
		)
		(polygon
			(pts
				(xy 294.974772 -237.02518) (xy 296.473372 -237.02518) (xy 296.473372 -237.545118) (xy 294.974772 -237.545118)
			)
		)
	)
	(zone
		(layer "In2.Cu")
		(hatch none 0.5)
		(connect_pads
			(clearance 0)
		)
		(min_thickness 0.25)
		(keepout
			(tracks not_allowed)
			(vias allowed)
			(pads allowed)
			(copperpour not_allowed)
			(footprints allowed)
		)
		(placement
			(enabled no)
			(sheetname "")
		)
		(fill
			(thermal_gap 0.5)
			(thermal_bridge_width 0.5)
			(island_removal_mode 0)
		)
		(polygon
			(pts
				(xy 302.518826 -220.025214) (xy 304.017426 -220.025214) (xy 304.017426 -220.545152) (xy 302.518826 -220.545152)
			)
		)
	)
	(zone
		(layer "In2.Cu")
		(hatch none 0.5)
		(connect_pads
			(clearance 0)
		)
		(min_thickness 0.25)
		(keepout
			(tracks not_allowed)
			(vias allowed)
			(pads allowed)
			(copperpour not_allowed)
			(footprints allowed)
		)
		(placement
			(enabled no)
			(sheetname "")
		)
		(fill
			(thermal_gap 0.5)
			(thermal_bridge_width 0.5)
			(island_removal_mode 0)
		)
		(polygon
			(pts
				(xy 51.134772 -236.175296) (xy 52.633372 -236.175296) (xy 52.633372 -236.695234) (xy 51.134772 -236.695234)
			)
		)
	)
	(zone
		(layer "In2.Cu")
		(hatch none 0.5)
		(connect_pads
			(clearance 0)
		)
		(min_thickness 0.25)
		(keepout
			(tracks not_allowed)
			(vias allowed)
			(pads allowed)
			(copperpour not_allowed)
			(footprints allowed)
		)
		(placement
			(enabled no)
			(sheetname "")
		)
		(fill
			(thermal_gap 0.5)
			(thermal_bridge_width 0.5)
			(island_removal_mode 0)
		)
		(polygon
			(pts
				(xy 175.322738 -215.775286) (xy 176.821338 -215.775286) (xy 176.821338 -216.295224) (xy 175.322738 -216.295224)
			)
		)
	)
	(zone
		(layer "In2.Cu")
		(hatch none 0.5)
		(connect_pads
			(clearance 0)
		)
		(min_thickness 0.25)
		(keepout
			(tracks not_allowed)
			(vias allowed)
			(pads allowed)
			(copperpour not_allowed)
			(footprints allowed)
		)
		(placement
			(enabled no)
			(sheetname "")
		)
		(fill
			(thermal_gap 0.5)
			(thermal_bridge_width 0.5)
			(island_removal_mode 0)
		)
		(polygon
			(pts
				(xy 415.718752 -210.67522) (xy 417.217352 -210.67522) (xy 417.217352 -211.195158) (xy 415.718752 -211.195158)
			)
		)
	)
	(zone
		(layer "In2.Cu")
		(hatch none 0.5)
		(connect_pads
			(clearance 0)
		)
		(min_thickness 0.25)
		(keepout
			(tracks not_allowed)
			(vias allowed)
			(pads allowed)
			(copperpour not_allowed)
			(footprints allowed)
		)
		(placement
			(enabled no)
			(sheetname "")
		)
		(fill
			(thermal_gap 0.5)
			(thermal_bridge_width 0.5)
			(island_removal_mode 0)
		)
		(polygon
			(pts
				(xy 16.858742 -285.475172) (xy 18.357342 -285.475172) (xy 18.357342 -285.99511) (xy 16.858742 -285.99511)
			)
		)
	)
	(zone
		(layer "In2.Cu")
		(hatch none 0.5)
		(connect_pads
			(clearance 0)
		)
		(min_thickness 0.25)
		(keepout
			(tracks not_allowed)
			(vias allowed)
			(pads allowed)
			(copperpour not_allowed)
			(footprints allowed)
		)
		(placement
			(enabled no)
			(sheetname "")
		)
		(fill
			(thermal_gap 0.5)
			(thermal_bridge_width 0.5)
			(island_removal_mode 0)
		)
		(polygon
			(pts
				(xy 287.430718 -239.57534) (xy 288.929318 -239.57534) (xy 288.929318 -240.095278) (xy 287.430718 -240.095278)
			)
		)
	)
	(zone
		(layer "In2.Cu")
		(hatch none 0.5)
		(connect_pads
			(clearance 0)
		)
		(min_thickness 0.25)
		(keepout
			(tracks not_allowed)
			(vias allowed)
			(pads allowed)
			(copperpour not_allowed)
			(footprints allowed)
		)
		(placement
			(enabled no)
			(sheetname "")
		)
		(fill
			(thermal_gap 0.5)
			(thermal_bridge_width 0.5)
			(island_removal_mode 0)
		)
		(polygon
			(pts
				(xy 426.706792 -211.525104) (xy 428.205392 -211.525104) (xy 428.205392 -212.045042) (xy 426.706792 -212.045042)
			)
		)
	)
	(zone
		(layer "In2.Cu")
		(hatch none 0.5)
		(connect_pads
			(clearance 0)
		)
		(min_thickness 0.25)
		(keepout
			(tracks not_allowed)
			(vias allowed)
			(pads allowed)
			(copperpour not_allowed)
			(footprints allowed)
		)
		(placement
			(enabled no)
			(sheetname "")
		)
		(fill
			(thermal_gap 0.5)
			(thermal_bridge_width 0.5)
			(island_removal_mode 0)
		)
		(polygon
			(pts
				(xy 291.530786 -231.07523) (xy 293.029386 -231.07523) (xy 293.029386 -231.595168) (xy 291.530786 -231.595168)
			)
		)
	)
	(zone
		(layer "In2.Cu")
		(hatch none 0.5)
		(connect_pads
			(clearance 0)
		)
		(min_thickness 0.25)
		(keepout
			(tracks not_allowed)
			(vias allowed)
			(pads allowed)
			(copperpour not_allowed)
			(footprints allowed)
		)
		(placement
			(enabled no)
			(sheetname "")
		)
		(fill
			(thermal_gap 0.5)
			(thermal_bridge_width 0.5)
			(island_removal_mode 0)
		)
		(polygon
			(pts
				(xy 294.974772 -276.125178) (xy 296.473372 -276.125178) (xy 296.473372 -276.645116) (xy 294.974772 -276.645116)
			)
		)
	)
	(zone
		(layer "In2.Cu")
		(hatch none 0.5)
		(connect_pads
			(clearance 0)
		)
		(min_thickness 0.25)
		(keepout
			(tracks not_allowed)
			(vias allowed)
			(pads allowed)
			(copperpour not_allowed)
			(footprints allowed)
		)
		(placement
			(enabled no)
			(sheetname "")
		)
		(fill
			(thermal_gap 0.5)
			(thermal_bridge_width 0.5)
			(island_removal_mode 0)
		)
		(polygon
			(pts
				(xy 415.718752 -288.875216) (xy 417.217352 -288.875216) (xy 417.217352 -289.395154) (xy 415.718752 -289.395154)
			)
		)
	)
	(zone
		(layer "In2.Cu")
		(hatch none 0.5)
		(connect_pads
			(clearance 0)
		)
		(min_thickness 0.25)
		(keepout
			(tracks not_allowed)
			(vias allowed)
			(pads allowed)
			(copperpour not_allowed)
			(footprints allowed)
		)
		(placement
			(enabled no)
			(sheetname "")
		)
		(fill
			(thermal_gap 0.5)
			(thermal_bridge_width 0.5)
			(island_removal_mode 0)
		)
		(polygon
			(pts
				(xy 20.95881 -276.125178) (xy 22.45741 -276.125178) (xy 22.45741 -276.645116) (xy 20.95881 -276.645116)
			)
		)
	)
	(zone
		(layer "In2.Cu")
		(hatch none 0.5)
		(connect_pads
			(clearance 0)
		)
		(min_thickness 0.25)
		(keepout
			(tracks not_allowed)
			(vias allowed)
			(pads allowed)
			(copperpour not_allowed)
			(footprints allowed)
		)
		(placement
			(enabled no)
			(sheetname "")
		)
		(fill
			(thermal_gap 0.5)
			(thermal_bridge_width 0.5)
			(island_removal_mode 0)
		)
		(polygon
			(pts
				(xy 302.518826 -265.075162) (xy 304.017426 -265.075162) (xy 304.017426 -265.5951) (xy 302.518826 -265.5951)
			)
		)
	)
	(zone
		(layer "In2.Cu")
		(hatch none 0.5)
		(connect_pads
			(clearance 0)
		)
		(min_thickness 0.25)
		(keepout
			(tracks not_allowed)
			(vias allowed)
			(pads allowed)
			(copperpour not_allowed)
			(footprints allowed)
		)
		(placement
			(enabled no)
			(sheetname "")
		)
		(fill
			(thermal_gap 0.5)
			(thermal_bridge_width 0.5)
			(island_removal_mode 0)
		)
		(polygon
			(pts
				(xy 445.894968 -220.025214) (xy 447.393568 -220.025214) (xy 447.393568 -220.545152) (xy 445.894968 -220.545152)
			)
		)
	)
	(zone
		(layer "In2.Cu")
		(hatch none 0.5)
		(connect_pads
			(clearance 0)
		)
		(min_thickness 0.25)
		(keepout
			(tracks not_allowed)
			(vias allowed)
			(pads allowed)
			(copperpour not_allowed)
			(footprints allowed)
		)
		(placement
			(enabled no)
			(sheetname "")
		)
		(fill
			(thermal_gap 0.5)
			(thermal_bridge_width 0.5)
			(island_removal_mode 0)
		)
		(polygon
			(pts
				(xy 279.886664 -203.875132) (xy 281.385264 -203.875132) (xy 281.385264 -204.39507) (xy 279.886664 -204.39507)
			)
		)
	)
	(zone
		(layer "In2.Cu")
		(hatch none 0.5)
		(connect_pads
			(clearance 0)
		)
		(min_thickness 0.25)
		(keepout
			(tracks not_allowed)
			(vias allowed)
			(pads allowed)
			(copperpour not_allowed)
			(footprints allowed)
		)
		(placement
			(enabled no)
			(sheetname "")
		)
		(fill
			(thermal_gap 0.5)
			(thermal_bridge_width 0.5)
			(island_removal_mode 0)
		)
		(polygon
			(pts
				(xy 279.886664 -207.275176) (xy 281.385264 -207.275176) (xy 281.385264 -207.795114) (xy 279.886664 -207.795114)
			)
		)
	)
	(zone
		(layer "In2.Cu")
		(hatch none 0.5)
		(connect_pads
			(clearance 0)
		)
		(min_thickness 0.25)
		(keepout
			(tracks not_allowed)
			(vias allowed)
			(pads allowed)
			(copperpour not_allowed)
			(footprints allowed)
		)
		(placement
			(enabled no)
			(sheetname "")
		)
		(fill
			(thermal_gap 0.5)
			(thermal_bridge_width 0.5)
			(island_removal_mode 0)
		)
		(polygon
			(pts
				(xy 411.618684 -238.725202) (xy 413.117284 -238.725202) (xy 413.117284 -239.24514) (xy 411.618684 -239.24514)
			)
		)
	)
	(zone
		(layer "In2.Cu")
		(hatch none 0.5)
		(connect_pads
			(clearance 0)
		)
		(min_thickness 0.25)
		(keepout
			(tracks not_allowed)
			(vias allowed)
			(pads allowed)
			(copperpour not_allowed)
			(footprints allowed)
		)
		(placement
			(enabled no)
			(sheetname "")
		)
		(fill
			(thermal_gap 0.5)
			(thermal_bridge_width 0.5)
			(island_removal_mode 0)
		)
		(polygon
			(pts
				(xy 449.3387 -231.925114) (xy 450.8373 -231.925114) (xy 450.8373 -232.445052) (xy 449.3387 -232.445052)
			)
		)
	)
	(zone
		(layer "In2.Cu")
		(hatch none 0.5)
		(connect_pads
			(clearance 0)
		)
		(min_thickness 0.25)
		(keepout
			(tracks not_allowed)
			(vias allowed)
			(pads allowed)
			(copperpour not_allowed)
			(footprints allowed)
		)
		(placement
			(enabled no)
			(sheetname "")
		)
		(fill
			(thermal_gap 0.5)
			(thermal_bridge_width 0.5)
			(island_removal_mode 0)
		)
		(polygon
			(pts
				(xy 28.50261 -303.325276) (xy 30.00121 -303.325276) (xy 30.00121 -303.845214) (xy 28.50261 -303.845214)
			)
		)
	)
	(zone
		(layer "In2.Cu")
		(hatch none 0.5)
		(connect_pads
			(clearance 0)
		)
		(min_thickness 0.25)
		(keepout
			(tracks not_allowed)
			(vias allowed)
			(pads allowed)
			(copperpour not_allowed)
			(footprints allowed)
		)
		(placement
			(enabled no)
			(sheetname "")
		)
		(fill
			(thermal_gap 0.5)
			(thermal_bridge_width 0.5)
			(island_removal_mode 0)
		)
		(polygon
			(pts
				(xy 20.95881 -312.67527) (xy 22.45741 -312.67527) (xy 22.45741 -313.195208) (xy 20.95881 -313.195208)
			)
		)
	)
	(zone
		(layer "In2.Cu")
		(hatch none 0.5)
		(connect_pads
			(clearance 0)
		)
		(min_thickness 0.25)
		(keepout
			(tracks not_allowed)
			(vias allowed)
			(pads allowed)
			(copperpour not_allowed)
			(footprints allowed)
		)
		(placement
			(enabled no)
			(sheetname "")
		)
		(fill
			(thermal_gap 0.5)
			(thermal_bridge_width 0.5)
			(island_removal_mode 0)
		)
		(polygon
			(pts
				(xy 167.778684 -204.72527) (xy 169.277284 -204.72527) (xy 169.277284 -205.245208) (xy 167.778684 -205.245208)
			)
		)
	)
	(zone
		(layer "In2.Cu")
		(hatch none 0.5)
		(connect_pads
			(clearance 0)
		)
		(min_thickness 0.25)
		(keepout
			(tracks not_allowed)
			(vias allowed)
			(pads allowed)
			(copperpour not_allowed)
			(footprints allowed)
		)
		(placement
			(enabled no)
			(sheetname "")
		)
		(fill
			(thermal_gap 0.5)
			(thermal_bridge_width 0.5)
			(island_removal_mode 0)
		)
		(polygon
			(pts
				(xy 171.22267 -268.475206) (xy 172.72127 -268.475206) (xy 172.72127 -268.995144) (xy 171.22267 -268.995144)
			)
		)
	)
	(zone
		(layer "In2.Cu")
		(hatch none 0.5)
		(connect_pads
			(clearance 0)
		)
		(min_thickness 0.25)
		(keepout
			(tracks not_allowed)
			(vias allowed)
			(pads allowed)
			(copperpour not_allowed)
			(footprints allowed)
		)
		(placement
			(enabled no)
			(sheetname "")
		)
		(fill
			(thermal_gap 0.5)
			(thermal_bridge_width 0.5)
			(island_removal_mode 0)
		)
		(polygon
			(pts
				(xy 190.410846 -204.72527) (xy 191.909446 -204.72527) (xy 191.909446 -205.245208) (xy 190.410846 -205.245208)
			)
		)
	)
	(zone
		(layer "In2.Cu")
		(hatch none 0.5)
		(connect_pads
			(clearance 0)
		)
		(min_thickness 0.25)
		(keepout
			(tracks not_allowed)
			(vias allowed)
			(pads allowed)
			(copperpour not_allowed)
			(footprints allowed)
		)
		(placement
			(enabled no)
			(sheetname "")
		)
		(fill
			(thermal_gap 0.5)
			(thermal_bridge_width 0.5)
			(island_removal_mode 0)
		)
		(polygon
			(pts
				(xy 423.262806 -215.775286) (xy 424.761406 -215.775286) (xy 424.761406 -216.295224) (xy 423.262806 -216.295224)
			)
		)
	)
	(zone
		(layer "In2.Cu")
		(hatch none 0.5)
		(connect_pads
			(clearance 0)
		)
		(min_thickness 0.25)
		(keepout
			(tracks not_allowed)
			(vias allowed)
			(pads allowed)
			(copperpour not_allowed)
			(footprints allowed)
		)
		(placement
			(enabled no)
			(sheetname "")
		)
		(fill
			(thermal_gap 0.5)
			(thermal_bridge_width 0.5)
			(island_removal_mode 0)
		)
		(polygon
			(pts
				(xy 279.886664 -280.375106) (xy 281.385264 -280.375106) (xy 281.385264 -280.895044) (xy 279.886664 -280.895044)
			)
		)
	)
	(zone
		(layer "In2.Cu")
		(hatch none 0.5)
		(connect_pads
			(clearance 0)
		)
		(min_thickness 0.25)
		(keepout
			(tracks not_allowed)
			(vias allowed)
			(pads allowed)
			(copperpour not_allowed)
			(footprints allowed)
		)
		(placement
			(enabled no)
			(sheetname "")
		)
		(fill
			(thermal_gap 0.5)
			(thermal_bridge_width 0.5)
			(island_removal_mode 0)
		)
		(polygon
			(pts
				(xy 175.322738 -273.575272) (xy 176.821338 -273.575272) (xy 176.821338 -274.09521) (xy 175.322738 -274.09521)
			)
		)
	)
	(zone
		(layer "In2.Cu")
		(hatch none 0.5)
		(connect_pads
			(clearance 0)
		)
		(min_thickness 0.25)
		(keepout
			(tracks not_allowed)
			(vias allowed)
			(pads allowed)
			(copperpour not_allowed)
			(footprints allowed)
		)
		(placement
			(enabled no)
			(sheetname "")
		)
		(fill
			(thermal_gap 0.5)
			(thermal_bridge_width 0.5)
			(island_removal_mode 0)
		)
		(polygon
			(pts
				(xy 302.518826 -205.575154) (xy 304.017426 -205.575154) (xy 304.017426 -206.095092) (xy 302.518826 -206.095092)
			)
		)
	)
	(zone
		(layer "In2.Cu")
		(hatch none 0.5)
		(connect_pads
			(clearance 0)
		)
		(min_thickness 0.25)
		(keepout
			(tracks not_allowed)
			(vias allowed)
			(pads allowed)
			(copperpour not_allowed)
			(footprints allowed)
		)
		(placement
			(enabled no)
			(sheetname "")
		)
		(fill
			(thermal_gap 0.5)
			(thermal_bridge_width 0.5)
			(island_removal_mode 0)
		)
		(polygon
			(pts
				(xy 197.954646 -248.925334) (xy 199.453246 -248.925334) (xy 199.453246 -249.445272) (xy 197.954646 -249.445272)
			)
		)
	)
	(zone
		(layer "In2.Cu")
		(hatch none 0.5)
		(connect_pads
			(clearance 0)
		)
		(min_thickness 0.25)
		(keepout
			(tracks not_allowed)
			(vias allowed)
			(pads allowed)
			(copperpour not_allowed)
			(footprints allowed)
		)
		(placement
			(enabled no)
			(sheetname "")
		)
		(fill
			(thermal_gap 0.5)
			(thermal_bridge_width 0.5)
			(island_removal_mode 0)
		)
		(polygon
			(pts
				(xy 167.778684 -287.175194) (xy 169.277284 -287.175194) (xy 169.277284 -287.695132) (xy 167.778684 -287.695132)
			)
		)
	)
	(zone
		(layer "In2.Cu")
		(hatch none 0.5)
		(connect_pads
			(clearance 0)
		)
		(min_thickness 0.25)
		(keepout
			(tracks not_allowed)
			(vias allowed)
			(pads allowed)
			(copperpour not_allowed)
			(footprints allowed)
		)
		(placement
			(enabled no)
			(sheetname "")
		)
		(fill
			(thermal_gap 0.5)
			(thermal_bridge_width 0.5)
			(island_removal_mode 0)
		)
		(polygon
			(pts
				(xy 438.350914 -245.52529) (xy 439.849514 -245.52529) (xy 439.849514 -246.045228) (xy 438.350914 -246.045228)
			)
		)
	)
	(zone
		(layer "In2.Cu")
		(hatch none 0.5)
		(connect_pads
			(clearance 0)
		)
		(min_thickness 0.25)
		(keepout
			(tracks not_allowed)
			(vias allowed)
			(pads allowed)
			(copperpour not_allowed)
			(footprints allowed)
		)
		(placement
			(enabled no)
			(sheetname "")
		)
		(fill
			(thermal_gap 0.5)
			(thermal_bridge_width 0.5)
			(island_removal_mode 0)
		)
		(polygon
			(pts
				(xy 426.706792 -317.775336) (xy 428.205392 -317.775336) (xy 428.205392 -318.295274) (xy 426.706792 -318.295274)
			)
		)
	)
	(zone
		(layer "In2.Cu")
		(hatch none 0.5)
		(connect_pads
			(clearance 0)
		)
		(min_thickness 0.25)
		(keepout
			(tracks not_allowed)
			(vias allowed)
			(pads allowed)
			(copperpour not_allowed)
			(footprints allowed)
		)
		(placement
			(enabled no)
			(sheetname "")
		)
		(fill
			(thermal_gap 0.5)
			(thermal_bridge_width 0.5)
			(island_removal_mode 0)
		)
		(polygon
			(pts
				(xy 279.886664 -211.525104) (xy 281.385264 -211.525104) (xy 281.385264 -212.045042) (xy 279.886664 -212.045042)
			)
		)
	)
	(zone
		(layer "In2.Cu")
		(hatch none 0.5)
		(connect_pads
			(clearance 0)
		)
		(min_thickness 0.25)
		(keepout
			(tracks not_allowed)
			(vias allowed)
			(pads allowed)
			(copperpour not_allowed)
			(footprints allowed)
		)
		(placement
			(enabled no)
			(sheetname "")
		)
		(fill
			(thermal_gap 0.5)
			(thermal_bridge_width 0.5)
			(island_removal_mode 0)
		)
		(polygon
			(pts
				(xy 28.50261 -198.77532) (xy 30.00121 -198.77532) (xy 30.00121 -199.295258) (xy 28.50261 -199.295258)
			)
		)
	)
	(zone
		(layer "In2.Cu")
		(hatch none 0.5)
		(connect_pads
			(clearance 0)
		)
		(min_thickness 0.25)
		(keepout
			(tracks not_allowed)
			(vias allowed)
			(pads allowed)
			(copperpour not_allowed)
			(footprints allowed)
		)
		(placement
			(enabled no)
			(sheetname "")
		)
		(fill
			(thermal_gap 0.5)
			(thermal_bridge_width 0.5)
			(island_removal_mode 0)
		)
		(polygon
			(pts
				(xy 423.262806 -232.775252) (xy 424.761406 -232.775252) (xy 424.761406 -233.29519) (xy 423.262806 -233.29519)
			)
		)
	)
	(zone
		(layer "In2.Cu")
		(hatch none 0.5)
		(connect_pads
			(clearance 0)
		)
		(min_thickness 0.25)
		(keepout
			(tracks not_allowed)
			(vias allowed)
			(pads allowed)
			(copperpour not_allowed)
			(footprints allowed)
		)
		(placement
			(enabled no)
			(sheetname "")
		)
		(fill
			(thermal_gap 0.5)
			(thermal_bridge_width 0.5)
			(island_removal_mode 0)
		)
		(polygon
			(pts
				(xy 28.50261 -260.825234) (xy 30.00121 -260.825234) (xy 30.00121 -261.345172) (xy 28.50261 -261.345172)
			)
		)
	)
	(zone
		(layer "In2.Cu")
		(hatch none 0.5)
		(connect_pads
			(clearance 0)
		)
		(min_thickness 0.25)
		(keepout
			(tracks not_allowed)
			(vias allowed)
			(pads allowed)
			(copperpour not_allowed)
			(footprints allowed)
		)
		(placement
			(enabled no)
			(sheetname "")
		)
		(fill
			(thermal_gap 0.5)
			(thermal_bridge_width 0.5)
			(island_removal_mode 0)
		)
		(polygon
			(pts
				(xy 20.95881 -303.325276) (xy 22.45741 -303.325276) (xy 22.45741 -303.845214) (xy 20.95881 -303.845214)
			)
		)
	)
	(zone
		(layer "In2.Cu")
		(hatch none 0.5)
		(connect_pads
			(clearance 0)
		)
		(min_thickness 0.25)
		(keepout
			(tracks not_allowed)
			(vias allowed)
			(pads allowed)
			(copperpour not_allowed)
			(footprints allowed)
		)
		(placement
			(enabled no)
			(sheetname "")
		)
		(fill
			(thermal_gap 0.5)
			(thermal_bridge_width 0.5)
			(island_removal_mode 0)
		)
		(polygon
			(pts
				(xy 54.578758 -293.125144) (xy 56.077358 -293.125144) (xy 56.077358 -293.645082) (xy 54.578758 -293.645082)
			)
		)
	)
	(zone
		(layer "In2.Cu")
		(hatch none 0.5)
		(connect_pads
			(clearance 0)
		)
		(min_thickness 0.25)
		(keepout
			(tracks not_allowed)
			(vias allowed)
			(pads allowed)
			(copperpour not_allowed)
			(footprints allowed)
		)
		(placement
			(enabled no)
			(sheetname "")
		)
		(fill
			(thermal_gap 0.5)
			(thermal_bridge_width 0.5)
			(island_removal_mode 0)
		)
		(polygon
			(pts
				(xy 441.7949 -308.425342) (xy 443.2935 -308.425342) (xy 443.2935 -308.94528) (xy 441.7949 -308.94528)
			)
		)
	)
	(zone
		(layer "In2.Cu")
		(hatch none 0.5)
		(connect_pads
			(clearance 0)
		)
		(min_thickness 0.25)
		(keepout
			(tracks not_allowed)
			(vias allowed)
			(pads allowed)
			(copperpour not_allowed)
			(footprints allowed)
		)
		(placement
			(enabled no)
			(sheetname "")
		)
		(fill
			(thermal_gap 0.5)
			(thermal_bridge_width 0.5)
			(island_removal_mode 0)
		)
		(polygon
			(pts
				(xy 302.518826 -202.17511) (xy 304.017426 -202.17511) (xy 304.017426 -202.695048) (xy 302.518826 -202.695048)
			)
		)
	)
	(zone
		(layer "In2.Cu")
		(hatch none 0.5)
		(connect_pads
			(clearance 0)
		)
		(min_thickness 0.25)
		(keepout
			(tracks not_allowed)
			(vias allowed)
			(pads allowed)
			(copperpour not_allowed)
			(footprints allowed)
		)
		(placement
			(enabled no)
			(sheetname "")
		)
		(fill
			(thermal_gap 0.5)
			(thermal_bridge_width 0.5)
			(island_removal_mode 0)
		)
		(polygon
			(pts
				(xy 419.162738 -230.225346) (xy 420.661338 -230.225346) (xy 420.661338 -230.745284) (xy 419.162738 -230.745284)
			)
		)
	)
	(zone
		(layer "In2.Cu")
		(hatch none 0.5)
		(connect_pads
			(clearance 0)
		)
		(min_thickness 0.25)
		(keepout
			(tracks not_allowed)
			(vias allowed)
			(pads allowed)
			(copperpour not_allowed)
			(footprints allowed)
		)
		(placement
			(enabled no)
			(sheetname "")
		)
		(fill
			(thermal_gap 0.5)
			(thermal_bridge_width 0.5)
			(island_removal_mode 0)
		)
		(polygon
			(pts
				(xy 306.618894 -243.825268) (xy 308.117494 -243.825268) (xy 308.117494 -244.345206) (xy 306.618894 -244.345206)
			)
		)
	)
	(zone
		(layer "In2.Cu")
		(hatch none 0.5)
		(connect_pads
			(clearance 0)
		)
		(min_thickness 0.25)
		(keepout
			(tracks not_allowed)
			(vias allowed)
			(pads allowed)
			(copperpour not_allowed)
			(footprints allowed)
		)
		(placement
			(enabled no)
			(sheetname "")
		)
		(fill
			(thermal_gap 0.5)
			(thermal_bridge_width 0.5)
			(island_removal_mode 0)
		)
		(polygon
			(pts
				(xy 426.706792 -276.125178) (xy 428.205392 -276.125178) (xy 428.205392 -276.645116) (xy 426.706792 -276.645116)
			)
		)
	)
	(zone
		(layer "In2.Cu")
		(hatch none 0.5)
		(connect_pads
			(clearance 0)
		)
		(min_thickness 0.25)
		(keepout
			(tracks not_allowed)
			(vias allowed)
			(pads allowed)
			(copperpour not_allowed)
			(footprints allowed)
		)
		(placement
			(enabled no)
			(sheetname "")
		)
		(fill
			(thermal_gap 0.5)
			(thermal_bridge_width 0.5)
			(island_removal_mode 0)
		)
		(polygon
			(pts
				(xy 411.618684 -229.375208) (xy 413.117284 -229.375208) (xy 413.117284 -229.895146) (xy 411.618684 -229.895146)
			)
		)
	)
	(zone
		(layer "In2.Cu")
		(hatch none 0.5)
		(connect_pads
			(clearance 0)
		)
		(min_thickness 0.25)
		(keepout
			(tracks not_allowed)
			(vias allowed)
			(pads allowed)
			(copperpour not_allowed)
			(footprints allowed)
		)
		(placement
			(enabled no)
			(sheetname "")
		)
		(fill
			(thermal_gap 0.5)
			(thermal_bridge_width 0.5)
			(island_removal_mode 0)
		)
		(polygon
			(pts
				(xy 47.034704 -216.62517) (xy 48.533304 -216.62517) (xy 48.533304 -217.145108) (xy 47.034704 -217.145108)
			)
		)
	)
	(zone
		(layer "In2.Cu")
		(hatch none 0.5)
		(connect_pads
			(clearance 0)
		)
		(min_thickness 0.25)
		(keepout
			(tracks not_allowed)
			(vias allowed)
			(pads allowed)
			(copperpour not_allowed)
			(footprints allowed)
		)
		(placement
			(enabled no)
			(sheetname "")
		)
		(fill
			(thermal_gap 0.5)
			(thermal_bridge_width 0.5)
			(island_removal_mode 0)
		)
		(polygon
			(pts
				(xy 36.046664 -201.325226) (xy 37.545264 -201.325226) (xy 37.545264 -201.845164) (xy 36.046664 -201.845164)
			)
		)
	)
	(zone
		(layer "In2.Cu")
		(hatch none 0.5)
		(connect_pads
			(clearance 0)
		)
		(min_thickness 0.25)
		(keepout
			(tracks not_allowed)
			(vias allowed)
			(pads allowed)
			(copperpour not_allowed)
			(footprints allowed)
		)
		(placement
			(enabled no)
			(sheetname "")
		)
		(fill
			(thermal_gap 0.5)
			(thermal_bridge_width 0.5)
			(island_removal_mode 0)
		)
		(polygon
			(pts
				(arc
					(start 313.397646 -381.824484)
					(mid 313.41757 -381.83372)
					(end 313.439302 -381.83693)
				)
				(arc
					(start 313.633866 -381.83693)
					(mid 313.687748 -381.814612)
					(end 313.710066 -381.76073)
				)
				(arc
					(start 313.710066 -381.07493)
					(mid 313.687748 -381.021048)
					(end 313.633866 -380.99873)
				)
				(arc
					(start 313.439302 -380.99873)
					(mid 313.417558 -381.001898)
					(end 313.397646 -381.011176)
				)
				(arc
					(start 313.101482 -381.203962)
					(mid 313.059798 -381.216184)
					(end 313.01817 -381.203708)
				)
				(arc
					(start 312.724546 -381.011176)
					(mid 312.704622 -381.00194)
					(end 312.68289 -380.99873)
				)
				(arc
					(start 312.488326 -380.99873)
					(mid 312.434444 -381.021048)
					(end 312.412126 -381.07493)
				)
				(arc
					(start 312.412126 -381.76073)
					(mid 312.434444 -381.814612)
					(end 312.488326 -381.83693)
				)
				(arc
					(start 312.68416 -381.83693)
					(mid 312.705904 -381.833762)
					(end 312.725816 -381.824484)
				)
				(arc
					(start 313.01944 -381.631952)
					(mid 313.061096 -381.61955)
					(end 313.102752 -381.631952)
				)
			)
		)
	)
	(zone
		(layer "In2.Cu")
		(hatch none 0.5)
		(connect_pads
			(clearance 0)
		)
		(min_thickness 0.25)
		(keepout
			(tracks not_allowed)
			(vias allowed)
			(pads allowed)
			(copperpour not_allowed)
			(footprints allowed)
		)
		(placement
			(enabled no)
			(sheetname "")
		)
		(fill
			(thermal_gap 0.5)
			(thermal_bridge_width 0.5)
			(island_removal_mode 0)
		)
		(polygon
			(pts
				(xy 306.618894 -215.775286) (xy 308.117494 -215.775286) (xy 308.117494 -216.295224) (xy 306.618894 -216.295224)
			)
		)
	)
	(zone
		(layer "In2.Cu")
		(hatch none 0.5)
		(connect_pads
			(clearance 0)
		)
		(min_thickness 0.25)
		(keepout
			(tracks not_allowed)
			(vias allowed)
			(pads allowed)
			(copperpour not_allowed)
			(footprints allowed)
		)
		(placement
			(enabled no)
			(sheetname "")
		)
		(fill
			(thermal_gap 0.5)
			(thermal_bridge_width 0.5)
			(island_removal_mode 0)
		)
		(polygon
			(pts
				(xy 36.046664 -219.17533) (xy 37.545264 -219.17533) (xy 37.545264 -219.695268) (xy 36.046664 -219.695268)
			)
		)
	)
	(zone
		(layer "In2.Cu")
		(hatch none 0.5)
		(connect_pads
			(clearance 0)
		)
		(min_thickness 0.25)
		(keepout
			(tracks not_allowed)
			(vias allowed)
			(pads allowed)
			(copperpour not_allowed)
			(footprints allowed)
		)
		(placement
			(enabled no)
			(sheetname "")
		)
		(fill
			(thermal_gap 0.5)
			(thermal_bridge_width 0.5)
			(island_removal_mode 0)
		)
		(polygon
			(pts
				(xy 16.858742 -274.425156) (xy 18.357342 -274.425156) (xy 18.357342 -274.945094) (xy 16.858742 -274.945094)
			)
		)
	)
	(zone
		(layer "In2.Cu")
		(hatch none 0.5)
		(connect_pads
			(clearance 0)
		)
		(min_thickness 0.25)
		(keepout
			(tracks not_allowed)
			(vias allowed)
			(pads allowed)
			(copperpour not_allowed)
			(footprints allowed)
		)
		(placement
			(enabled no)
			(sheetname "")
		)
		(fill
			(thermal_gap 0.5)
			(thermal_bridge_width 0.5)
			(island_removal_mode 0)
		)
		(polygon
			(pts
				(xy 175.322738 -254.025146) (xy 176.821338 -254.025146) (xy 176.821338 -254.545084) (xy 175.322738 -254.545084)
			)
		)
	)
	(zone
		(layer "In2.Cu")
		(hatch none 0.5)
		(connect_pads
			(clearance 0)
		)
		(min_thickness 0.25)
		(keepout
			(tracks not_allowed)
			(vias allowed)
			(pads allowed)
			(copperpour not_allowed)
			(footprints allowed)
		)
		(placement
			(enabled no)
			(sheetname "")
		)
		(fill
			(thermal_gap 0.5)
			(thermal_bridge_width 0.5)
			(island_removal_mode 0)
		)
		(polygon
			(pts
				(xy 47.034704 -283.77515) (xy 48.533304 -283.77515) (xy 48.533304 -284.295088) (xy 47.034704 -284.295088)
			)
		)
	)
	(zone
		(layer "In2.Cu")
		(hatch none 0.5)
		(connect_pads
			(clearance 0)
		)
		(min_thickness 0.25)
		(keepout
			(tracks not_allowed)
			(vias allowed)
			(pads allowed)
			(copperpour not_allowed)
			(footprints allowed)
		)
		(placement
			(enabled no)
			(sheetname "")
		)
		(fill
			(thermal_gap 0.5)
			(thermal_bridge_width 0.5)
			(island_removal_mode 0)
		)
		(polygon
			(pts
				(xy 193.854578 -199.625204) (xy 195.353178 -199.625204) (xy 195.353178 -200.145142) (xy 193.854578 -200.145142)
			)
		)
	)
	(zone
		(layer "In2.Cu")
		(hatch none 0.5)
		(connect_pads
			(clearance 0)
		)
		(min_thickness 0.25)
		(keepout
			(tracks not_allowed)
			(vias allowed)
			(pads allowed)
			(copperpour not_allowed)
			(footprints allowed)
		)
		(placement
			(enabled no)
			(sheetname "")
		)
		(fill
			(thermal_gap 0.5)
			(thermal_bridge_width 0.5)
			(island_removal_mode 0)
		)
		(polygon
			(pts
				(arc
					(start 357.86187 -385.243578)
					(mid 357.852634 -385.263502)
					(end 357.849424 -385.285234)
				)
				(arc
					(start 357.849424 -385.479798)
					(mid 357.871742 -385.53368)
					(end 357.925624 -385.555998)
				)
				(arc
					(start 358.611424 -385.555998)
					(mid 358.665306 -385.53368)
					(end 358.687624 -385.479798)
				)
				(arc
					(start 358.687624 -385.285234)
					(mid 358.684456 -385.26349)
					(end 358.675178 -385.243578)
				)
				(arc
					(start 358.482392 -384.947414)
					(mid 358.47017 -384.90573)
					(end 358.482646 -384.864102)
				)
				(arc
					(start 358.675178 -384.570478)
					(mid 358.684414 -384.550554)
					(end 358.687624 -384.528822)
				)
				(arc
					(start 358.687624 -384.334258)
					(mid 358.665306 -384.280376)
					(end 358.611424 -384.258058)
				)
				(arc
					(start 357.925624 -384.258058)
					(mid 357.871742 -384.280376)
					(end 357.849424 -384.334258)
				)
				(arc
					(start 357.849424 -384.530092)
					(mid 357.852592 -384.551836)
					(end 357.86187 -384.571748)
				)
				(arc
					(start 358.054402 -384.865372)
					(mid 358.066804 -384.907028)
					(end 358.054402 -384.948684)
				)
			)
		)
	)
	(zone
		(layer "In2.Cu")
		(hatch none 0.5)
		(connect_pads
			(clearance 0)
		)
		(min_thickness 0.25)
		(keepout
			(tracks not_allowed)
			(vias allowed)
			(pads allowed)
			(copperpour not_allowed)
			(footprints allowed)
		)
		(placement
			(enabled no)
			(sheetname "")
		)
		(fill
			(thermal_gap 0.5)
			(thermal_bridge_width 0.5)
			(island_removal_mode 0)
		)
		(polygon
			(pts
				(xy 415.718752 -254.025146) (xy 417.217352 -254.025146) (xy 417.217352 -254.545084) (xy 415.718752 -254.545084)
			)
		)
	)
	(zone
		(layer "In2.Cu")
		(hatch none 0.5)
		(connect_pads
			(clearance 0)
		)
		(min_thickness 0.25)
		(keepout
			(tracks not_allowed)
			(vias allowed)
			(pads allowed)
			(copperpour not_allowed)
			(footprints allowed)
		)
		(placement
			(enabled no)
			(sheetname "")
		)
		(fill
			(thermal_gap 0.5)
			(thermal_bridge_width 0.5)
			(island_removal_mode 0)
		)
		(polygon
			(pts
				(xy 434.250846 -286.32531) (xy 435.749446 -286.32531) (xy 435.749446 -286.845248) (xy 434.250846 -286.845248)
			)
		)
	)
	(zone
		(layer "In2.Cu")
		(hatch none 0.5)
		(connect_pads
			(clearance 0)
		)
		(min_thickness 0.25)
		(keepout
			(tracks not_allowed)
			(vias allowed)
			(pads allowed)
			(copperpour not_allowed)
			(footprints allowed)
		)
		(placement
			(enabled no)
			(sheetname "")
		)
		(fill
			(thermal_gap 0.5)
			(thermal_bridge_width 0.5)
			(island_removal_mode 0)
		)
		(polygon
			(pts
				(xy 268.898878 -298.22521) (xy 270.397478 -298.22521) (xy 270.397478 -298.745148) (xy 268.898878 -298.745148)
			)
		)
	)
	(zone
		(layer "In2.Cu")
		(hatch none 0.5)
		(connect_pads
			(clearance 0)
		)
		(min_thickness 0.25)
		(keepout
			(tracks not_allowed)
			(vias allowed)
			(pads allowed)
			(copperpour not_allowed)
			(footprints allowed)
		)
		(placement
			(enabled no)
			(sheetname "")
		)
		(fill
			(thermal_gap 0.5)
			(thermal_bridge_width 0.5)
			(island_removal_mode 0)
		)
		(polygon
			(pts
				(xy 28.50261 -273.575272) (xy 30.00121 -273.575272) (xy 30.00121 -274.09521) (xy 28.50261 -274.09521)
			)
		)
	)
	(zone
		(layer "In2.Cu")
		(hatch none 0.5)
		(connect_pads
			(clearance 0)
		)
		(min_thickness 0.25)
		(keepout
			(tracks not_allowed)
			(vias allowed)
			(pads allowed)
			(copperpour not_allowed)
			(footprints allowed)
		)
		(placement
			(enabled no)
			(sheetname "")
		)
		(fill
			(thermal_gap 0.5)
			(thermal_bridge_width 0.5)
			(island_removal_mode 0)
		)
		(polygon
			(pts
				(xy 438.350914 -288.875216) (xy 439.849514 -288.875216) (xy 439.849514 -289.395154) (xy 438.350914 -289.395154)
			)
		)
	)
	(zone
		(layer "In2.Cu")
		(hatch none 0.5)
		(connect_pads
			(clearance 0)
		)
		(min_thickness 0.25)
		(keepout
			(tracks not_allowed)
			(vias allowed)
			(pads allowed)
			(copperpour not_allowed)
			(footprints allowed)
		)
		(placement
			(enabled no)
			(sheetname "")
		)
		(fill
			(thermal_gap 0.5)
			(thermal_bridge_width 0.5)
			(island_removal_mode 0)
		)
		(polygon
			(pts
				(xy 434.250846 -253.175262) (xy 435.749446 -253.175262) (xy 435.749446 -253.6952) (xy 434.250846 -253.6952)
			)
		)
	)
	(zone
		(layer "In2.Cu")
		(hatch none 0.5)
		(connect_pads
			(clearance 0)
		)
		(min_thickness 0.25)
		(keepout
			(tracks not_allowed)
			(vias allowed)
			(pads allowed)
			(copperpour not_allowed)
			(footprints allowed)
		)
		(placement
			(enabled no)
			(sheetname "")
		)
		(fill
			(thermal_gap 0.5)
			(thermal_bridge_width 0.5)
			(island_removal_mode 0)
		)
		(polygon
			(pts
				(arc
					(start 37.668708 -16.442436)
					(mid 37.691026 -16.496318)
					(end 37.744908 -16.518636)
				)
				(arc
					(start 37.940488 -16.518636)
					(mid 37.962364 -16.515504)
					(end 37.982398 -16.50619)
				)
				(arc
					(start 38.276022 -16.313658)
					(mid 38.317678 -16.301256)
					(end 38.359334 -16.313658)
				)
				(arc
					(start 38.654228 -16.50619)
					(mid 38.674152 -16.515426)
					(end 38.695884 -16.518636)
				)
				(arc
					(start 38.890448 -16.518636)
					(mid 38.94433 -16.496318)
					(end 38.966648 -16.442436)
				)
				(arc
					(start 38.966648 -15.756636)
					(mid 38.94433 -15.702754)
					(end 38.890448 -15.680436)
				)
				(arc
					(start 38.695884 -15.680436)
					(mid 38.67414 -15.683604)
					(end 38.654228 -15.692882)
				)
				(arc
					(start 38.358064 -15.885668)
					(mid 38.31638 -15.89789)
					(end 38.274752 -15.885414)
				)
				(arc
					(start 37.981128 -15.692882)
					(mid 37.961204 -15.683646)
					(end 37.939472 -15.680436)
				)
				(arc
					(start 37.744908 -15.680436)
					(mid 37.691026 -15.702754)
					(end 37.668708 -15.756636)
				)
			)
		)
	)
	(zone
		(layer "In2.Cu")
		(hatch none 0.5)
		(connect_pads
			(clearance 0)
		)
		(min_thickness 0.25)
		(keepout
			(tracks not_allowed)
			(vias allowed)
			(pads allowed)
			(copperpour not_allowed)
			(footprints allowed)
		)
		(placement
			(enabled no)
			(sheetname "")
		)
		(fill
			(thermal_gap 0.5)
			(thermal_bridge_width 0.5)
			(island_removal_mode 0)
		)
		(polygon
			(pts
				(xy 54.578758 -231.925114) (xy 56.077358 -231.925114) (xy 56.077358 -232.445052) (xy 54.578758 -232.445052)
			)
		)
	)
	(zone
		(layer "In2.Cu")
		(hatch none 0.5)
		(connect_pads
			(clearance 0)
		)
		(min_thickness 0.25)
		(keepout
			(tracks not_allowed)
			(vias allowed)
			(pads allowed)
			(copperpour not_allowed)
			(footprints allowed)
		)
		(placement
			(enabled no)
			(sheetname "")
		)
		(fill
			(thermal_gap 0.5)
			(thermal_bridge_width 0.5)
			(island_removal_mode 0)
		)
		(polygon
			(pts
				(xy 291.530786 -197.075298) (xy 293.029386 -197.075298) (xy 293.029386 -197.595236) (xy 291.530786 -197.595236)
			)
		)
	)
	(zone
		(layer "In2.Cu")
		(hatch none 0.5)
		(connect_pads
			(clearance 0)
		)
		(min_thickness 0.25)
		(keepout
			(tracks not_allowed)
			(vias allowed)
			(pads allowed)
			(copperpour not_allowed)
			(footprints allowed)
		)
		(placement
			(enabled no)
			(sheetname "")
		)
		(fill
			(thermal_gap 0.5)
			(thermal_bridge_width 0.5)
			(island_removal_mode 0)
		)
		(polygon
			(pts
				(xy 441.7949 -220.875098) (xy 443.2935 -220.875098) (xy 443.2935 -221.395036) (xy 441.7949 -221.395036)
			)
		)
	)
	(zone
		(layer "In2.Cu")
		(hatch none 0.5)
		(connect_pads
			(clearance 0)
		)
		(min_thickness 0.25)
		(keepout
			(tracks not_allowed)
			(vias allowed)
			(pads allowed)
			(copperpour not_allowed)
			(footprints allowed)
		)
		(placement
			(enabled no)
			(sheetname "")
		)
		(fill
			(thermal_gap 0.5)
			(thermal_bridge_width 0.5)
			(island_removal_mode 0)
		)
		(polygon
			(pts
				(xy 197.954646 -225.12528) (xy 199.453246 -225.12528) (xy 199.453246 -225.645218) (xy 197.954646 -225.645218)
			)
		)
	)
	(zone
		(layer "In2.Cu")
		(hatch none 0.5)
		(connect_pads
			(clearance 0)
		)
		(min_thickness 0.25)
		(keepout
			(tracks not_allowed)
			(vias allowed)
			(pads allowed)
			(copperpour not_allowed)
			(footprints allowed)
		)
		(placement
			(enabled no)
			(sheetname "")
		)
		(fill
			(thermal_gap 0.5)
			(thermal_bridge_width 0.5)
			(island_removal_mode 0)
		)
		(polygon
			(pts
				(xy 268.898878 -299.925232) (xy 270.397478 -299.925232) (xy 270.397478 -300.44517) (xy 268.898878 -300.44517)
			)
		)
	)
	(zone
		(layer "In2.Cu")
		(hatch none 0.5)
		(connect_pads
			(clearance 0)
		)
		(min_thickness 0.25)
		(keepout
			(tracks not_allowed)
			(vias allowed)
			(pads allowed)
			(copperpour not_allowed)
			(footprints allowed)
		)
		(placement
			(enabled no)
			(sheetname "")
		)
		(fill
			(thermal_gap 0.5)
			(thermal_bridge_width 0.5)
			(island_removal_mode 0)
		)
		(polygon
			(pts
				(xy 268.898878 -209.825336) (xy 270.397478 -209.825336) (xy 270.397478 -210.345274) (xy 268.898878 -210.345274)
			)
		)
	)
	(zone
		(layer "In2.Cu")
		(hatch none 0.5)
		(connect_pads
			(clearance 0)
		)
		(min_thickness 0.25)
		(keepout
			(tracks not_allowed)
			(vias allowed)
			(pads allowed)
			(copperpour not_allowed)
			(footprints allowed)
		)
		(placement
			(enabled no)
			(sheetname "")
		)
		(fill
			(thermal_gap 0.5)
			(thermal_bridge_width 0.5)
			(island_removal_mode 0)
		)
		(polygon
			(pts
				(xy 197.954646 -315.225176) (xy 199.453246 -315.225176) (xy 199.453246 -315.745114) (xy 197.954646 -315.745114)
			)
		)
	)
	(zone
		(layer "In2.Cu")
		(hatch none 0.5)
		(connect_pads
			(clearance 0)
		)
		(min_thickness 0.25)
		(keepout
			(tracks not_allowed)
			(vias allowed)
			(pads allowed)
			(copperpour not_allowed)
			(footprints allowed)
		)
		(placement
			(enabled no)
			(sheetname "")
		)
		(fill
			(thermal_gap 0.5)
			(thermal_bridge_width 0.5)
			(island_removal_mode 0)
		)
		(polygon
			(pts
				(xy 438.350914 -225.12528) (xy 439.849514 -225.12528) (xy 439.849514 -225.645218) (xy 438.350914 -225.645218)
			)
		)
	)
	(zone
		(layer "In2.Cu")
		(hatch none 0.5)
		(connect_pads
			(clearance 0)
		)
		(min_thickness 0.25)
		(keepout
			(tracks not_allowed)
			(vias allowed)
			(pads allowed)
			(copperpour not_allowed)
			(footprints allowed)
		)
		(placement
			(enabled no)
			(sheetname "")
		)
		(fill
			(thermal_gap 0.5)
			(thermal_bridge_width 0.5)
			(island_removal_mode 0)
		)
		(polygon
			(pts
				(xy 302.518826 -229.375208) (xy 304.017426 -229.375208) (xy 304.017426 -229.895146) (xy 302.518826 -229.895146)
			)
		)
	)
	(zone
		(layer "In2.Cu")
		(hatch none 0.5)
		(connect_pads
			(clearance 0)
		)
		(min_thickness 0.25)
		(keepout
			(tracks not_allowed)
			(vias allowed)
			(pads allowed)
			(copperpour not_allowed)
			(footprints allowed)
		)
		(placement
			(enabled no)
			(sheetname "")
		)
		(fill
			(thermal_gap 0.5)
			(thermal_bridge_width 0.5)
			(island_removal_mode 0)
		)
		(polygon
			(pts
				(xy 47.034704 -293.125144) (xy 48.533304 -293.125144) (xy 48.533304 -293.645082) (xy 47.034704 -293.645082)
			)
		)
	)
	(zone
		(layer "In2.Cu")
		(hatch none 0.5)
		(connect_pads
			(clearance 0)
		)
		(min_thickness 0.25)
		(keepout
			(tracks not_allowed)
			(vias allowed)
			(pads allowed)
			(copperpour not_allowed)
			(footprints allowed)
		)
		(placement
			(enabled no)
			(sheetname "")
		)
		(fill
			(thermal_gap 0.5)
			(thermal_bridge_width 0.5)
			(island_removal_mode 0)
		)
		(polygon
			(pts
				(xy 186.310778 -311.825132) (xy 187.809378 -311.825132) (xy 187.809378 -312.34507) (xy 186.310778 -312.34507)
			)
		)
	)
	(zone
		(layer "In2.Cu")
		(hatch none 0.5)
		(connect_pads
			(clearance 0)
		)
		(min_thickness 0.25)
		(keepout
			(tracks not_allowed)
			(vias allowed)
			(pads allowed)
			(copperpour not_allowed)
			(footprints allowed)
		)
		(placement
			(enabled no)
			(sheetname "")
		)
		(fill
			(thermal_gap 0.5)
			(thermal_bridge_width 0.5)
			(island_removal_mode 0)
		)
		(polygon
			(pts
				(xy 186.310778 -210.67522) (xy 187.809378 -210.67522) (xy 187.809378 -211.195158) (xy 186.310778 -211.195158)
			)
		)
	)
	(zone
		(layer "In2.Cu")
		(hatch none 0.5)
		(connect_pads
			(clearance 0)
		)
		(min_thickness 0.25)
		(keepout
			(tracks not_allowed)
			(vias allowed)
			(pads allowed)
			(copperpour not_allowed)
			(footprints allowed)
		)
		(placement
			(enabled no)
			(sheetname "")
		)
		(fill
			(thermal_gap 0.5)
			(thermal_bridge_width 0.5)
			(island_removal_mode 0)
		)
		(polygon
			(pts
				(xy 449.3387 -218.325192) (xy 450.8373 -218.325192) (xy 450.8373 -218.84513) (xy 449.3387 -218.84513)
			)
		)
	)
	(zone
		(layer "In2.Cu")
		(hatch none 0.5)
		(connect_pads
			(clearance 0)
		)
		(min_thickness 0.25)
		(keepout
			(tracks allowed)
			(vias allowed)
			(pads allowed)
			(copperpour allowed)
			(footprints allowed)
		)
		(placement
			(enabled no)
			(sheetname "")
		)
		(fill
			(thermal_gap 0.5)
			(thermal_bridge_width 0.5)
			(island_removal_mode 0)
		)
		(polygon
			(pts
				(xy 98.46945 -339.310218) (xy 98.46945 -338.687918) (xy 99.02063 -338.687918) (xy 99.02063 -339.310218)
			)
		)
	)
	(zone
		(layer "In2.Cu")
		(hatch none 0.5)
		(connect_pads
			(clearance 0)
		)
		(min_thickness 0.25)
		(keepout
			(tracks not_allowed)
			(vias allowed)
			(pads allowed)
			(copperpour not_allowed)
			(footprints allowed)
		)
		(placement
			(enabled no)
			(sheetname "")
		)
		(fill
			(thermal_gap 0.5)
			(thermal_bridge_width 0.5)
			(island_removal_mode 0)
		)
		(polygon
			(pts
				(xy 291.530786 -225.12528) (xy 293.029386 -225.12528) (xy 293.029386 -225.645218) (xy 291.530786 -225.645218)
			)
		)
	)
	(zone
		(layer "In2.Cu")
		(hatch none 0.5)
		(connect_pads
			(clearance 0)
		)
		(min_thickness 0.25)
		(keepout
			(tracks not_allowed)
			(vias allowed)
			(pads allowed)
			(copperpour not_allowed)
			(footprints allowed)
		)
		(placement
			(enabled no)
			(sheetname "")
		)
		(fill
			(thermal_gap 0.5)
			(thermal_bridge_width 0.5)
			(island_removal_mode 0)
		)
		(polygon
			(pts
				(xy 36.046664 -237.875318) (xy 37.545264 -237.875318) (xy 37.545264 -238.395256) (xy 36.046664 -238.395256)
			)
		)
	)
	(zone
		(layer "In2.Cu")
		(hatch none 0.5)
		(connect_pads
			(clearance 0)
		)
		(min_thickness 0.25)
		(keepout
			(tracks not_allowed)
			(vias allowed)
			(pads allowed)
			(copperpour not_allowed)
			(footprints allowed)
		)
		(placement
			(enabled no)
			(sheetname "")
		)
		(fill
			(thermal_gap 0.5)
			(thermal_bridge_width 0.5)
			(island_removal_mode 0)
		)
		(polygon
			(pts
				(xy 426.706792 -265.075162) (xy 428.205392 -265.075162) (xy 428.205392 -265.5951) (xy 426.706792 -265.5951)
			)
		)
	)
	(zone
		(layer "In2.Cu")
		(hatch none 0.5)
		(connect_pads
			(clearance 0)
		)
		(min_thickness 0.25)
		(keepout
			(tracks not_allowed)
			(vias allowed)
			(pads allowed)
			(copperpour not_allowed)
			(footprints allowed)
		)
		(placement
			(enabled no)
			(sheetname "")
		)
		(fill
			(thermal_gap 0.5)
			(thermal_bridge_width 0.5)
			(island_removal_mode 0)
		)
		(polygon
			(pts
				(xy 36.046664 -285.475172) (xy 37.545264 -285.475172) (xy 37.545264 -285.99511) (xy 36.046664 -285.99511)
			)
		)
	)
	(zone
		(layer "In2.Cu")
		(hatch none 0.5)
		(connect_pads
			(clearance 0)
		)
		(min_thickness 0.25)
		(keepout
			(tracks not_allowed)
			(vias allowed)
			(pads allowed)
			(copperpour not_allowed)
			(footprints allowed)
		)
		(placement
			(enabled no)
			(sheetname "")
		)
		(fill
			(thermal_gap 0.5)
			(thermal_bridge_width 0.5)
			(island_removal_mode 0)
		)
		(polygon
			(pts
				(xy 197.954646 -262.525256) (xy 199.453246 -262.525256) (xy 199.453246 -263.045194) (xy 197.954646 -263.045194)
			)
		)
	)
	(zone
		(layer "In2.Cu")
		(hatch none 0.5)
		(connect_pads
			(clearance 0)
		)
		(min_thickness 0.25)
		(keepout
			(tracks not_allowed)
			(vias allowed)
			(pads allowed)
			(copperpour not_allowed)
			(footprints allowed)
		)
		(placement
			(enabled no)
			(sheetname "")
		)
		(fill
			(thermal_gap 0.5)
			(thermal_bridge_width 0.5)
			(island_removal_mode 0)
		)
		(polygon
			(pts
				(xy 306.618894 -236.175296) (xy 308.117494 -236.175296) (xy 308.117494 -236.695234) (xy 306.618894 -236.695234)
			)
		)
	)
	(zone
		(layer "In2.Cu")
		(hatch none 0.5)
		(connect_pads
			(clearance 0)
		)
		(min_thickness 0.25)
		(keepout
			(tracks not_allowed)
			(vias allowed)
			(pads allowed)
			(copperpour not_allowed)
			(footprints allowed)
		)
		(placement
			(enabled no)
			(sheetname "")
		)
		(fill
			(thermal_gap 0.5)
			(thermal_bridge_width 0.5)
			(island_removal_mode 0)
		)
		(polygon
			(pts
				(xy 58.678826 -204.72527) (xy 60.177426 -204.72527) (xy 60.177426 -205.245208) (xy 58.678826 -205.245208)
			)
		)
	)
	(zone
		(layer "In2.Cu")
		(hatch none 0.5)
		(connect_pads
			(clearance 0)
		)
		(min_thickness 0.25)
		(keepout
			(tracks not_allowed)
			(vias allowed)
			(pads allowed)
			(copperpour not_allowed)
			(footprints allowed)
		)
		(placement
			(enabled no)
			(sheetname "")
		)
		(fill
			(thermal_gap 0.5)
			(thermal_bridge_width 0.5)
			(island_removal_mode 0)
		)
		(polygon
			(pts
				(xy 167.778684 -284.625288) (xy 169.277284 -284.625288) (xy 169.277284 -285.145226) (xy 167.778684 -285.145226)
			)
		)
	)
	(zone
		(layer "In2.Cu")
		(hatch none 0.5)
		(connect_pads
			(clearance 0)
		)
		(min_thickness 0.25)
		(keepout
			(tracks not_allowed)
			(vias allowed)
			(pads allowed)
			(copperpour not_allowed)
			(footprints allowed)
		)
		(placement
			(enabled no)
			(sheetname "")
		)
		(fill
			(thermal_gap 0.5)
			(thermal_bridge_width 0.5)
			(island_removal_mode 0)
		)
		(polygon
			(pts
				(xy 16.858742 -249.775218) (xy 18.357342 -249.775218) (xy 18.357342 -250.295156) (xy 16.858742 -250.295156)
			)
		)
	)
	(zone
		(layer "In2.Cu")
		(hatch none 0.5)
		(connect_pads
			(clearance 0)
		)
		(min_thickness 0.25)
		(keepout
			(tracks not_allowed)
			(vias allowed)
			(pads allowed)
			(copperpour not_allowed)
			(footprints allowed)
		)
		(placement
			(enabled no)
			(sheetname "")
		)
		(fill
			(thermal_gap 0.5)
			(thermal_bridge_width 0.5)
			(island_removal_mode 0)
		)
		(polygon
			(pts
				(xy 283.986732 -215.775286) (xy 285.485332 -215.775286) (xy 285.485332 -216.295224) (xy 283.986732 -216.295224)
			)
		)
	)
	(zone
		(layer "In2.Cu")
		(hatch none 0.5)
		(connect_pads
			(clearance 0)
		)
		(min_thickness 0.25)
		(keepout
			(tracks not_allowed)
			(vias allowed)
			(pads allowed)
			(copperpour not_allowed)
			(footprints allowed)
		)
		(placement
			(enabled no)
			(sheetname "")
		)
		(fill
			(thermal_gap 0.5)
			(thermal_bridge_width 0.5)
			(island_removal_mode 0)
		)
		(polygon
			(pts
				(xy 268.898878 -288.875216) (xy 270.397478 -288.875216) (xy 270.397478 -289.395154) (xy 268.898878 -289.395154)
			)
		)
	)
	(zone
		(layer "In2.Cu")
		(hatch none 0.5)
		(connect_pads
			(clearance 0)
		)
		(min_thickness 0.25)
		(keepout
			(tracks not_allowed)
			(vias allowed)
			(pads allowed)
			(copperpour not_allowed)
			(footprints allowed)
		)
		(placement
			(enabled no)
			(sheetname "")
		)
		(fill
			(thermal_gap 0.5)
			(thermal_bridge_width 0.5)
			(island_removal_mode 0)
		)
		(polygon
			(pts
				(xy 197.954646 -210.67522) (xy 199.453246 -210.67522) (xy 199.453246 -211.195158) (xy 197.954646 -211.195158)
			)
		)
	)
	(zone
		(layer "In2.Cu")
		(hatch none 0.5)
		(connect_pads
			(clearance 0)
		)
		(min_thickness 0.25)
		(keepout
			(tracks not_allowed)
			(vias allowed)
			(pads allowed)
			(copperpour not_allowed)
			(footprints allowed)
		)
		(placement
			(enabled no)
			(sheetname "")
		)
		(fill
			(thermal_gap 0.5)
			(thermal_bridge_width 0.5)
			(island_removal_mode 0)
		)
		(polygon
			(pts
				(xy 167.778684 -265.9253) (xy 169.277284 -265.9253) (xy 169.277284 -266.445238) (xy 167.778684 -266.445238)
			)
		)
	)
	(zone
		(layer "In2.Cu")
		(hatch none 0.5)
		(connect_pads
			(clearance 0)
		)
		(min_thickness 0.25)
		(keepout
			(tracks not_allowed)
			(vias allowed)
			(pads allowed)
			(copperpour not_allowed)
			(footprints allowed)
		)
		(placement
			(enabled no)
			(sheetname "")
		)
		(fill
			(thermal_gap 0.5)
			(thermal_bridge_width 0.5)
			(island_removal_mode 0)
		)
		(polygon
			(pts
				(xy 242.628928 -313.952636) (xy 242.628928 -313.252612) (xy 245.052342 -313.252612) (xy 245.052342 -313.952636)
			)
		)
	)
	(zone
		(layer "In2.Cu")
		(hatch none 0.5)
		(connect_pads
			(clearance 0)
		)
		(min_thickness 0.25)
		(keepout
			(tracks not_allowed)
			(vias allowed)
			(pads allowed)
			(copperpour not_allowed)
			(footprints allowed)
		)
		(placement
			(enabled no)
			(sheetname "")
		)
		(fill
			(thermal_gap 0.5)
			(thermal_bridge_width 0.5)
			(island_removal_mode 0)
		)
		(polygon
			(pts
				(xy 445.894968 -200.475342) (xy 447.393568 -200.475342) (xy 447.393568 -200.99528) (xy 445.894968 -200.99528)
			)
		)
	)
	(zone
		(layer "In2.Cu")
		(hatch none 0.5)
		(connect_pads
			(clearance 0)
		)
		(min_thickness 0.25)
		(keepout
			(tracks not_allowed)
			(vias allowed)
			(pads allowed)
			(copperpour not_allowed)
			(footprints allowed)
		)
		(placement
			(enabled no)
			(sheetname "")
		)
		(fill
			(thermal_gap 0.5)
			(thermal_bridge_width 0.5)
			(island_removal_mode 0)
		)
		(polygon
			(pts
				(xy 287.430718 -216.62517) (xy 288.929318 -216.62517) (xy 288.929318 -217.145108) (xy 287.430718 -217.145108)
			)
		)
	)
	(zone
		(layer "In2.Cu")
		(hatch none 0.5)
		(connect_pads
			(clearance 0)
		)
		(min_thickness 0.25)
		(keepout
			(tracks not_allowed)
			(vias allowed)
			(pads allowed)
			(copperpour not_allowed)
			(footprints allowed)
		)
		(placement
			(enabled no)
			(sheetname "")
		)
		(fill
			(thermal_gap 0.5)
			(thermal_bridge_width 0.5)
			(island_removal_mode 0)
		)
		(polygon
			(pts
				(xy 434.250846 -235.325158) (xy 435.749446 -235.325158) (xy 435.749446 -235.845096) (xy 434.250846 -235.845096)
			)
		)
	)
	(zone
		(layer "In2.Cu")
		(hatch none 0.5)
		(connect_pads
			(clearance 0)
		)
		(min_thickness 0.25)
		(keepout
			(tracks not_allowed)
			(vias allowed)
			(pads allowed)
			(copperpour not_allowed)
			(footprints allowed)
		)
		(placement
			(enabled no)
			(sheetname "")
		)
		(fill
			(thermal_gap 0.5)
			(thermal_bridge_width 0.5)
			(island_removal_mode 0)
		)
		(polygon
			(pts
				(arc
					(start 334.012794 -379.360684)
					(mid 334.032718 -379.36992)
					(end 334.05445 -379.37313)
				)
				(arc
					(start 334.249014 -379.37313)
					(mid 334.302896 -379.350812)
					(end 334.325214 -379.29693)
				)
				(arc
					(start 334.325214 -378.61113)
					(mid 334.302896 -378.557248)
					(end 334.249014 -378.53493)
				)
				(arc
					(start 334.05445 -378.53493)
					(mid 334.032706 -378.538098)
					(end 334.012794 -378.547376)
				)
				(arc
					(start 333.71663 -378.740162)
					(mid 333.674946 -378.752384)
					(end 333.633318 -378.739908)
				)
				(arc
					(start 333.339694 -378.547376)
					(mid 333.31977 -378.53814)
					(end 333.298038 -378.53493)
				)
				(arc
					(start 333.103474 -378.53493)
					(mid 333.049592 -378.557248)
					(end 333.027274 -378.61113)
				)
				(arc
					(start 333.027274 -379.29693)
					(mid 333.049592 -379.350812)
					(end 333.103474 -379.37313)
				)
				(arc
					(start 333.299308 -379.37313)
					(mid 333.321052 -379.369962)
					(end 333.340964 -379.360684)
				)
				(arc
					(start 333.634588 -379.168152)
					(mid 333.676244 -379.15575)
					(end 333.7179 -379.168152)
				)
			)
		)
	)
	(zone
		(layer "In2.Cu")
		(hatch none 0.5)
		(connect_pads
			(clearance 0)
		)
		(min_thickness 0.25)
		(keepout
			(tracks not_allowed)
			(vias allowed)
			(pads allowed)
			(copperpour not_allowed)
			(footprints allowed)
		)
		(placement
			(enabled no)
			(sheetname "")
		)
		(fill
			(thermal_gap 0.5)
			(thermal_bridge_width 0.5)
			(island_removal_mode 0)
		)
		(polygon
			(pts
				(xy 54.578758 -265.075162) (xy 56.077358 -265.075162) (xy 56.077358 -265.5951) (xy 54.578758 -265.5951)
			)
		)
	)
	(zone
		(layer "In2.Cu")
		(hatch none 0.5)
		(connect_pads
			(clearance 0)
		)
		(min_thickness 0.25)
		(keepout
			(tracks not_allowed)
			(vias allowed)
			(pads allowed)
			(copperpour not_allowed)
			(footprints allowed)
		)
		(placement
			(enabled no)
			(sheetname "")
		)
		(fill
			(thermal_gap 0.5)
			(thermal_bridge_width 0.5)
			(island_removal_mode 0)
		)
		(polygon
			(pts
				(xy 279.886664 -225.975164) (xy 281.385264 -225.975164) (xy 281.385264 -226.495102) (xy 279.886664 -226.495102)
			)
		)
	)
	(zone
		(layer "In2.Cu")
		(hatch none 0.5)
		(connect_pads
			(clearance 0)
		)
		(min_thickness 0.25)
		(keepout
			(tracks not_allowed)
			(vias allowed)
			(pads allowed)
			(copperpour not_allowed)
			(footprints allowed)
		)
		(placement
			(enabled no)
			(sheetname "")
		)
		(fill
			(thermal_gap 0.5)
			(thermal_bridge_width 0.5)
			(island_removal_mode 0)
		)
		(polygon
			(pts
				(xy 419.162738 -201.325226) (xy 420.661338 -201.325226) (xy 420.661338 -201.845164) (xy 419.162738 -201.845164)
			)
		)
	)
	(zone
		(layer "In2.Cu")
		(hatch none 0.5)
		(connect_pads
			(clearance 0)
		)
		(min_thickness 0.25)
		(keepout
			(tracks not_allowed)
			(vias allowed)
			(pads allowed)
			(copperpour not_allowed)
			(footprints allowed)
		)
		(placement
			(enabled no)
			(sheetname "")
		)
		(fill
			(thermal_gap 0.5)
			(thermal_bridge_width 0.5)
			(island_removal_mode 0)
		)
		(polygon
			(pts
				(xy 438.350914 -250.625102) (xy 439.849514 -250.625102) (xy 439.849514 -251.14504) (xy 438.350914 -251.14504)
			)
		)
	)
	(zone
		(layer "In2.Cu")
		(hatch none 0.5)
		(connect_pads
			(clearance 0)
		)
		(min_thickness 0.25)
		(keepout
			(tracks not_allowed)
			(vias allowed)
			(pads allowed)
			(copperpour not_allowed)
			(footprints allowed)
		)
		(placement
			(enabled no)
			(sheetname "")
		)
		(fill
			(thermal_gap 0.5)
			(thermal_bridge_width 0.5)
			(island_removal_mode 0)
		)
		(polygon
			(pts
				(xy 201.398632 -214.925148) (xy 202.897232 -214.925148) (xy 202.897232 -215.445086) (xy 201.398632 -215.445086)
			)
		)
	)
	(zone
		(layer "In2.Cu")
		(hatch none 0.5)
		(connect_pads
			(clearance 0)
		)
		(min_thickness 0.25)
		(keepout
			(tracks not_allowed)
			(vias allowed)
			(pads allowed)
			(copperpour not_allowed)
			(footprints allowed)
		)
		(placement
			(enabled no)
			(sheetname "")
		)
		(fill
			(thermal_gap 0.5)
			(thermal_bridge_width 0.5)
			(island_removal_mode 0)
		)
		(polygon
			(pts
				(xy 36.046664 -277.8252) (xy 37.545264 -277.8252) (xy 37.545264 -278.345138) (xy 36.046664 -278.345138)
			)
		)
	)
	(zone
		(layer "In2.Cu")
		(hatch none 0.5)
		(connect_pads
			(clearance 0)
		)
		(min_thickness 0.25)
		(keepout
			(tracks not_allowed)
			(vias allowed)
			(pads allowed)
			(copperpour not_allowed)
			(footprints allowed)
		)
		(placement
			(enabled no)
			(sheetname "")
		)
		(fill
			(thermal_gap 0.5)
			(thermal_bridge_width 0.5)
			(island_removal_mode 0)
		)
		(polygon
			(pts
				(xy 441.7949 -249.775218) (xy 443.2935 -249.775218) (xy 443.2935 -250.295156) (xy 441.7949 -250.295156)
			)
		)
	)
	(zone
		(layer "In2.Cu")
		(hatch none 0.5)
		(connect_pads
			(clearance 0)
		)
		(min_thickness 0.25)
		(keepout
			(tracks not_allowed)
			(vias allowed)
			(pads allowed)
			(copperpour not_allowed)
			(footprints allowed)
		)
		(placement
			(enabled no)
			(sheetname "")
		)
		(fill
			(thermal_gap 0.5)
			(thermal_bridge_width 0.5)
			(island_removal_mode 0)
		)
		(polygon
			(pts
				(xy 449.3387 -216.62517) (xy 450.8373 -216.62517) (xy 450.8373 -217.145108) (xy 449.3387 -217.145108)
			)
		)
	)
	(zone
		(layer "In2.Cu")
		(hatch none 0.5)
		(connect_pads
			(clearance 0)
		)
		(min_thickness 0.25)
		(keepout
			(tracks allowed)
			(vias allowed)
			(pads allowed)
			(copperpour allowed)
			(footprints allowed)
		)
		(placement
			(enabled no)
			(sheetname "")
		)
		(fill
			(thermal_gap 0.5)
			(thermal_bridge_width 0.5)
			(island_removal_mode 0)
		)
		(polygon
			(pts
				(xy 84.119212 -338.200492) (xy 84.119212 -337.578192) (xy 84.670392 -337.578192) (xy 84.670392 -338.200492)
			)
		)
	)
	(zone
		(layer "In2.Cu")
		(hatch none 0.5)
		(connect_pads
			(clearance 0)
		)
		(min_thickness 0.25)
		(keepout
			(tracks not_allowed)
			(vias allowed)
			(pads allowed)
			(copperpour not_allowed)
			(footprints allowed)
		)
		(placement
			(enabled no)
			(sheetname "")
		)
		(fill
			(thermal_gap 0.5)
			(thermal_bridge_width 0.5)
			(island_removal_mode 0)
		)
		(polygon
			(pts
				(xy 190.410846 -288.875216) (xy 191.909446 -288.875216) (xy 191.909446 -289.395154) (xy 190.410846 -289.395154)
			)
		)
	)
	(zone
		(layer "In2.Cu")
		(hatch none 0.5)
		(connect_pads
			(clearance 0)
		)
		(min_thickness 0.25)
		(keepout
			(tracks not_allowed)
			(vias allowed)
			(pads allowed)
			(copperpour not_allowed)
			(footprints allowed)
		)
		(placement
			(enabled no)
			(sheetname "")
		)
		(fill
			(thermal_gap 0.5)
			(thermal_bridge_width 0.5)
			(island_removal_mode 0)
		)
		(polygon
			(pts
				(xy 268.898878 -279.525222) (xy 270.397478 -279.525222) (xy 270.397478 -280.04516) (xy 268.898878 -280.04516)
			)
		)
	)
	(zone
		(layer "In2.Cu")
		(hatch none 0.5)
		(connect_pads
			(clearance 0)
		)
		(min_thickness 0.25)
		(keepout
			(tracks not_allowed)
			(vias allowed)
			(pads allowed)
			(copperpour not_allowed)
			(footprints allowed)
		)
		(placement
			(enabled no)
			(sheetname "")
		)
		(fill
			(thermal_gap 0.5)
			(thermal_bridge_width 0.5)
			(island_removal_mode 0)
		)
		(polygon
			(pts
				(xy 423.262806 -269.325344) (xy 424.761406 -269.325344) (xy 424.761406 -269.845282) (xy 423.262806 -269.845282)
			)
		)
	)
	(zone
		(layer "In2.Cu")
		(hatch none 0.5)
		(connect_pads
			(clearance 0)
		)
		(min_thickness 0.25)
		(keepout
			(tracks not_allowed)
			(vias allowed)
			(pads allowed)
			(copperpour not_allowed)
			(footprints allowed)
		)
		(placement
			(enabled no)
			(sheetname "")
		)
		(fill
			(thermal_gap 0.5)
			(thermal_bridge_width 0.5)
			(island_removal_mode 0)
		)
		(polygon
			(pts
				(xy 47.034704 -248.075196) (xy 48.533304 -248.075196) (xy 48.533304 -248.595134) (xy 47.034704 -248.595134)
			)
		)
	)
	(zone
		(layer "In2.Cu")
		(hatch none 0.5)
		(connect_pads
			(clearance 0)
		)
		(min_thickness 0.25)
		(keepout
			(tracks not_allowed)
			(vias allowed)
			(pads allowed)
			(copperpour not_allowed)
			(footprints allowed)
		)
		(placement
			(enabled no)
			(sheetname "")
		)
		(fill
			(thermal_gap 0.5)
			(thermal_bridge_width 0.5)
			(island_removal_mode 0)
		)
		(polygon
			(pts
				(xy 291.530786 -310.975248) (xy 293.029386 -310.975248) (xy 293.029386 -311.495186) (xy 291.530786 -311.495186)
			)
		)
	)
	(zone
		(layer "In2.Cu")
		(hatch none 0.5)
		(connect_pads
			(clearance 0)
		)
		(min_thickness 0.25)
		(keepout
			(tracks not_allowed)
			(vias allowed)
			(pads allowed)
			(copperpour not_allowed)
			(footprints allowed)
		)
		(placement
			(enabled no)
			(sheetname "")
		)
		(fill
			(thermal_gap 0.5)
			(thermal_bridge_width 0.5)
			(island_removal_mode 0)
		)
		(polygon
			(pts
				(xy 58.678826 -296.525188) (xy 60.177426 -296.525188) (xy 60.177426 -297.045126) (xy 58.678826 -297.045126)
			)
		)
	)
	(zone
		(layer "In2.Cu")
		(hatch none 0.5)
		(connect_pads
			(clearance 0)
		)
		(min_thickness 0.25)
		(keepout
			(tracks not_allowed)
			(vias allowed)
			(pads allowed)
			(copperpour not_allowed)
			(footprints allowed)
		)
		(placement
			(enabled no)
			(sheetname "")
		)
		(fill
			(thermal_gap 0.5)
			(thermal_bridge_width 0.5)
			(island_removal_mode 0)
		)
		(polygon
			(pts
				(xy 445.894968 -248.925334) (xy 447.393568 -248.925334) (xy 447.393568 -249.445272) (xy 445.894968 -249.445272)
			)
		)
	)
	(zone
		(layer "In2.Cu")
		(hatch none 0.5)
		(connect_pads
			(clearance 0)
		)
		(min_thickness 0.25)
		(keepout
			(tracks not_allowed)
			(vias allowed)
			(pads allowed)
			(copperpour not_allowed)
			(footprints allowed)
		)
		(placement
			(enabled no)
			(sheetname "")
		)
		(fill
			(thermal_gap 0.5)
			(thermal_bridge_width 0.5)
			(island_removal_mode 0)
		)
		(polygon
			(pts
				(xy 24.402542 -248.075196) (xy 25.901142 -248.075196) (xy 25.901142 -248.595134) (xy 24.402542 -248.595134)
			)
		)
	)
	(zone
		(layer "In2.Cu")
		(hatch none 0.5)
		(connect_pads
			(clearance 0)
		)
		(min_thickness 0.25)
		(keepout
			(tracks not_allowed)
			(vias allowed)
			(pads allowed)
			(copperpour not_allowed)
			(footprints allowed)
		)
		(placement
			(enabled no)
			(sheetname "")
		)
		(fill
			(thermal_gap 0.5)
			(thermal_bridge_width 0.5)
			(island_removal_mode 0)
		)
		(polygon
			(pts
				(xy 276.442932 -248.925334) (xy 277.941532 -248.925334) (xy 277.941532 -249.445272) (xy 276.442932 -249.445272)
			)
		)
	)
	(zone
		(layer "In2.Cu")
		(hatch none 0.5)
		(connect_pads
			(clearance 0)
		)
		(min_thickness 0.25)
		(keepout
			(tracks not_allowed)
			(vias allowed)
			(pads allowed)
			(copperpour not_allowed)
			(footprints allowed)
		)
		(placement
			(enabled no)
			(sheetname "")
		)
		(fill
			(thermal_gap 0.5)
			(thermal_bridge_width 0.5)
			(island_removal_mode 0)
		)
		(polygon
			(pts
				(xy 283.986732 -240.425224) (xy 285.485332 -240.425224) (xy 285.485332 -240.945162) (xy 283.986732 -240.945162)
			)
		)
	)
	(zone
		(layer "In2.Cu")
		(hatch none 0.5)
		(connect_pads
			(clearance 0)
		)
		(min_thickness 0.25)
		(keepout
			(tracks not_allowed)
			(vias allowed)
			(pads allowed)
			(copperpour not_allowed)
			(footprints allowed)
		)
		(placement
			(enabled no)
			(sheetname "")
		)
		(fill
			(thermal_gap 0.5)
			(thermal_bridge_width 0.5)
			(island_removal_mode 0)
		)
		(polygon
			(pts
				(xy 31.946596 -265.075162) (xy 33.445196 -265.075162) (xy 33.445196 -265.5951) (xy 31.946596 -265.5951)
			)
		)
	)
	(zone
		(layer "In2.Cu")
		(hatch none 0.5)
		(connect_pads
			(clearance 0)
		)
		(min_thickness 0.25)
		(keepout
			(tracks not_allowed)
			(vias allowed)
			(pads allowed)
			(copperpour not_allowed)
			(footprints allowed)
		)
		(placement
			(enabled no)
			(sheetname "")
		)
		(fill
			(thermal_gap 0.5)
			(thermal_bridge_width 0.5)
			(island_removal_mode 0)
		)
		(polygon
			(pts
				(xy 129.504694 -34.784538) (xy 129.504694 -35.362388) (xy 128.183894 -35.362388) (xy 128.183894 -34.784538)
			)
		)
	)
	(zone
		(layer "In2.Cu")
		(hatch none 0.5)
		(connect_pads
			(clearance 0)
		)
		(min_thickness 0.25)
		(keepout
			(tracks not_allowed)
			(vias allowed)
			(pads allowed)
			(copperpour not_allowed)
			(footprints allowed)
		)
		(placement
			(enabled no)
			(sheetname "")
		)
		(fill
			(thermal_gap 0.5)
			(thermal_bridge_width 0.5)
			(island_removal_mode 0)
		)
		(polygon
			(pts
				(xy 268.898878 -220.025214) (xy 270.397478 -220.025214) (xy 270.397478 -220.545152) (xy 268.898878 -220.545152)
			)
		)
	)
	(zone
		(layer "In2.Cu")
		(hatch none 0.5)
		(connect_pads
			(clearance 0)
		)
		(min_thickness 0.25)
		(keepout
			(tracks not_allowed)
			(vias allowed)
			(pads allowed)
			(copperpour not_allowed)
			(footprints allowed)
		)
		(placement
			(enabled no)
			(sheetname "")
		)
		(fill
			(thermal_gap 0.5)
			(thermal_bridge_width 0.5)
			(island_removal_mode 0)
		)
		(polygon
			(pts
				(xy 276.442932 -201.325226) (xy 277.941532 -201.325226) (xy 277.941532 -201.845164) (xy 276.442932 -201.845164)
			)
		)
	)
	(zone
		(layer "In2.Cu")
		(hatch none 0.5)
		(connect_pads
			(clearance 0)
		)
		(min_thickness 0.25)
		(keepout
			(tracks not_allowed)
			(vias allowed)
			(pads allowed)
			(copperpour not_allowed)
			(footprints allowed)
		)
		(placement
			(enabled no)
			(sheetname "")
		)
		(fill
			(thermal_gap 0.5)
			(thermal_bridge_width 0.5)
			(island_removal_mode 0)
		)
		(polygon
			(pts
				(xy 20.95881 -296.525188) (xy 22.45741 -296.525188) (xy 22.45741 -297.045126) (xy 20.95881 -297.045126)
			)
		)
	)
	(zone
		(layer "In2.Cu")
		(hatch none 0.5)
		(connect_pads
			(clearance 0)
		)
		(min_thickness 0.25)
		(keepout
			(tracks not_allowed)
			(vias allowed)
			(pads allowed)
			(copperpour not_allowed)
			(footprints allowed)
		)
		(placement
			(enabled no)
			(sheetname "")
		)
		(fill
			(thermal_gap 0.5)
			(thermal_bridge_width 0.5)
			(island_removal_mode 0)
		)
		(polygon
			(pts
				(xy 186.310778 -220.025214) (xy 187.809378 -220.025214) (xy 187.809378 -220.545152) (xy 186.310778 -220.545152)
			)
		)
	)
	(zone
		(layer "In2.Cu")
		(hatch none 0.5)
		(connect_pads
			(clearance 0)
		)
		(min_thickness 0.25)
		(keepout
			(tracks not_allowed)
			(vias allowed)
			(pads allowed)
			(copperpour not_allowed)
			(footprints allowed)
		)
		(placement
			(enabled no)
			(sheetname "")
		)
		(fill
			(thermal_gap 0.5)
			(thermal_bridge_width 0.5)
			(island_removal_mode 0)
		)
		(polygon
			(pts
				(xy 201.398632 -220.875098) (xy 202.897232 -220.875098) (xy 202.897232 -221.395036) (xy 201.398632 -221.395036)
			)
		)
	)
	(zone
		(layer "In2.Cu")
		(hatch none 0.5)
		(connect_pads
			(clearance 0)
		)
		(min_thickness 0.25)
		(keepout
			(tracks not_allowed)
			(vias allowed)
			(pads allowed)
			(copperpour not_allowed)
			(footprints allowed)
		)
		(placement
			(enabled no)
			(sheetname "")
		)
		(fill
			(thermal_gap 0.5)
			(thermal_bridge_width 0.5)
			(island_removal_mode 0)
		)
		(polygon
			(pts
				(arc
					(start 304.888646 -384.288284)
					(mid 304.90857 -384.29752)
					(end 304.930302 -384.30073)
				)
				(arc
					(start 305.124866 -384.30073)
					(mid 305.178748 -384.278412)
					(end 305.201066 -384.22453)
				)
				(arc
					(start 305.201066 -383.53873)
					(mid 305.178748 -383.484848)
					(end 305.124866 -383.46253)
				)
				(arc
					(start 304.930302 -383.46253)
					(mid 304.908558 -383.465698)
					(end 304.888646 -383.474976)
				)
				(arc
					(start 304.592482 -383.667762)
					(mid 304.550798 -383.679984)
					(end 304.50917 -383.667508)
				)
				(arc
					(start 304.215546 -383.474976)
					(mid 304.195622 -383.46574)
					(end 304.17389 -383.46253)
				)
				(arc
					(start 303.979326 -383.46253)
					(mid 303.925444 -383.484848)
					(end 303.903126 -383.53873)
				)
				(arc
					(start 303.903126 -384.22453)
					(mid 303.925444 -384.278412)
					(end 303.979326 -384.30073)
				)
				(arc
					(start 304.17516 -384.30073)
					(mid 304.196904 -384.297562)
					(end 304.216816 -384.288284)
				)
				(arc
					(start 304.51044 -384.095752)
					(mid 304.552096 -384.08335)
					(end 304.593752 -384.095752)
				)
			)
		)
	)
	(zone
		(layer "In2.Cu")
		(hatch none 0.5)
		(connect_pads
			(clearance 0)
		)
		(min_thickness 0.25)
		(keepout
			(tracks not_allowed)
			(vias allowed)
			(pads allowed)
			(copperpour not_allowed)
			(footprints allowed)
		)
		(placement
			(enabled no)
			(sheetname "")
		)
		(fill
			(thermal_gap 0.5)
			(thermal_bridge_width 0.5)
			(island_removal_mode 0)
		)
		(polygon
			(pts
				(xy 193.854578 -293.125144) (xy 195.353178 -293.125144) (xy 195.353178 -293.645082) (xy 193.854578 -293.645082)
			)
		)
	)
	(zone
		(layer "In2.Cu")
		(hatch none 0.5)
		(connect_pads
			(clearance 0)
		)
		(min_thickness 0.25)
		(keepout
			(tracks not_allowed)
			(vias allowed)
			(pads allowed)
			(copperpour not_allowed)
			(footprints allowed)
		)
		(placement
			(enabled no)
			(sheetname "")
		)
		(fill
			(thermal_gap 0.5)
			(thermal_bridge_width 0.5)
			(island_removal_mode 0)
		)
		(polygon
			(pts
				(xy 54.578758 -237.02518) (xy 56.077358 -237.02518) (xy 56.077358 -237.545118) (xy 54.578758 -237.545118)
			)
		)
	)
	(zone
		(layer "In2.Cu")
		(hatch none 0.5)
		(connect_pads
			(clearance 0)
		)
		(min_thickness 0.25)
		(keepout
			(tracks not_allowed)
			(vias allowed)
			(pads allowed)
			(copperpour not_allowed)
			(footprints allowed)
		)
		(placement
			(enabled no)
			(sheetname "")
		)
		(fill
			(thermal_gap 0.5)
			(thermal_bridge_width 0.5)
			(island_removal_mode 0)
		)
		(polygon
			(pts
				(arc
					(start 352.732594 -381.824484)
					(mid 352.752518 -381.83372)
					(end 352.77425 -381.83693)
				)
				(arc
					(start 352.968814 -381.83693)
					(mid 353.022696 -381.814612)
					(end 353.045014 -381.76073)
				)
				(arc
					(start 353.045014 -381.07493)
					(mid 353.022696 -381.021048)
					(end 352.968814 -380.99873)
				)
				(arc
					(start 352.77425 -380.99873)
					(mid 352.752506 -381.001898)
					(end 352.732594 -381.011176)
				)
				(arc
					(start 352.43643 -381.203962)
					(mid 352.394746 -381.216184)
					(end 352.353118 -381.203708)
				)
				(arc
					(start 352.059494 -381.011176)
					(mid 352.03957 -381.00194)
					(end 352.017838 -380.99873)
				)
				(arc
					(start 351.823274 -380.99873)
					(mid 351.769392 -381.021048)
					(end 351.747074 -381.07493)
				)
				(arc
					(start 351.747074 -381.76073)
					(mid 351.769392 -381.814612)
					(end 351.823274 -381.83693)
				)
				(arc
					(start 352.019108 -381.83693)
					(mid 352.040852 -381.833762)
					(end 352.060764 -381.824484)
				)
				(arc
					(start 352.354388 -381.631952)
					(mid 352.396044 -381.61955)
					(end 352.4377 -381.631952)
				)
			)
		)
	)
	(zone
		(layer "In2.Cu")
		(hatch none 0.5)
		(connect_pads
			(clearance 0)
		)
		(min_thickness 0.25)
		(keepout
			(tracks not_allowed)
			(vias allowed)
			(pads allowed)
			(copperpour not_allowed)
			(footprints allowed)
		)
		(placement
			(enabled no)
			(sheetname "")
		)
		(fill
			(thermal_gap 0.5)
			(thermal_bridge_width 0.5)
			(island_removal_mode 0)
		)
		(polygon
			(pts
				(xy 453.438768 -221.725236) (xy 454.937368 -221.725236) (xy 454.937368 -222.245174) (xy 453.438768 -222.245174)
			)
		)
	)
	(zone
		(layer "In2.Cu")
		(hatch none 0.5)
		(connect_pads
			(clearance 0)
		)
		(min_thickness 0.25)
		(keepout
			(tracks not_allowed)
			(vias allowed)
			(pads allowed)
			(copperpour not_allowed)
			(footprints allowed)
		)
		(placement
			(enabled no)
			(sheetname "")
		)
		(fill
			(thermal_gap 0.5)
			(thermal_bridge_width 0.5)
			(island_removal_mode 0)
		)
		(polygon
			(pts
				(xy 411.618684 -239.57534) (xy 413.117284 -239.57534) (xy 413.117284 -240.095278) (xy 411.618684 -240.095278)
			)
		)
	)
	(zone
		(layer "In2.Cu")
		(hatch none 0.5)
		(connect_pads
			(clearance 0)
		)
		(min_thickness 0.25)
		(keepout
			(tracks not_allowed)
			(vias allowed)
			(pads allowed)
			(copperpour not_allowed)
			(footprints allowed)
		)
		(placement
			(enabled no)
			(sheetname "")
		)
		(fill
			(thermal_gap 0.5)
			(thermal_bridge_width 0.5)
			(island_removal_mode 0)
		)
		(polygon
			(pts
				(xy 294.974772 -280.375106) (xy 296.473372 -280.375106) (xy 296.473372 -280.895044) (xy 294.974772 -280.895044)
			)
		)
	)
	(zone
		(layer "In2.Cu")
		(hatch none 0.5)
		(connect_pads
			(clearance 0)
		)
		(min_thickness 0.25)
		(keepout
			(tracks not_allowed)
			(vias allowed)
			(pads allowed)
			(copperpour not_allowed)
			(footprints allowed)
		)
		(placement
			(enabled no)
			(sheetname "")
		)
		(fill
			(thermal_gap 0.5)
			(thermal_bridge_width 0.5)
			(island_removal_mode 0)
		)
		(polygon
			(pts
				(xy 28.50261 -270.175228) (xy 30.00121 -270.175228) (xy 30.00121 -270.695166) (xy 28.50261 -270.695166)
			)
		)
	)
	(zone
		(layer "In2.Cu")
		(hatch none 0.5)
		(connect_pads
			(clearance 0)
		)
		(min_thickness 0.25)
		(keepout
			(tracks not_allowed)
			(vias allowed)
			(pads allowed)
			(copperpour not_allowed)
			(footprints allowed)
		)
		(placement
			(enabled no)
			(sheetname "")
		)
		(fill
			(thermal_gap 0.5)
			(thermal_bridge_width 0.5)
			(island_removal_mode 0)
		)
		(polygon
			(pts
				(xy 287.430718 -276.125178) (xy 288.929318 -276.125178) (xy 288.929318 -276.645116) (xy 287.430718 -276.645116)
			)
		)
	)
	(zone
		(layer "In2.Cu")
		(hatch none 0.5)
		(connect_pads
			(clearance 0)
		)
		(min_thickness 0.25)
		(keepout
			(tracks not_allowed)
			(vias allowed)
			(pads allowed)
			(copperpour not_allowed)
			(footprints allowed)
		)
		(placement
			(enabled no)
			(sheetname "")
		)
		(fill
			(thermal_gap 0.5)
			(thermal_bridge_width 0.5)
			(island_removal_mode 0)
		)
		(polygon
			(pts
				(xy 186.310778 -276.975316) (xy 187.809378 -276.975316) (xy 187.809378 -277.495254) (xy 186.310778 -277.495254)
			)
		)
	)
	(zone
		(layer "In2.Cu")
		(hatch none 0.5)
		(connect_pads
			(clearance 0)
		)
		(min_thickness 0.25)
		(keepout
			(tracks not_allowed)
			(vias allowed)
			(pads allowed)
			(copperpour not_allowed)
			(footprints allowed)
		)
		(placement
			(enabled no)
			(sheetname "")
		)
		(fill
			(thermal_gap 0.5)
			(thermal_bridge_width 0.5)
			(island_removal_mode 0)
		)
		(polygon
			(pts
				(xy 445.894968 -279.525222) (xy 447.393568 -279.525222) (xy 447.393568 -280.04516) (xy 445.894968 -280.04516)
			)
		)
	)
	(zone
		(layer "In2.Cu")
		(hatch none 0.5)
		(connect_pads
			(clearance 0)
		)
		(min_thickness 0.25)
		(keepout
			(tracks not_allowed)
			(vias allowed)
			(pads allowed)
			(copperpour not_allowed)
			(footprints allowed)
		)
		(placement
			(enabled no)
			(sheetname "")
		)
		(fill
			(thermal_gap 0.5)
			(thermal_bridge_width 0.5)
			(island_removal_mode 0)
		)
		(polygon
			(pts
				(xy 163.678616 -205.575154) (xy 165.177216 -205.575154) (xy 165.177216 -206.095092) (xy 163.678616 -206.095092)
			)
		)
	)
	(zone
		(layer "In2.Cu")
		(hatch none 0.5)
		(connect_pads
			(clearance 0)
		)
		(min_thickness 0.25)
		(keepout
			(tracks not_allowed)
			(vias allowed)
			(pads allowed)
			(copperpour not_allowed)
			(footprints allowed)
		)
		(placement
			(enabled no)
			(sheetname "")
		)
		(fill
			(thermal_gap 0.5)
			(thermal_bridge_width 0.5)
			(island_removal_mode 0)
		)
		(polygon
			(pts
				(xy 16.858742 -278.675338) (xy 18.357342 -278.675338) (xy 18.357342 -279.195276) (xy 16.858742 -279.195276)
			)
		)
	)
	(zone
		(layer "In2.Cu")
		(hatch none 0.5)
		(connect_pads
			(clearance 0)
		)
		(min_thickness 0.25)
		(keepout
			(tracks not_allowed)
			(vias allowed)
			(pads allowed)
			(copperpour not_allowed)
			(footprints allowed)
		)
		(placement
			(enabled no)
			(sheetname "")
		)
		(fill
			(thermal_gap 0.5)
			(thermal_bridge_width 0.5)
			(island_removal_mode 0)
		)
		(polygon
			(pts
				(xy 441.7949 -241.275108) (xy 443.2935 -241.275108) (xy 443.2935 -241.795046) (xy 441.7949 -241.795046)
			)
		)
	)
	(zone
		(layer "In2.Cu")
		(hatch none 0.5)
		(connect_pads
			(clearance 0)
		)
		(min_thickness 0.25)
		(keepout
			(tracks not_allowed)
			(vias allowed)
			(pads allowed)
			(copperpour not_allowed)
			(footprints allowed)
		)
		(placement
			(enabled no)
			(sheetname "")
		)
		(fill
			(thermal_gap 0.5)
			(thermal_bridge_width 0.5)
			(island_removal_mode 0)
		)
		(polygon
			(pts
				(xy 16.92148 -107.441492) (xy 16.655542 -107.441492) (xy 16.655542 -107.381548)
				(arc
					(start 16.515334 -107.381548)
					(mid 16.445452 -107.410757)
					(end 16.416782 -107.480862)
				)
				(arc
					(start 16.416782 -107.782106)
					(mid 16.445452 -107.852211)
					(end 16.515334 -107.88142)
				)
				(xy 16.655542 -107.88142) (xy 16.655542 -107.821476) (xy 16.92148 -107.821476)
			)
		)
	)
	(zone
		(layer "In2.Cu")
		(hatch none 0.5)
		(connect_pads
			(clearance 0)
		)
		(min_thickness 0.25)
		(keepout
			(tracks not_allowed)
			(vias allowed)
			(pads allowed)
			(copperpour not_allowed)
			(footprints allowed)
		)
		(placement
			(enabled no)
			(sheetname "")
		)
		(fill
			(thermal_gap 0.5)
			(thermal_bridge_width 0.5)
			(island_removal_mode 0)
		)
		(polygon
			(pts
				(xy 201.398632 -254.025146) (xy 202.897232 -254.025146) (xy 202.897232 -254.545084) (xy 201.398632 -254.545084)
			)
		)
	)
	(zone
		(layer "In2.Cu")
		(hatch none 0.5)
		(connect_pads
			(clearance 0)
		)
		(min_thickness 0.25)
		(keepout
			(tracks not_allowed)
			(vias allowed)
			(pads allowed)
			(copperpour not_allowed)
			(footprints allowed)
		)
		(placement
			(enabled no)
			(sheetname "")
		)
		(fill
			(thermal_gap 0.5)
			(thermal_bridge_width 0.5)
			(island_removal_mode 0)
		)
		(polygon
			(pts
				(xy 171.22267 -222.57512) (xy 172.72127 -222.57512) (xy 172.72127 -223.095058) (xy 171.22267 -223.095058)
			)
		)
	)
	(zone
		(layer "In2.Cu")
		(hatch none 0.5)
		(connect_pads
			(clearance 0)
		)
		(min_thickness 0.25)
		(keepout
			(tracks not_allowed)
			(vias allowed)
			(pads allowed)
			(copperpour not_allowed)
			(footprints allowed)
		)
		(placement
			(enabled no)
			(sheetname "")
		)
		(fill
			(thermal_gap 0.5)
			(thermal_bridge_width 0.5)
			(island_removal_mode 0)
		)
		(polygon
			(pts
				(xy 415.718752 -229.375208) (xy 417.217352 -229.375208) (xy 417.217352 -229.895146) (xy 415.718752 -229.895146)
			)
		)
	)
	(zone
		(layer "In2.Cu")
		(hatch none 0.5)
		(connect_pads
			(clearance 0)
		)
		(min_thickness 0.25)
		(keepout
			(tracks not_allowed)
			(vias allowed)
			(pads allowed)
			(copperpour not_allowed)
			(footprints allowed)
		)
		(placement
			(enabled no)
			(sheetname "")
		)
		(fill
			(thermal_gap 0.5)
			(thermal_bridge_width 0.5)
			(island_removal_mode 0)
		)
		(polygon
			(pts
				(xy 415.718752 -264.225278) (xy 417.217352 -264.225278) (xy 417.217352 -264.745216) (xy 415.718752 -264.745216)
			)
		)
	)
	(zone
		(layer "In2.Cu")
		(hatch none 0.5)
		(connect_pads
			(clearance 0)
		)
		(min_thickness 0.25)
		(keepout
			(tracks not_allowed)
			(vias allowed)
			(pads allowed)
			(copperpour not_allowed)
			(footprints allowed)
		)
		(placement
			(enabled no)
			(sheetname "")
		)
		(fill
			(thermal_gap 0.5)
			(thermal_bridge_width 0.5)
			(island_removal_mode 0)
		)
		(polygon
			(pts
				(xy 186.310778 -276.125178) (xy 187.809378 -276.125178) (xy 187.809378 -276.645116) (xy 186.310778 -276.645116)
			)
		)
	)
	(zone
		(layer "In2.Cu")
		(hatch none 0.5)
		(connect_pads
			(clearance 0)
		)
		(min_thickness 0.25)
		(keepout
			(tracks not_allowed)
			(vias allowed)
			(pads allowed)
			(copperpour not_allowed)
			(footprints allowed)
		)
		(placement
			(enabled no)
			(sheetname "")
		)
		(fill
			(thermal_gap 0.5)
			(thermal_bridge_width 0.5)
			(island_removal_mode 0)
		)
		(polygon
			(pts
				(xy 415.718752 -237.875318) (xy 417.217352 -237.875318) (xy 417.217352 -238.395256) (xy 415.718752 -238.395256)
			)
		)
	)
	(zone
		(layer "In2.Cu")
		(hatch none 0.5)
		(connect_pads
			(clearance 0)
		)
		(min_thickness 0.25)
		(keepout
			(tracks not_allowed)
			(vias allowed)
			(pads allowed)
			(copperpour not_allowed)
			(footprints allowed)
		)
		(placement
			(enabled no)
			(sheetname "")
		)
		(fill
			(thermal_gap 0.5)
			(thermal_bridge_width 0.5)
			(island_removal_mode 0)
		)
		(polygon
			(pts
				(xy 16.858742 -266.775184) (xy 18.357342 -266.775184) (xy 18.357342 -267.295122) (xy 16.858742 -267.295122)
			)
		)
	)
	(zone
		(layer "In2.Cu")
		(hatch none 0.5)
		(connect_pads
			(clearance 0)
		)
		(min_thickness 0.25)
		(keepout
			(tracks not_allowed)
			(vias allowed)
			(pads allowed)
			(copperpour not_allowed)
			(footprints allowed)
		)
		(placement
			(enabled no)
			(sheetname "")
		)
		(fill
			(thermal_gap 0.5)
			(thermal_bridge_width 0.5)
			(island_removal_mode 0)
		)
		(polygon
			(pts
				(xy 291.530786 -312.67527) (xy 293.029386 -312.67527) (xy 293.029386 -313.195208) (xy 291.530786 -313.195208)
			)
		)
	)
	(zone
		(layer "In2.Cu")
		(hatch none 0.5)
		(connect_pads
			(clearance 0)
		)
		(min_thickness 0.25)
		(keepout
			(tracks not_allowed)
			(vias allowed)
			(pads allowed)
			(copperpour not_allowed)
			(footprints allowed)
		)
		(placement
			(enabled no)
			(sheetname "")
		)
		(fill
			(thermal_gap 0.5)
			(thermal_bridge_width 0.5)
			(island_removal_mode 0)
		)
		(polygon
			(pts
				(xy 16.858742 -210.67522) (xy 18.357342 -210.67522) (xy 18.357342 -211.195158) (xy 16.858742 -211.195158)
			)
		)
	)
	(zone
		(layer "In2.Cu")
		(hatch none 0.5)
		(connect_pads
			(clearance 0)
		)
		(min_thickness 0.25)
		(keepout
			(tracks not_allowed)
			(vias allowed)
			(pads allowed)
			(copperpour not_allowed)
			(footprints allowed)
		)
		(placement
			(enabled no)
			(sheetname "")
		)
		(fill
			(thermal_gap 0.5)
			(thermal_bridge_width 0.5)
			(island_removal_mode 0)
		)
		(polygon
			(pts
				(xy 175.322738 -270.175228) (xy 176.821338 -270.175228) (xy 176.821338 -270.695166) (xy 175.322738 -270.695166)
			)
		)
	)
	(zone
		(layer "In2.Cu")
		(hatch none 0.5)
		(connect_pads
			(clearance 0)
		)
		(min_thickness 0.25)
		(keepout
			(tracks not_allowed)
			(vias allowed)
			(pads allowed)
			(copperpour not_allowed)
			(footprints allowed)
		)
		(placement
			(enabled no)
			(sheetname "")
		)
		(fill
			(thermal_gap 0.5)
			(thermal_bridge_width 0.5)
			(island_removal_mode 0)
		)
		(polygon
			(pts
				(xy 306.618894 -210.67522) (xy 308.117494 -210.67522) (xy 308.117494 -211.195158) (xy 306.618894 -211.195158)
			)
		)
	)
	(zone
		(layer "In2.Cu")
		(hatch none 0.5)
		(connect_pads
			(clearance 0)
		)
		(min_thickness 0.25)
		(keepout
			(tracks not_allowed)
			(vias allowed)
			(pads allowed)
			(copperpour not_allowed)
			(footprints allowed)
		)
		(placement
			(enabled no)
			(sheetname "")
		)
		(fill
			(thermal_gap 0.5)
			(thermal_bridge_width 0.5)
			(island_removal_mode 0)
		)
		(polygon
			(pts
				(xy 163.678616 -246.375174) (xy 165.177216 -246.375174) (xy 165.177216 -246.895112) (xy 163.678616 -246.895112)
			)
		)
	)
	(zone
		(layer "In2.Cu")
		(hatch none 0.5)
		(connect_pads
			(clearance 0)
		)
		(min_thickness 0.25)
		(keepout
			(tracks not_allowed)
			(vias allowed)
			(pads allowed)
			(copperpour not_allowed)
			(footprints allowed)
		)
		(placement
			(enabled no)
			(sheetname "")
		)
		(fill
			(thermal_gap 0.5)
			(thermal_bridge_width 0.5)
			(island_removal_mode 0)
		)
		(polygon
			(pts
				(xy 287.430718 -199.625204) (xy 288.929318 -199.625204) (xy 288.929318 -200.145142) (xy 287.430718 -200.145142)
			)
		)
	)
	(zone
		(layer "In2.Cu")
		(hatch none 0.5)
		(connect_pads
			(clearance 0)
		)
		(min_thickness 0.25)
		(keepout
			(tracks not_allowed)
			(vias allowed)
			(pads allowed)
			(copperpour not_allowed)
			(footprints allowed)
		)
		(placement
			(enabled no)
			(sheetname "")
		)
		(fill
			(thermal_gap 0.5)
			(thermal_bridge_width 0.5)
			(island_removal_mode 0)
		)
		(polygon
			(pts
				(xy 434.250846 -249.775218) (xy 435.749446 -249.775218) (xy 435.749446 -250.295156) (xy 434.250846 -250.295156)
			)
		)
	)
	(zone
		(layer "In2.Cu")
		(hatch none 0.5)
		(connect_pads
			(clearance 0)
		)
		(min_thickness 0.25)
		(keepout
			(tracks not_allowed)
			(vias allowed)
			(pads allowed)
			(copperpour not_allowed)
			(footprints allowed)
		)
		(placement
			(enabled no)
			(sheetname "")
		)
		(fill
			(thermal_gap 0.5)
			(thermal_bridge_width 0.5)
			(island_removal_mode 0)
		)
		(polygon
			(pts
				(xy 283.986732 -220.025214) (xy 285.485332 -220.025214) (xy 285.485332 -220.545152) (xy 283.986732 -220.545152)
			)
		)
	)
	(zone
		(layer "In2.Cu")
		(hatch none 0.5)
		(connect_pads
			(clearance 0)
		)
		(min_thickness 0.25)
		(keepout
			(tracks not_allowed)
			(vias allowed)
			(pads allowed)
			(copperpour not_allowed)
			(footprints allowed)
		)
		(placement
			(enabled no)
			(sheetname "")
		)
		(fill
			(thermal_gap 0.5)
			(thermal_bridge_width 0.5)
			(island_removal_mode 0)
		)
		(polygon
			(pts
				(xy 36.046664 -293.975282) (xy 37.545264 -293.975282) (xy 37.545264 -294.49522) (xy 36.046664 -294.49522)
			)
		)
	)
	(zone
		(layer "In2.Cu")
		(hatch none 0.5)
		(connect_pads
			(clearance 0)
		)
		(min_thickness 0.25)
		(keepout
			(tracks allowed)
			(vias allowed)
			(pads allowed)
			(copperpour allowed)
			(footprints allowed)
		)
		(placement
			(enabled no)
			(sheetname "")
		)
		(fill
			(thermal_gap 0.5)
			(thermal_bridge_width 0.5)
			(island_removal_mode 0)
		)
		(polygon
			(pts
				(xy 56.97601 -350.595692) (xy 56.97601 -349.973392) (xy 57.52719 -349.973392) (xy 57.52719 -350.595692)
			)
		)
	)
	(zone
		(layer "In2.Cu")
		(hatch none 0.5)
		(connect_pads
			(clearance 0)
		)
		(min_thickness 0.25)
		(keepout
			(tracks not_allowed)
			(vias allowed)
			(pads allowed)
			(copperpour not_allowed)
			(footprints allowed)
		)
		(placement
			(enabled no)
			(sheetname "")
		)
		(fill
			(thermal_gap 0.5)
			(thermal_bridge_width 0.5)
			(island_removal_mode 0)
		)
		(polygon
			(pts
				(xy 51.134772 -203.025248) (xy 52.633372 -203.025248) (xy 52.633372 -203.545186) (xy 51.134772 -203.545186)
			)
		)
	)
	(zone
		(layer "In2.Cu")
		(hatch none 0.5)
		(connect_pads
			(clearance 0)
		)
		(min_thickness 0.25)
		(keepout
			(tracks not_allowed)
			(vias allowed)
			(pads allowed)
			(copperpour not_allowed)
			(footprints allowed)
		)
		(placement
			(enabled no)
			(sheetname "")
		)
		(fill
			(thermal_gap 0.5)
			(thermal_bridge_width 0.5)
			(island_removal_mode 0)
		)
		(polygon
			(pts
				(arc
					(start 54.77256 -16.442436)
					(mid 54.794878 -16.496318)
					(end 54.84876 -16.518636)
				)
				(arc
					(start 55.04434 -16.518636)
					(mid 55.066216 -16.515504)
					(end 55.08625 -16.50619)
				)
				(arc
					(start 55.379874 -16.313658)
					(mid 55.42153 -16.301256)
					(end 55.463186 -16.313658)
				)
				(arc
					(start 55.75808 -16.50619)
					(mid 55.778004 -16.515426)
					(end 55.799736 -16.518636)
				)
				(arc
					(start 55.9943 -16.518636)
					(mid 56.048182 -16.496318)
					(end 56.0705 -16.442436)
				)
				(arc
					(start 56.0705 -15.756636)
					(mid 56.048182 -15.702754)
					(end 55.9943 -15.680436)
				)
				(arc
					(start 55.799736 -15.680436)
					(mid 55.777992 -15.683604)
					(end 55.75808 -15.692882)
				)
				(arc
					(start 55.461916 -15.885668)
					(mid 55.420232 -15.89789)
					(end 55.378604 -15.885414)
				)
				(arc
					(start 55.08498 -15.692882)
					(mid 55.065056 -15.683646)
					(end 55.043324 -15.680436)
				)
				(arc
					(start 54.84876 -15.680436)
					(mid 54.794878 -15.702754)
					(end 54.77256 -15.756636)
				)
			)
		)
	)
	(zone
		(layer "In2.Cu")
		(hatch none 0.5)
		(connect_pads
			(clearance 0)
		)
		(min_thickness 0.25)
		(keepout
			(tracks not_allowed)
			(vias allowed)
			(pads allowed)
			(copperpour not_allowed)
			(footprints allowed)
		)
		(placement
			(enabled no)
			(sheetname "")
		)
		(fill
			(thermal_gap 0.5)
			(thermal_bridge_width 0.5)
			(island_removal_mode 0)
		)
		(polygon
			(pts
				(xy 430.80686 -284.625288) (xy 432.30546 -284.625288) (xy 432.30546 -285.145226) (xy 430.80686 -285.145226)
			)
		)
	)
	(zone
		(layer "In2.Cu")
		(hatch none 0.5)
		(connect_pads
			(clearance 0)
		)
		(min_thickness 0.25)
		(keepout
			(tracks not_allowed)
			(vias allowed)
			(pads allowed)
			(copperpour not_allowed)
			(footprints allowed)
		)
		(placement
			(enabled no)
			(sheetname "")
		)
		(fill
			(thermal_gap 0.5)
			(thermal_bridge_width 0.5)
			(island_removal_mode 0)
		)
		(polygon
			(pts
				(xy 438.350914 -273.575272) (xy 439.849514 -273.575272) (xy 439.849514 -274.09521) (xy 438.350914 -274.09521)
			)
		)
	)
	(zone
		(layer "In2.Cu")
		(hatch none 0.5)
		(connect_pads
			(clearance 0)
		)
		(min_thickness 0.25)
		(keepout
			(tracks not_allowed)
			(vias allowed)
			(pads allowed)
			(copperpour not_allowed)
			(footprints allowed)
		)
		(placement
			(enabled no)
			(sheetname "")
		)
		(fill
			(thermal_gap 0.5)
			(thermal_bridge_width 0.5)
			(island_removal_mode 0)
		)
		(polygon
			(pts
				(xy 299.07484 -231.07523) (xy 300.57344 -231.07523) (xy 300.57344 -231.595168) (xy 299.07484 -231.595168)
			)
		)
	)
	(zone
		(layer "In2.Cu")
		(hatch none 0.5)
		(connect_pads
			(clearance 0)
		)
		(min_thickness 0.25)
		(keepout
			(tracks not_allowed)
			(vias allowed)
			(pads allowed)
			(copperpour not_allowed)
			(footprints allowed)
		)
		(placement
			(enabled no)
			(sheetname "")
		)
		(fill
			(thermal_gap 0.5)
			(thermal_bridge_width 0.5)
			(island_removal_mode 0)
		)
		(polygon
			(pts
				(xy 190.410846 -310.975248) (xy 191.909446 -310.975248) (xy 191.909446 -311.495186) (xy 190.410846 -311.495186)
			)
		)
	)
	(zone
		(layer "In2.Cu")
		(hatch none 0.5)
		(connect_pads
			(clearance 0)
		)
		(min_thickness 0.25)
		(keepout
			(tracks not_allowed)
			(vias allowed)
			(pads allowed)
			(copperpour not_allowed)
			(footprints allowed)
		)
		(placement
			(enabled no)
			(sheetname "")
		)
		(fill
			(thermal_gap 0.5)
			(thermal_bridge_width 0.5)
			(island_removal_mode 0)
		)
		(polygon
			(pts
				(xy 31.946596 -306.72532) (xy 33.445196 -306.72532) (xy 33.445196 -307.245258) (xy 31.946596 -307.245258)
			)
		)
	)
	(zone
		(layer "In2.Cu")
		(hatch none 0.5)
		(connect_pads
			(clearance 0)
		)
		(min_thickness 0.25)
		(keepout
			(tracks not_allowed)
			(vias allowed)
			(pads allowed)
			(copperpour not_allowed)
			(footprints allowed)
		)
		(placement
			(enabled no)
			(sheetname "")
		)
		(fill
			(thermal_gap 0.5)
			(thermal_bridge_width 0.5)
			(island_removal_mode 0)
		)
		(polygon
			(pts
				(xy 24.402542 -207.275176) (xy 25.901142 -207.275176) (xy 25.901142 -207.795114) (xy 24.402542 -207.795114)
			)
		)
	)
	(zone
		(layer "In2.Cu")
		(hatch none 0.5)
		(connect_pads
			(clearance 0)
		)
		(min_thickness 0.25)
		(keepout
			(tracks not_allowed)
			(vias allowed)
			(pads allowed)
			(copperpour not_allowed)
			(footprints allowed)
		)
		(placement
			(enabled no)
			(sheetname "")
		)
		(fill
			(thermal_gap 0.5)
			(thermal_bridge_width 0.5)
			(island_removal_mode 0)
		)
		(polygon
			(pts
				(xy 291.530786 -284.625288) (xy 293.029386 -284.625288) (xy 293.029386 -285.145226) (xy 291.530786 -285.145226)
			)
		)
	)
	(zone
		(layer "In2.Cu")
		(hatch none 0.5)
		(connect_pads
			(clearance 0)
		)
		(min_thickness 0.25)
		(keepout
			(tracks not_allowed)
			(vias allowed)
			(pads allowed)
			(copperpour not_allowed)
			(footprints allowed)
		)
		(placement
			(enabled no)
			(sheetname "")
		)
		(fill
			(thermal_gap 0.5)
			(thermal_bridge_width 0.5)
			(island_removal_mode 0)
		)
		(polygon
			(pts
				(xy 272.342864 -311.825132) (xy 273.841464 -311.825132) (xy 273.841464 -312.34507) (xy 272.342864 -312.34507)
			)
		)
	)
	(zone
		(layer "In2.Cu")
		(hatch none 0.5)
		(connect_pads
			(clearance 0)
		)
		(min_thickness 0.25)
		(keepout
			(tracks not_allowed)
			(vias allowed)
			(pads allowed)
			(copperpour not_allowed)
			(footprints allowed)
		)
		(placement
			(enabled no)
			(sheetname "")
		)
		(fill
			(thermal_gap 0.5)
			(thermal_bridge_width 0.5)
			(island_removal_mode 0)
		)
		(polygon
			(pts
				(xy 279.886664 -202.17511) (xy 281.385264 -202.17511) (xy 281.385264 -202.695048) (xy 279.886664 -202.695048)
			)
		)
	)
	(zone
		(layer "In2.Cu")
		(hatch none 0.5)
		(connect_pads
			(clearance 0)
		)
		(min_thickness 0.25)
		(keepout
			(tracks not_allowed)
			(vias allowed)
			(pads allowed)
			(copperpour not_allowed)
			(footprints allowed)
		)
		(placement
			(enabled no)
			(sheetname "")
		)
		(fill
			(thermal_gap 0.5)
			(thermal_bridge_width 0.5)
			(island_removal_mode 0)
		)
		(polygon
			(pts
				(xy 306.618894 -292.27526) (xy 308.117494 -292.27526) (xy 308.117494 -292.795198) (xy 306.618894 -292.795198)
			)
		)
	)
	(zone
		(layer "In2.Cu")
		(hatch none 0.5)
		(connect_pads
			(clearance 0)
		)
		(min_thickness 0.25)
		(keepout
			(tracks not_allowed)
			(vias allowed)
			(pads allowed)
			(copperpour not_allowed)
			(footprints allowed)
		)
		(placement
			(enabled no)
			(sheetname "")
		)
		(fill
			(thermal_gap 0.5)
			(thermal_bridge_width 0.5)
			(island_removal_mode 0)
		)
		(polygon
			(pts
				(xy 171.22267 -207.275176) (xy 172.72127 -207.275176) (xy 172.72127 -207.795114) (xy 171.22267 -207.795114)
			)
		)
	)
	(zone
		(layer "In2.Cu")
		(hatch none 0.5)
		(connect_pads
			(clearance 0)
		)
		(min_thickness 0.25)
		(keepout
			(tracks not_allowed)
			(vias allowed)
			(pads allowed)
			(copperpour not_allowed)
			(footprints allowed)
		)
		(placement
			(enabled no)
			(sheetname "")
		)
		(fill
			(thermal_gap 0.5)
			(thermal_bridge_width 0.5)
			(island_removal_mode 0)
		)
		(polygon
			(pts
				(xy 132.205222 -32.363156) (xy 132.783072 -32.363156) (xy 132.783072 -33.683956) (xy 132.205222 -33.683956)
			)
		)
	)
	(zone
		(layer "In2.Cu")
		(hatch none 0.5)
		(connect_pads
			(clearance 0)
		)
		(min_thickness 0.25)
		(keepout
			(tracks not_allowed)
			(vias allowed)
			(pads allowed)
			(copperpour not_allowed)
			(footprints allowed)
		)
		(placement
			(enabled no)
			(sheetname "")
		)
		(fill
			(thermal_gap 0.5)
			(thermal_bridge_width 0.5)
			(island_removal_mode 0)
		)
		(polygon
			(pts
				(xy 306.618894 -217.475308) (xy 308.117494 -217.475308) (xy 308.117494 -217.995246) (xy 306.618894 -217.995246)
			)
		)
	)
	(zone
		(layer "In2.Cu")
		(hatch none 0.5)
		(connect_pads
			(clearance 0)
		)
		(min_thickness 0.25)
		(keepout
			(tracks not_allowed)
			(vias allowed)
			(pads allowed)
			(copperpour not_allowed)
			(footprints allowed)
		)
		(placement
			(enabled no)
			(sheetname "")
		)
		(fill
			(thermal_gap 0.5)
			(thermal_bridge_width 0.5)
			(island_removal_mode 0)
		)
		(polygon
			(pts
				(xy 31.946596 -291.425122) (xy 33.445196 -291.425122) (xy 33.445196 -291.94506) (xy 31.946596 -291.94506)
			)
		)
	)
	(zone
		(layer "In2.Cu")
		(hatch none 0.5)
		(connect_pads
			(clearance 0)
		)
		(min_thickness 0.25)
		(keepout
			(tracks not_allowed)
			(vias allowed)
			(pads allowed)
			(copperpour not_allowed)
			(footprints allowed)
		)
		(placement
			(enabled no)
			(sheetname "")
		)
		(fill
			(thermal_gap 0.5)
			(thermal_bridge_width 0.5)
			(island_removal_mode 0)
		)
		(polygon
			(pts
				(xy 175.322738 -309.275226) (xy 176.821338 -309.275226) (xy 176.821338 -309.795164) (xy 175.322738 -309.795164)
			)
		)
	)
	(zone
		(layer "In2.Cu")
		(hatch none 0.5)
		(connect_pads
			(clearance 0)
		)
		(min_thickness 0.25)
		(keepout
			(tracks not_allowed)
			(vias allowed)
			(pads allowed)
			(copperpour not_allowed)
			(footprints allowed)
		)
		(placement
			(enabled no)
			(sheetname "")
		)
		(fill
			(thermal_gap 0.5)
			(thermal_bridge_width 0.5)
			(island_removal_mode 0)
		)
		(polygon
			(pts
				(xy 175.322738 -237.875318) (xy 176.821338 -237.875318) (xy 176.821338 -238.395256) (xy 175.322738 -238.395256)
			)
		)
	)
	(zone
		(layer "In2.Cu")
		(hatch none 0.5)
		(connect_pads
			(clearance 0)
		)
		(min_thickness 0.25)
		(keepout
			(tracks not_allowed)
			(vias allowed)
			(pads allowed)
			(copperpour not_allowed)
			(footprints allowed)
		)
		(placement
			(enabled no)
			(sheetname "")
		)
		(fill
			(thermal_gap 0.5)
			(thermal_bridge_width 0.5)
			(island_removal_mode 0)
		)
		(polygon
			(pts
				(xy 441.7949 -239.57534) (xy 443.2935 -239.57534) (xy 443.2935 -240.095278) (xy 441.7949 -240.095278)
			)
		)
	)
	(zone
		(layer "In2.Cu")
		(hatch none 0.5)
		(connect_pads
			(clearance 0)
		)
		(min_thickness 0.25)
		(keepout
			(tracks not_allowed)
			(vias allowed)
			(pads allowed)
			(copperpour not_allowed)
			(footprints allowed)
		)
		(placement
			(enabled no)
			(sheetname "")
		)
		(fill
			(thermal_gap 0.5)
			(thermal_bridge_width 0.5)
			(island_removal_mode 0)
		)
		(polygon
			(pts
				(xy 287.430718 -197.925182) (xy 288.929318 -197.925182) (xy 288.929318 -198.44512) (xy 287.430718 -198.44512)
			)
		)
	)
	(zone
		(layer "In2.Cu")
		(hatch none 0.5)
		(connect_pads
			(clearance 0)
		)
		(min_thickness 0.25)
		(keepout
			(tracks not_allowed)
			(vias allowed)
			(pads allowed)
			(copperpour not_allowed)
			(footprints allowed)
		)
		(placement
			(enabled no)
			(sheetname "")
		)
		(fill
			(thermal_gap 0.5)
			(thermal_bridge_width 0.5)
			(island_removal_mode 0)
		)
		(polygon
			(pts
				(xy 438.350914 -290.575238) (xy 439.849514 -290.575238) (xy 439.849514 -291.095176) (xy 438.350914 -291.095176)
			)
		)
	)
	(zone
		(layer "In2.Cu")
		(hatch none 0.5)
		(connect_pads
			(clearance 0)
		)
		(min_thickness 0.25)
		(keepout
			(tracks not_allowed)
			(vias allowed)
			(pads allowed)
			(copperpour not_allowed)
			(footprints allowed)
		)
		(placement
			(enabled no)
			(sheetname "")
		)
		(fill
			(thermal_gap 0.5)
			(thermal_bridge_width 0.5)
			(island_removal_mode 0)
		)
		(polygon
			(pts
				(xy 201.398632 -248.075196) (xy 202.897232 -248.075196) (xy 202.897232 -248.595134) (xy 201.398632 -248.595134)
			)
		)
	)
	(zone
		(layer "In2.Cu")
		(hatch none 0.5)
		(connect_pads
			(clearance 0)
		)
		(min_thickness 0.25)
		(keepout
			(tracks not_allowed)
			(vias allowed)
			(pads allowed)
			(copperpour not_allowed)
			(footprints allowed)
		)
		(placement
			(enabled no)
			(sheetname "")
		)
		(fill
			(thermal_gap 0.5)
			(thermal_bridge_width 0.5)
			(island_removal_mode 0)
		)
		(polygon
			(pts
				(xy 14.455394 -105.41381) (xy 14.455394 -105.147872) (xy 14.515338 -105.147872)
				(arc
					(start 14.515338 -105.007664)
					(mid 14.486129 -104.937782)
					(end 14.416024 -104.909112)
				)
				(arc
					(start 14.11478 -104.909112)
					(mid 14.044675 -104.937782)
					(end 14.015466 -105.007664)
				)
				(xy 14.015466 -105.147872) (xy 14.07541 -105.147872) (xy 14.07541 -105.41381)
			)
		)
	)
	(zone
		(layer "In2.Cu")
		(hatch none 0.5)
		(connect_pads
			(clearance 0)
		)
		(min_thickness 0.25)
		(keepout
			(tracks not_allowed)
			(vias allowed)
			(pads allowed)
			(copperpour not_allowed)
			(footprints allowed)
		)
		(placement
			(enabled no)
			(sheetname "")
		)
		(fill
			(thermal_gap 0.5)
			(thermal_bridge_width 0.5)
			(island_removal_mode 0)
		)
		(polygon
			(pts
				(xy 441.7949 -302.475138) (xy 443.2935 -302.475138) (xy 443.2935 -302.995076) (xy 441.7949 -302.995076)
			)
		)
	)
	(zone
		(layer "In2.Cu")
		(hatch none 0.5)
		(connect_pads
			(clearance 0)
		)
		(min_thickness 0.25)
		(keepout
			(tracks not_allowed)
			(vias allowed)
			(pads allowed)
			(copperpour not_allowed)
			(footprints allowed)
		)
		(placement
			(enabled no)
			(sheetname "")
		)
		(fill
			(thermal_gap 0.5)
			(thermal_bridge_width 0.5)
			(island_removal_mode 0)
		)
		(polygon
			(pts
				(xy 54.578758 -308.425342) (xy 56.077358 -308.425342) (xy 56.077358 -308.94528) (xy 54.578758 -308.94528)
			)
		)
	)
	(zone
		(layer "In2.Cu")
		(hatch none 0.5)
		(connect_pads
			(clearance 0)
		)
		(min_thickness 0.25)
		(keepout
			(tracks not_allowed)
			(vias allowed)
			(pads allowed)
			(copperpour not_allowed)
			(footprints allowed)
		)
		(placement
			(enabled no)
			(sheetname "")
		)
		(fill
			(thermal_gap 0.5)
			(thermal_bridge_width 0.5)
			(island_removal_mode 0)
		)
		(polygon
			(pts
				(xy 441.7949 -253.175262) (xy 443.2935 -253.175262) (xy 443.2935 -253.6952) (xy 441.7949 -253.6952)
			)
		)
	)
	(zone
		(layer "In2.Cu")
		(hatch none 0.5)
		(connect_pads
			(clearance 0)
		)
		(min_thickness 0.25)
		(keepout
			(tracks not_allowed)
			(vias allowed)
			(pads allowed)
			(copperpour not_allowed)
			(footprints allowed)
		)
		(placement
			(enabled no)
			(sheetname "")
		)
		(fill
			(thermal_gap 0.5)
			(thermal_bridge_width 0.5)
			(island_removal_mode 0)
		)
		(polygon
			(pts
				(xy 441.7949 -216.62517) (xy 443.2935 -216.62517) (xy 443.2935 -217.145108) (xy 441.7949 -217.145108)
			)
		)
	)
	(zone
		(layer "In2.Cu")
		(hatch none 0.5)
		(connect_pads
			(clearance 0)
		)
		(min_thickness 0.25)
		(keepout
			(tracks not_allowed)
			(vias allowed)
			(pads allowed)
			(copperpour not_allowed)
			(footprints allowed)
		)
		(placement
			(enabled no)
			(sheetname "")
		)
		(fill
			(thermal_gap 0.5)
			(thermal_bridge_width 0.5)
			(island_removal_mode 0)
		)
		(polygon
			(pts
				(xy 20.95881 -219.17533) (xy 22.45741 -219.17533) (xy 22.45741 -219.695268) (xy 20.95881 -219.695268)
			)
		)
	)
	(zone
		(layer "In2.Cu")
		(hatch none 0.5)
		(connect_pads
			(clearance 0)
		)
		(min_thickness 0.25)
		(keepout
			(tracks not_allowed)
			(vias allowed)
			(pads allowed)
			(copperpour not_allowed)
			(footprints allowed)
		)
		(placement
			(enabled no)
			(sheetname "")
		)
		(fill
			(thermal_gap 0.5)
			(thermal_bridge_width 0.5)
			(island_removal_mode 0)
		)
		(polygon
			(pts
				(xy 47.034704 -289.725354) (xy 48.533304 -289.725354) (xy 48.533304 -290.245292) (xy 47.034704 -290.245292)
			)
		)
	)
	(zone
		(layer "In2.Cu")
		(hatch none 0.5)
		(connect_pads
			(clearance 0)
		)
		(min_thickness 0.25)
		(keepout
			(tracks not_allowed)
			(vias allowed)
			(pads allowed)
			(copperpour not_allowed)
			(footprints allowed)
		)
		(placement
			(enabled no)
			(sheetname "")
		)
		(fill
			(thermal_gap 0.5)
			(thermal_bridge_width 0.5)
			(island_removal_mode 0)
		)
		(polygon
			(pts
				(xy 276.442932 -305.875182) (xy 277.941532 -305.875182) (xy 277.941532 -306.39512) (xy 276.442932 -306.39512)
			)
		)
	)
	(zone
		(layer "In2.Cu")
		(hatch none 0.5)
		(connect_pads
			(clearance 0)
		)
		(min_thickness 0.25)
		(keepout
			(tracks not_allowed)
			(vias allowed)
			(pads allowed)
			(copperpour not_allowed)
			(footprints allowed)
		)
		(placement
			(enabled no)
			(sheetname "")
		)
		(fill
			(thermal_gap 0.5)
			(thermal_bridge_width 0.5)
			(island_removal_mode 0)
		)
		(polygon
			(pts
				(xy 171.22267 -249.775218) (xy 172.72127 -249.775218) (xy 172.72127 -250.295156) (xy 171.22267 -250.295156)
			)
		)
	)
	(zone
		(layer "In2.Cu")
		(hatch none 0.5)
		(connect_pads
			(clearance 0)
		)
		(min_thickness 0.25)
		(keepout
			(tracks not_allowed)
			(vias allowed)
			(pads allowed)
			(copperpour not_allowed)
			(footprints allowed)
		)
		(placement
			(enabled no)
			(sheetname "")
		)
		(fill
			(thermal_gap 0.5)
			(thermal_bridge_width 0.5)
			(island_removal_mode 0)
		)
		(polygon
			(pts
				(xy 438.350914 -210.67522) (xy 439.849514 -210.67522) (xy 439.849514 -211.195158) (xy 438.350914 -211.195158)
			)
		)
	)
	(zone
		(layer "In2.Cu")
		(hatch none 0.5)
		(connect_pads
			(clearance 0)
		)
		(min_thickness 0.25)
		(keepout
			(tracks not_allowed)
			(vias allowed)
			(pads allowed)
			(copperpour not_allowed)
			(footprints allowed)
		)
		(placement
			(enabled no)
			(sheetname "")
		)
		(fill
			(thermal_gap 0.5)
			(thermal_bridge_width 0.5)
			(island_removal_mode 0)
		)
		(polygon
			(pts
				(xy 430.80686 -215.775286) (xy 432.30546 -215.775286) (xy 432.30546 -216.295224) (xy 430.80686 -216.295224)
			)
		)
	)
	(zone
		(layer "In2.Cu")
		(hatch none 0.5)
		(connect_pads
			(clearance 0)
		)
		(min_thickness 0.25)
		(keepout
			(tracks not_allowed)
			(vias allowed)
			(pads allowed)
			(copperpour not_allowed)
			(footprints allowed)
		)
		(placement
			(enabled no)
			(sheetname "")
		)
		(fill
			(thermal_gap 0.5)
			(thermal_bridge_width 0.5)
			(island_removal_mode 0)
		)
		(polygon
			(pts
				(xy 423.262806 -220.025214) (xy 424.761406 -220.025214) (xy 424.761406 -220.545152) (xy 423.262806 -220.545152)
			)
		)
	)
	(zone
		(layer "In2.Cu")
		(hatch none 0.5)
		(connect_pads
			(clearance 0)
		)
		(min_thickness 0.25)
		(keepout
			(tracks not_allowed)
			(vias allowed)
			(pads allowed)
			(copperpour not_allowed)
			(footprints allowed)
		)
		(placement
			(enabled no)
			(sheetname "")
		)
		(fill
			(thermal_gap 0.5)
			(thermal_bridge_width 0.5)
			(island_removal_mode 0)
		)
		(polygon
			(pts
				(xy 279.886664 -263.37514) (xy 281.385264 -263.37514) (xy 281.385264 -263.895078) (xy 279.886664 -263.895078)
			)
		)
	)
	(zone
		(layer "In2.Cu")
		(hatch none 0.5)
		(connect_pads
			(clearance 0)
		)
		(min_thickness 0.25)
		(keepout
			(tracks not_allowed)
			(vias allowed)
			(pads allowed)
			(copperpour not_allowed)
			(footprints allowed)
		)
		(placement
			(enabled no)
			(sheetname "")
		)
		(fill
			(thermal_gap 0.5)
			(thermal_bridge_width 0.5)
			(island_removal_mode 0)
		)
		(polygon
			(pts
				(xy 411.618684 -311.825132) (xy 413.117284 -311.825132) (xy 413.117284 -312.34507) (xy 411.618684 -312.34507)
			)
		)
	)
	(zone
		(layer "In2.Cu")
		(hatch none 0.5)
		(connect_pads
			(clearance 0)
		)
		(min_thickness 0.25)
		(keepout
			(tracks not_allowed)
			(vias allowed)
			(pads allowed)
			(copperpour not_allowed)
			(footprints allowed)
		)
		(placement
			(enabled no)
			(sheetname "")
		)
		(fill
			(thermal_gap 0.5)
			(thermal_bridge_width 0.5)
			(island_removal_mode 0)
		)
		(polygon
			(pts
				(xy 125.77826 -33.001204)
				(arc
					(start 125.918468 -33.001204)
					(mid 125.98835 -32.971995)
					(end 126.01702 -32.90189)
				)
				(arc
					(start 126.01702 -32.600646)
					(mid 125.98835 -32.530541)
					(end 125.918468 -32.501332)
				)
				(xy 125.77826 -32.501332) (xy 125.77826 -32.561276)
				(arc
					(start 125.209046 -32.561276)
					(mid 125.172677 -32.517777)
					(end 125.118368 -32.501332)
				)
				(arc
					(start 124.858272 -32.501332)
					(mid 124.80388 -32.517651)
					(end 124.767594 -32.561276)
				)
				(xy 124.19838 -32.561276) (xy 124.19838 -32.501332)
				(arc
					(start 124.058172 -32.501332)
					(mid 123.98829 -32.530541)
					(end 123.95962 -32.600646)
				)
				(arc
					(start 123.95962 -32.90189)
					(mid 123.98829 -32.971995)
					(end 124.058172 -33.001204)
				)
				(xy 124.19838 -33.001204) (xy 124.19838 -32.94126)
				(arc
					(start 124.767594 -32.94126)
					(mid 124.803963 -32.984759)
					(end 124.858272 -33.001204)
				)
				(arc
					(start 125.118368 -33.001204)
					(mid 125.17276 -32.984885)
					(end 125.209046 -32.94126)
				)
				(xy 125.77826 -32.94126)
			)
		)
	)
	(zone
		(layer "In2.Cu")
		(hatch none 0.5)
		(connect_pads
			(clearance 0)
		)
		(min_thickness 0.25)
		(keepout
			(tracks not_allowed)
			(vias allowed)
			(pads allowed)
			(copperpour not_allowed)
			(footprints allowed)
		)
		(placement
			(enabled no)
			(sheetname "")
		)
		(fill
			(thermal_gap 0.5)
			(thermal_bridge_width 0.5)
			(island_removal_mode 0)
		)
		(polygon
			(pts
				(arc
					(start 320.204846 -381.824484)
					(mid 320.22477 -381.83372)
					(end 320.246502 -381.83693)
				)
				(arc
					(start 320.441066 -381.83693)
					(mid 320.494948 -381.814612)
					(end 320.517266 -381.76073)
				)
				(arc
					(start 320.517266 -381.07493)
					(mid 320.494948 -381.021048)
					(end 320.441066 -380.99873)
				)
				(arc
					(start 320.246502 -380.99873)
					(mid 320.224758 -381.001898)
					(end 320.204846 -381.011176)
				)
				(arc
					(start 319.908682 -381.203962)
					(mid 319.866998 -381.216184)
					(end 319.82537 -381.203708)
				)
				(arc
					(start 319.531746 -381.011176)
					(mid 319.511822 -381.00194)
					(end 319.49009 -380.99873)
				)
				(arc
					(start 319.295526 -380.99873)
					(mid 319.241644 -381.021048)
					(end 319.219326 -381.07493)
				)
				(arc
					(start 319.219326 -381.76073)
					(mid 319.241644 -381.814612)
					(end 319.295526 -381.83693)
				)
				(arc
					(start 319.49136 -381.83693)
					(mid 319.513104 -381.833762)
					(end 319.533016 -381.824484)
				)
				(arc
					(start 319.82664 -381.631952)
					(mid 319.868296 -381.61955)
					(end 319.909952 -381.631952)
				)
			)
		)
	)
	(zone
		(layer "In2.Cu")
		(hatch none 0.5)
		(connect_pads
			(clearance 0)
		)
		(min_thickness 0.25)
		(keepout
			(tracks not_allowed)
			(vias allowed)
			(pads allowed)
			(copperpour not_allowed)
			(footprints allowed)
		)
		(placement
			(enabled no)
			(sheetname "")
		)
		(fill
			(thermal_gap 0.5)
			(thermal_bridge_width 0.5)
			(island_removal_mode 0)
		)
		(polygon
			(pts
				(xy 445.894968 -210.67522) (xy 447.393568 -210.67522) (xy 447.393568 -211.195158) (xy 445.894968 -211.195158)
			)
		)
	)
	(zone
		(layer "In2.Cu")
		(hatch none 0.5)
		(connect_pads
			(clearance 0)
		)
		(min_thickness 0.25)
		(keepout
			(tracks not_allowed)
			(vias allowed)
			(pads allowed)
			(copperpour not_allowed)
			(footprints allowed)
		)
		(placement
			(enabled no)
			(sheetname "")
		)
		(fill
			(thermal_gap 0.5)
			(thermal_bridge_width 0.5)
			(island_removal_mode 0)
		)
		(polygon
			(pts
				(xy 201.398632 -295.675304) (xy 202.897232 -295.675304) (xy 202.897232 -296.195242) (xy 201.398632 -296.195242)
			)
		)
	)
	(zone
		(layer "In2.Cu")
		(hatch none 0.5)
		(connect_pads
			(clearance 0)
		)
		(min_thickness 0.25)
		(keepout
			(tracks not_allowed)
			(vias allowed)
			(pads allowed)
			(copperpour not_allowed)
			(footprints allowed)
		)
		(placement
			(enabled no)
			(sheetname "")
		)
		(fill
			(thermal_gap 0.5)
			(thermal_bridge_width 0.5)
			(island_removal_mode 0)
		)
		(polygon
			(pts
				(xy 283.986732 -260.825234) (xy 285.485332 -260.825234) (xy 285.485332 -261.345172) (xy 283.986732 -261.345172)
			)
		)
	)
	(zone
		(layer "In2.Cu")
		(hatch none 0.5)
		(connect_pads
			(clearance 0)
		)
		(min_thickness 0.25)
		(keepout
			(tracks not_allowed)
			(vias allowed)
			(pads allowed)
			(copperpour not_allowed)
			(footprints allowed)
		)
		(placement
			(enabled no)
			(sheetname "")
		)
		(fill
			(thermal_gap 0.5)
			(thermal_bridge_width 0.5)
			(island_removal_mode 0)
		)
		(polygon
			(pts
				(xy 36.046664 -203.025248) (xy 37.545264 -203.025248) (xy 37.545264 -203.545186) (xy 36.046664 -203.545186)
			)
		)
	)
	(zone
		(layer "In2.Cu")
		(hatch none 0.5)
		(connect_pads
			(clearance 0)
		)
		(min_thickness 0.25)
		(keepout
			(tracks not_allowed)
			(vias allowed)
			(pads allowed)
			(copperpour not_allowed)
			(footprints allowed)
		)
		(placement
			(enabled no)
			(sheetname "")
		)
		(fill
			(thermal_gap 0.5)
			(thermal_bridge_width 0.5)
			(island_removal_mode 0)
		)
		(polygon
			(pts
				(xy 423.262806 -200.475342) (xy 424.761406 -200.475342) (xy 424.761406 -200.99528) (xy 423.262806 -200.99528)
			)
		)
	)
	(zone
		(layer "In2.Cu")
		(hatch none 0.5)
		(connect_pads
			(clearance 0)
		)
		(min_thickness 0.25)
		(keepout
			(tracks not_allowed)
			(vias allowed)
			(pads allowed)
			(copperpour not_allowed)
			(footprints allowed)
		)
		(placement
			(enabled no)
			(sheetname "")
		)
		(fill
			(thermal_gap 0.5)
			(thermal_bridge_width 0.5)
			(island_removal_mode 0)
		)
		(polygon
			(pts
				(xy 430.80686 -232.775252) (xy 432.30546 -232.775252) (xy 432.30546 -233.29519) (xy 430.80686 -233.29519)
			)
		)
	)
	(zone
		(layer "In2.Cu")
		(hatch none 0.5)
		(connect_pads
			(clearance 0)
		)
		(min_thickness 0.25)
		(keepout
			(tracks not_allowed)
			(vias allowed)
			(pads allowed)
			(copperpour not_allowed)
			(footprints allowed)
		)
		(placement
			(enabled no)
			(sheetname "")
		)
		(fill
			(thermal_gap 0.5)
			(thermal_bridge_width 0.5)
			(island_removal_mode 0)
		)
		(polygon
			(pts
				(xy 453.438768 -305.875182) (xy 454.937368 -305.875182) (xy 454.937368 -306.39512) (xy 453.438768 -306.39512)
			)
		)
	)
	(zone
		(layer "In2.Cu")
		(hatch none 0.5)
		(connect_pads
			(clearance 0)
		)
		(min_thickness 0.25)
		(keepout
			(tracks not_allowed)
			(vias allowed)
			(pads allowed)
			(copperpour not_allowed)
			(footprints allowed)
		)
		(placement
			(enabled no)
			(sheetname "")
		)
		(fill
			(thermal_gap 0.5)
			(thermal_bridge_width 0.5)
			(island_removal_mode 0)
		)
		(polygon
			(pts
				(arc
					(start 416.86226 -7.672324)
					(mid 416.884578 -7.618442)
					(end 416.93846 -7.596124)
				)
				(arc
					(start 417.975034 -7.596124)
					(mid 418.028916 -7.618442)
					(end 418.051234 -7.672324)
				)
				(arc
					(start 418.051234 -9.071864)
					(mid 418.028916 -9.125746)
					(end 417.975034 -9.148064)
				)
				(arc
					(start 416.93846 -9.148064)
					(mid 416.884578 -9.125746)
					(end 416.86226 -9.071864)
				)
			)
		)
	)
	(zone
		(layer "In2.Cu")
		(hatch none 0.5)
		(connect_pads
			(clearance 0)
		)
		(min_thickness 0.25)
		(keepout
			(tracks allowed)
			(vias allowed)
			(pads allowed)
			(copperpour allowed)
			(footprints allowed)
		)
		(placement
			(enabled no)
			(sheetname "")
		)
		(fill
			(thermal_gap 0.5)
			(thermal_bridge_width 0.5)
			(island_removal_mode 0)
		)
		(polygon
			(pts
				(xy 101.51872 -180.09616) (xy 101.51872 -179.549806) (xy 102.07117 -179.549806) (xy 102.07117 -180.09616)
			)
		)
	)
	(zone
		(layer "In2.Cu")
		(hatch none 0.5)
		(connect_pads
			(clearance 0)
		)
		(min_thickness 0.25)
		(keepout
			(tracks not_allowed)
			(vias allowed)
			(pads allowed)
			(copperpour not_allowed)
			(footprints allowed)
		)
		(placement
			(enabled no)
			(sheetname "")
		)
		(fill
			(thermal_gap 0.5)
			(thermal_bridge_width 0.5)
			(island_removal_mode 0)
		)
		(polygon
			(pts
				(xy 28.50261 -298.22521) (xy 30.00121 -298.22521) (xy 30.00121 -298.745148) (xy 28.50261 -298.745148)
			)
		)
	)
	(zone
		(layer "In2.Cu")
		(hatch none 0.5)
		(connect_pads
			(clearance 0)
		)
		(min_thickness 0.25)
		(keepout
			(tracks not_allowed)
			(vias allowed)
			(pads allowed)
			(copperpour not_allowed)
			(footprints allowed)
		)
		(placement
			(enabled no)
			(sheetname "")
		)
		(fill
			(thermal_gap 0.5)
			(thermal_bridge_width 0.5)
			(island_removal_mode 0)
		)
		(polygon
			(pts
				(xy 171.22267 -317.775336) (xy 172.72127 -317.775336) (xy 172.72127 -318.295274) (xy 171.22267 -318.295274)
			)
		)
	)
	(zone
		(layer "In2.Cu")
		(hatch none 0.5)
		(connect_pads
			(clearance 0)
		)
		(min_thickness 0.25)
		(keepout
			(tracks not_allowed)
			(vias allowed)
			(pads allowed)
			(copperpour not_allowed)
			(footprints allowed)
		)
		(placement
			(enabled no)
			(sheetname "")
		)
		(fill
			(thermal_gap 0.5)
			(thermal_bridge_width 0.5)
			(island_removal_mode 0)
		)
		(polygon
			(pts
				(xy 294.974772 -289.725354) (xy 296.473372 -289.725354) (xy 296.473372 -290.245292) (xy 294.974772 -290.245292)
			)
		)
	)
	(zone
		(layer "In2.Cu")
		(hatch none 0.5)
		(connect_pads
			(clearance 0)
		)
		(min_thickness 0.25)
		(keepout
			(tracks not_allowed)
			(vias allowed)
			(pads allowed)
			(copperpour not_allowed)
			(footprints allowed)
		)
		(placement
			(enabled no)
			(sheetname "")
		)
		(fill
			(thermal_gap 0.5)
			(thermal_bridge_width 0.5)
			(island_removal_mode 0)
		)
		(polygon
			(pts
				(xy 283.986732 -214.075264) (xy 285.485332 -214.075264) (xy 285.485332 -214.595202) (xy 283.986732 -214.595202)
			)
		)
	)
	(zone
		(layer "In2.Cu")
		(hatch none 0.5)
		(connect_pads
			(clearance 0)
		)
		(min_thickness 0.25)
		(keepout
			(tracks allowed)
			(vias allowed)
			(pads allowed)
			(copperpour allowed)
			(footprints allowed)
		)
		(placement
			(enabled no)
			(sheetname "")
		)
		(fill
			(thermal_gap 0.5)
			(thermal_bridge_width 0.5)
			(island_removal_mode 0)
		)
		(polygon
			(pts
				(xy 172.202094 -332.759812) (xy 171.897294 -332.759812) (xy 171.567094 -333.090012) (xy 171.567094 -343.834212)
				(xy 177.180494 -349.447612) (xy 177.180494 -353.054412) (xy 175.580294 -354.654612) (xy 175.580294 -361.461812)
				(xy 181.396894 -367.278412) (xy 196.636894 -367.278412) (xy 199.888094 -364.027212) (xy 199.888094 -363.239812)
				(xy 199.634094 -363.239812) (xy 196.357494 -366.516412) (xy 181.676294 -366.516412) (xy 176.316894 -361.157012)
				(xy 176.316894 -355.061012) (xy 177.993294 -353.384612) (xy 177.993294 -349.092012) (xy 172.354494 -343.453212)
				(xy 172.354494 -332.912212)
			)
		)
	)
	(zone
		(layer "In2.Cu")
		(hatch none 0.5)
		(connect_pads
			(clearance 0)
		)
		(min_thickness 0.25)
		(keepout
			(tracks not_allowed)
			(vias allowed)
			(pads allowed)
			(copperpour not_allowed)
			(footprints allowed)
		)
		(placement
			(enabled no)
			(sheetname "")
		)
		(fill
			(thermal_gap 0.5)
			(thermal_bridge_width 0.5)
			(island_removal_mode 0)
		)
		(polygon
			(pts
				(xy 430.80686 -228.525324) (xy 432.30546 -228.525324) (xy 432.30546 -229.045262) (xy 430.80686 -229.045262)
			)
		)
	)
	(zone
		(layer "In2.Cu")
		(hatch none 0.5)
		(connect_pads
			(clearance 0)
		)
		(min_thickness 0.25)
		(keepout
			(tracks not_allowed)
			(vias allowed)
			(pads allowed)
			(copperpour not_allowed)
			(footprints allowed)
		)
		(placement
			(enabled no)
			(sheetname "")
		)
		(fill
			(thermal_gap 0.5)
			(thermal_bridge_width 0.5)
			(island_removal_mode 0)
		)
		(polygon
			(pts
				(xy 423.262806 -279.525222) (xy 424.761406 -279.525222) (xy 424.761406 -280.04516) (xy 423.262806 -280.04516)
			)
		)
	)
	(zone
		(layer "In2.Cu")
		(hatch none 0.5)
		(connect_pads
			(clearance 0)
		)
		(min_thickness 0.25)
		(keepout
			(tracks allowed)
			(vias allowed)
			(pads allowed)
			(copperpour allowed)
			(footprints allowed)
		)
		(placement
			(enabled no)
			(sheetname "")
		)
		(fill
			(thermal_gap 0.5)
			(thermal_bridge_width 0.5)
			(island_removal_mode 0)
		)
		(polygon
			(pts
				(xy 319.77457 -338.869782) (xy 319.77457 -338.247482) (xy 320.32575 -338.247482) (xy 320.32575 -338.869782)
			)
		)
	)
	(zone
		(layer "In2.Cu")
		(hatch none 0.5)
		(connect_pads
			(clearance 0)
		)
		(min_thickness 0.25)
		(keepout
			(tracks not_allowed)
			(vias allowed)
			(pads allowed)
			(copperpour not_allowed)
			(footprints allowed)
		)
		(placement
			(enabled no)
			(sheetname "")
		)
		(fill
			(thermal_gap 0.5)
			(thermal_bridge_width 0.5)
			(island_removal_mode 0)
		)
		(polygon
			(pts
				(xy 411.618684 -227.675186) (xy 413.117284 -227.675186) (xy 413.117284 -228.195124) (xy 411.618684 -228.195124)
			)
		)
	)
	(zone
		(layer "In2.Cu")
		(hatch none 0.5)
		(connect_pads
			(clearance 0)
		)
		(min_thickness 0.25)
		(keepout
			(tracks not_allowed)
			(vias allowed)
			(pads allowed)
			(copperpour not_allowed)
			(footprints allowed)
		)
		(placement
			(enabled no)
			(sheetname "")
		)
		(fill
			(thermal_gap 0.5)
			(thermal_bridge_width 0.5)
			(island_removal_mode 0)
		)
		(polygon
			(pts
				(xy 291.530786 -252.325124) (xy 293.029386 -252.325124) (xy 293.029386 -252.845062) (xy 291.530786 -252.845062)
			)
		)
	)
	(zone
		(layer "In2.Cu")
		(hatch none 0.5)
		(connect_pads
			(clearance 0)
		)
		(min_thickness 0.25)
		(keepout
			(tracks not_allowed)
			(vias allowed)
			(pads allowed)
			(copperpour not_allowed)
			(footprints allowed)
		)
		(placement
			(enabled no)
			(sheetname "")
		)
		(fill
			(thermal_gap 0.5)
			(thermal_bridge_width 0.5)
			(island_removal_mode 0)
		)
		(polygon
			(pts
				(xy 411.618684 -244.675152) (xy 413.117284 -244.675152) (xy 413.117284 -245.19509) (xy 411.618684 -245.19509)
			)
		)
	)
	(zone
		(layer "In2.Cu")
		(hatch none 0.5)
		(connect_pads
			(clearance 0)
		)
		(min_thickness 0.25)
		(keepout
			(tracks not_allowed)
			(vias allowed)
			(pads allowed)
			(copperpour not_allowed)
			(footprints allowed)
		)
		(placement
			(enabled no)
			(sheetname "")
		)
		(fill
			(thermal_gap 0.5)
			(thermal_bridge_width 0.5)
			(island_removal_mode 0)
		)
		(polygon
			(pts
				(xy 426.706792 -229.375208) (xy 428.205392 -229.375208) (xy 428.205392 -229.895146) (xy 426.706792 -229.895146)
			)
		)
	)
	(zone
		(layer "In2.Cu")
		(hatch none 0.5)
		(connect_pads
			(clearance 0)
		)
		(min_thickness 0.25)
		(keepout
			(tracks not_allowed)
			(vias allowed)
			(pads allowed)
			(copperpour not_allowed)
			(footprints allowed)
		)
		(placement
			(enabled no)
			(sheetname "")
		)
		(fill
			(thermal_gap 0.5)
			(thermal_bridge_width 0.5)
			(island_removal_mode 0)
		)
		(polygon
			(pts
				(xy 306.618894 -276.125178) (xy 308.117494 -276.125178) (xy 308.117494 -276.645116) (xy 306.618894 -276.645116)
			)
		)
	)
	(zone
		(layer "In2.Cu")
		(hatch none 0.5)
		(connect_pads
			(clearance 0)
		)
		(min_thickness 0.25)
		(keepout
			(tracks not_allowed)
			(vias allowed)
			(pads allowed)
			(copperpour not_allowed)
			(footprints allowed)
		)
		(placement
			(enabled no)
			(sheetname "")
		)
		(fill
			(thermal_gap 0.5)
			(thermal_bridge_width 0.5)
			(island_removal_mode 0)
		)
		(polygon
			(pts
				(xy 299.07484 -245.52529) (xy 300.57344 -245.52529) (xy 300.57344 -246.045228) (xy 299.07484 -246.045228)
			)
		)
	)
	(zone
		(layer "In2.Cu")
		(hatch none 0.5)
		(connect_pads
			(clearance 0)
		)
		(min_thickness 0.25)
		(keepout
			(tracks not_allowed)
			(vias allowed)
			(pads allowed)
			(copperpour not_allowed)
			(footprints allowed)
		)
		(placement
			(enabled no)
			(sheetname "")
		)
		(fill
			(thermal_gap 0.5)
			(thermal_bridge_width 0.5)
			(island_removal_mode 0)
		)
		(polygon
			(pts
				(xy 193.854578 -300.775116) (xy 195.353178 -300.775116) (xy 195.353178 -301.295054) (xy 193.854578 -301.295054)
			)
		)
	)
	(zone
		(layer "In2.Cu")
		(hatch none 0.5)
		(connect_pads
			(clearance 0)
		)
		(min_thickness 0.25)
		(keepout
			(tracks not_allowed)
			(vias allowed)
			(pads allowed)
			(copperpour not_allowed)
			(footprints allowed)
		)
		(placement
			(enabled no)
			(sheetname "")
		)
		(fill
			(thermal_gap 0.5)
			(thermal_bridge_width 0.5)
			(island_removal_mode 0)
		)
		(polygon
			(pts
				(xy 28.50261 -240.425224) (xy 30.00121 -240.425224) (xy 30.00121 -240.945162) (xy 28.50261 -240.945162)
			)
		)
	)
	(zone
		(layer "In2.Cu")
		(hatch none 0.5)
		(connect_pads
			(clearance 0)
		)
		(min_thickness 0.25)
		(keepout
			(tracks not_allowed)
			(vias allowed)
			(pads allowed)
			(copperpour not_allowed)
			(footprints allowed)
		)
		(placement
			(enabled no)
			(sheetname "")
		)
		(fill
			(thermal_gap 0.5)
			(thermal_bridge_width 0.5)
			(island_removal_mode 0)
		)
		(polygon
			(pts
				(xy 268.898878 -262.525256) (xy 270.397478 -262.525256) (xy 270.397478 -263.045194) (xy 268.898878 -263.045194)
			)
		)
	)
	(zone
		(layer "In2.Cu")
		(hatch none 0.5)
		(connect_pads
			(clearance 0)
		)
		(min_thickness 0.25)
		(keepout
			(tracks not_allowed)
			(vias allowed)
			(pads allowed)
			(copperpour not_allowed)
			(footprints allowed)
		)
		(placement
			(enabled no)
			(sheetname "")
		)
		(fill
			(thermal_gap 0.5)
			(thermal_bridge_width 0.5)
			(island_removal_mode 0)
		)
		(polygon
			(pts
				(xy 411.618684 -224.275142) (xy 413.117284 -224.275142) (xy 413.117284 -224.79508) (xy 411.618684 -224.79508)
			)
		)
	)
	(zone
		(layer "In2.Cu")
		(hatch none 0.5)
		(connect_pads
			(clearance 0)
		)
		(min_thickness 0.25)
		(keepout
			(tracks not_allowed)
			(vias allowed)
			(pads allowed)
			(copperpour not_allowed)
			(footprints allowed)
		)
		(placement
			(enabled no)
			(sheetname "")
		)
		(fill
			(thermal_gap 0.5)
			(thermal_bridge_width 0.5)
			(island_removal_mode 0)
		)
		(polygon
			(pts
				(xy 197.954646 -215.775286) (xy 199.453246 -215.775286) (xy 199.453246 -216.295224) (xy 197.954646 -216.295224)
			)
		)
	)
	(zone
		(layer "In2.Cu")
		(hatch none 0.5)
		(connect_pads
			(clearance 0)
		)
		(min_thickness 0.25)
		(keepout
			(tracks not_allowed)
			(vias allowed)
			(pads allowed)
			(copperpour not_allowed)
			(footprints allowed)
		)
		(placement
			(enabled no)
			(sheetname "")
		)
		(fill
			(thermal_gap 0.5)
			(thermal_bridge_width 0.5)
			(island_removal_mode 0)
		)
		(polygon
			(pts
				(xy 197.954646 -273.575272) (xy 199.453246 -273.575272) (xy 199.453246 -274.09521) (xy 197.954646 -274.09521)
			)
		)
	)
	(zone
		(layer "In2.Cu")
		(hatch none 0.5)
		(connect_pads
			(clearance 0)
		)
		(min_thickness 0.25)
		(keepout
			(tracks not_allowed)
			(vias allowed)
			(pads allowed)
			(copperpour not_allowed)
			(footprints allowed)
		)
		(placement
			(enabled no)
			(sheetname "")
		)
		(fill
			(thermal_gap 0.5)
			(thermal_bridge_width 0.5)
			(island_removal_mode 0)
		)
		(polygon
			(pts
				(xy 171.22267 -261.675118) (xy 172.72127 -261.675118) (xy 172.72127 -262.195056) (xy 171.22267 -262.195056)
			)
		)
	)
	(zone
		(layer "In2.Cu")
		(hatch none 0.5)
		(connect_pads
			(clearance 0)
		)
		(min_thickness 0.25)
		(keepout
			(tracks not_allowed)
			(vias allowed)
			(pads allowed)
			(copperpour not_allowed)
			(footprints allowed)
		)
		(placement
			(enabled no)
			(sheetname "")
		)
		(fill
			(thermal_gap 0.5)
			(thermal_bridge_width 0.5)
			(island_removal_mode 0)
		)
		(polygon
			(pts
				(xy 268.898878 -316.925198) (xy 270.397478 -316.925198) (xy 270.397478 -317.445136) (xy 268.898878 -317.445136)
			)
		)
	)
	(zone
		(layer "In2.Cu")
		(hatch none 0.5)
		(connect_pads
			(clearance 0)
		)
		(min_thickness 0.25)
		(keepout
			(tracks not_allowed)
			(vias allowed)
			(pads allowed)
			(copperpour not_allowed)
			(footprints allowed)
		)
		(placement
			(enabled no)
			(sheetname "")
		)
		(fill
			(thermal_gap 0.5)
			(thermal_bridge_width 0.5)
			(island_removal_mode 0)
		)
		(polygon
			(pts
				(xy 193.854578 -239.57534) (xy 195.353178 -239.57534) (xy 195.353178 -240.095278) (xy 193.854578 -240.095278)
			)
		)
	)
	(zone
		(layer "In2.Cu")
		(hatch none 0.5)
		(connect_pads
			(clearance 0)
		)
		(min_thickness 0.25)
		(keepout
			(tracks not_allowed)
			(vias allowed)
			(pads allowed)
			(copperpour not_allowed)
			(footprints allowed)
		)
		(placement
			(enabled no)
			(sheetname "")
		)
		(fill
			(thermal_gap 0.5)
			(thermal_bridge_width 0.5)
			(island_removal_mode 0)
		)
		(polygon
			(pts
				(xy 294.974772 -302.475138) (xy 296.473372 -302.475138) (xy 296.473372 -302.995076) (xy 294.974772 -302.995076)
			)
		)
	)
	(zone
		(layer "In2.Cu")
		(hatch none 0.5)
		(connect_pads
			(clearance 0)
		)
		(min_thickness 0.25)
		(keepout
			(tracks not_allowed)
			(vias allowed)
			(pads allowed)
			(copperpour not_allowed)
			(footprints allowed)
		)
		(placement
			(enabled no)
			(sheetname "")
		)
		(fill
			(thermal_gap 0.5)
			(thermal_bridge_width 0.5)
			(island_removal_mode 0)
		)
		(polygon
			(pts
				(xy 430.80686 -313.525154) (xy 432.30546 -313.525154) (xy 432.30546 -314.045092) (xy 430.80686 -314.045092)
			)
		)
	)
	(zone
		(layer "In2.Cu")
		(hatch none 0.5)
		(connect_pads
			(clearance 0)
		)
		(min_thickness 0.25)
		(keepout
			(tracks not_allowed)
			(vias allowed)
			(pads allowed)
			(copperpour not_allowed)
			(footprints allowed)
		)
		(placement
			(enabled no)
			(sheetname "")
		)
		(fill
			(thermal_gap 0.5)
			(thermal_bridge_width 0.5)
			(island_removal_mode 0)
		)
		(polygon
			(pts
				(xy 31.946596 -263.37514) (xy 33.445196 -263.37514) (xy 33.445196 -263.895078) (xy 31.946596 -263.895078)
			)
		)
	)
	(zone
		(layer "In2.Cu")
		(hatch none 0.5)
		(connect_pads
			(clearance 0)
		)
		(min_thickness 0.25)
		(keepout
			(tracks not_allowed)
			(vias allowed)
			(pads allowed)
			(copperpour not_allowed)
			(footprints allowed)
		)
		(placement
			(enabled no)
			(sheetname "")
		)
		(fill
			(thermal_gap 0.5)
			(thermal_bridge_width 0.5)
			(island_removal_mode 0)
		)
		(polygon
			(pts
				(xy 197.954646 -313.525154) (xy 199.453246 -313.525154) (xy 199.453246 -314.045092) (xy 197.954646 -314.045092)
			)
		)
	)
	(zone
		(layer "In2.Cu")
		(hatch none 0.5)
		(connect_pads
			(clearance 0)
		)
		(min_thickness 0.25)
		(keepout
			(tracks not_allowed)
			(vias allowed)
			(pads allowed)
			(copperpour not_allowed)
			(footprints allowed)
		)
		(placement
			(enabled no)
			(sheetname "")
		)
		(fill
			(thermal_gap 0.5)
			(thermal_bridge_width 0.5)
			(island_removal_mode 0)
		)
		(polygon
			(pts
				(xy 201.398632 -207.275176) (xy 202.897232 -207.275176) (xy 202.897232 -207.795114) (xy 201.398632 -207.795114)
			)
		)
	)
	(zone
		(layer "In2.Cu")
		(hatch none 0.5)
		(connect_pads
			(clearance 0)
		)
		(min_thickness 0.25)
		(keepout
			(tracks not_allowed)
			(vias allowed)
			(pads allowed)
			(copperpour not_allowed)
			(footprints allowed)
		)
		(placement
			(enabled no)
			(sheetname "")
		)
		(fill
			(thermal_gap 0.5)
			(thermal_bridge_width 0.5)
			(island_removal_mode 0)
		)
		(polygon
			(pts
				(xy 24.402542 -286.32531) (xy 25.901142 -286.32531) (xy 25.901142 -286.845248) (xy 24.402542 -286.845248)
			)
		)
	)
	(zone
		(layer "In2.Cu")
		(hatch none 0.5)
		(connect_pads
			(clearance 0)
		)
		(min_thickness 0.25)
		(keepout
			(tracks not_allowed)
			(vias allowed)
			(pads allowed)
			(copperpour not_allowed)
			(footprints allowed)
		)
		(placement
			(enabled no)
			(sheetname "")
		)
		(fill
			(thermal_gap 0.5)
			(thermal_bridge_width 0.5)
			(island_removal_mode 0)
		)
		(polygon
			(pts
				(xy 24.402542 -249.775218) (xy 25.901142 -249.775218) (xy 25.901142 -250.295156) (xy 24.402542 -250.295156)
			)
		)
	)
	(zone
		(layer "In2.Cu")
		(hatch none 0.5)
		(connect_pads
			(clearance 0)
		)
		(min_thickness 0.25)
		(keepout
			(tracks not_allowed)
			(vias allowed)
			(pads allowed)
			(copperpour not_allowed)
			(footprints allowed)
		)
		(placement
			(enabled no)
			(sheetname "")
		)
		(fill
			(thermal_gap 0.5)
			(thermal_bridge_width 0.5)
			(island_removal_mode 0)
		)
		(polygon
			(pts
				(xy 306.618894 -269.325344) (xy 308.117494 -269.325344) (xy 308.117494 -269.845282) (xy 306.618894 -269.845282)
			)
		)
	)
	(zone
		(layer "In2.Cu")
		(hatch none 0.5)
		(connect_pads
			(clearance 0)
		)
		(min_thickness 0.25)
		(keepout
			(tracks not_allowed)
			(vias allowed)
			(pads allowed)
			(copperpour not_allowed)
			(footprints allowed)
		)
		(placement
			(enabled no)
			(sheetname "")
		)
		(fill
			(thermal_gap 0.5)
			(thermal_bridge_width 0.5)
			(island_removal_mode 0)
		)
		(polygon
			(pts
				(xy 291.530786 -209.825336) (xy 293.029386 -209.825336) (xy 293.029386 -210.345274) (xy 291.530786 -210.345274)
			)
		)
	)
	(zone
		(layer "In2.Cu")
		(hatch none 0.5)
		(connect_pads
			(clearance 0)
		)
		(min_thickness 0.25)
		(keepout
			(tracks not_allowed)
			(vias allowed)
			(pads allowed)
			(copperpour not_allowed)
			(footprints allowed)
		)
		(placement
			(enabled no)
			(sheetname "")
		)
		(fill
			(thermal_gap 0.5)
			(thermal_bridge_width 0.5)
			(island_removal_mode 0)
		)
		(polygon
			(pts
				(xy 58.678826 -312.67527) (xy 60.177426 -312.67527) (xy 60.177426 -313.195208) (xy 58.678826 -313.195208)
			)
		)
	)
	(zone
		(layer "In2.Cu")
		(hatch none 0.5)
		(connect_pads
			(clearance 0)
		)
		(min_thickness 0.25)
		(keepout
			(tracks not_allowed)
			(vias allowed)
			(pads allowed)
			(copperpour not_allowed)
			(footprints allowed)
		)
		(placement
			(enabled no)
			(sheetname "")
		)
		(fill
			(thermal_gap 0.5)
			(thermal_bridge_width 0.5)
			(island_removal_mode 0)
		)
		(polygon
			(pts
				(xy 426.706792 -248.075196) (xy 428.205392 -248.075196) (xy 428.205392 -248.595134) (xy 426.706792 -248.595134)
			)
		)
	)
	(zone
		(layer "In2.Cu")
		(hatch none 0.5)
		(connect_pads
			(clearance 0)
		)
		(min_thickness 0.25)
		(keepout
			(tracks not_allowed)
			(vias allowed)
			(pads allowed)
			(copperpour not_allowed)
			(footprints allowed)
		)
		(placement
			(enabled no)
			(sheetname "")
		)
		(fill
			(thermal_gap 0.5)
			(thermal_bridge_width 0.5)
			(island_removal_mode 0)
		)
		(polygon
			(pts
				(xy 28.50261 -312.67527) (xy 30.00121 -312.67527) (xy 30.00121 -313.195208) (xy 28.50261 -313.195208)
			)
		)
	)
	(zone
		(layer "In2.Cu")
		(hatch none 0.5)
		(connect_pads
			(clearance 0)
		)
		(min_thickness 0.25)
		(keepout
			(tracks not_allowed)
			(vias allowed)
			(pads allowed)
			(copperpour not_allowed)
			(footprints allowed)
		)
		(placement
			(enabled no)
			(sheetname "")
		)
		(fill
			(thermal_gap 0.5)
			(thermal_bridge_width 0.5)
			(island_removal_mode 0)
		)
		(polygon
			(pts
				(xy 31.946596 -300.775116) (xy 33.445196 -300.775116) (xy 33.445196 -301.295054) (xy 31.946596 -301.295054)
			)
		)
	)
	(zone
		(layer "In2.Cu")
		(hatch none 0.5)
		(connect_pads
			(clearance 0)
		)
		(min_thickness 0.25)
		(keepout
			(tracks not_allowed)
			(vias allowed)
			(pads allowed)
			(copperpour not_allowed)
			(footprints allowed)
		)
		(placement
			(enabled no)
			(sheetname "")
		)
		(fill
			(thermal_gap 0.5)
			(thermal_bridge_width 0.5)
			(island_removal_mode 0)
		)
		(polygon
			(pts
				(xy 167.778684 -304.17516) (xy 169.277284 -304.17516) (xy 169.277284 -304.695098) (xy 167.778684 -304.695098)
			)
		)
	)
	(zone
		(layer "In2.Cu")
		(hatch none 0.5)
		(connect_pads
			(clearance 0)
		)
		(min_thickness 0.25)
		(keepout
			(tracks not_allowed)
			(vias allowed)
			(pads allowed)
			(copperpour not_allowed)
			(footprints allowed)
		)
		(placement
			(enabled no)
			(sheetname "")
		)
		(fill
			(thermal_gap 0.5)
			(thermal_bridge_width 0.5)
			(island_removal_mode 0)
		)
		(polygon
			(pts
				(xy 453.438768 -254.025146) (xy 454.937368 -254.025146) (xy 454.937368 -254.545084) (xy 453.438768 -254.545084)
			)
		)
	)
	(zone
		(layer "In2.Cu")
		(hatch none 0.5)
		(connect_pads
			(clearance 0)
		)
		(min_thickness 0.25)
		(keepout
			(tracks not_allowed)
			(vias allowed)
			(pads allowed)
			(copperpour not_allowed)
			(footprints allowed)
		)
		(placement
			(enabled no)
			(sheetname "")
		)
		(fill
			(thermal_gap 0.5)
			(thermal_bridge_width 0.5)
			(island_removal_mode 0)
		)
		(polygon
			(pts
				(xy 415.718752 -231.07523) (xy 417.217352 -231.07523) (xy 417.217352 -231.595168) (xy 415.718752 -231.595168)
			)
		)
	)
	(zone
		(layer "In2.Cu")
		(hatch none 0.5)
		(connect_pads
			(clearance 0)
		)
		(min_thickness 0.25)
		(keepout
			(tracks not_allowed)
			(vias allowed)
			(pads allowed)
			(copperpour not_allowed)
			(footprints allowed)
		)
		(placement
			(enabled no)
			(sheetname "")
		)
		(fill
			(thermal_gap 0.5)
			(thermal_bridge_width 0.5)
			(island_removal_mode 0)
		)
		(polygon
			(pts
				(xy 193.854578 -304.17516) (xy 195.353178 -304.17516) (xy 195.353178 -304.695098) (xy 193.854578 -304.695098)
			)
		)
	)
	(zone
		(layer "In2.Cu")
		(hatch none 0.5)
		(connect_pads
			(clearance 0)
		)
		(min_thickness 0.25)
		(keepout
			(tracks not_allowed)
			(vias allowed)
			(pads allowed)
			(copperpour not_allowed)
			(footprints allowed)
		)
		(placement
			(enabled no)
			(sheetname "")
		)
		(fill
			(thermal_gap 0.5)
			(thermal_bridge_width 0.5)
			(island_removal_mode 0)
		)
		(polygon
			(pts
				(xy 306.618894 -310.975248) (xy 308.117494 -310.975248) (xy 308.117494 -311.495186) (xy 306.618894 -311.495186)
			)
		)
	)
	(zone
		(layer "In2.Cu")
		(hatch none 0.5)
		(connect_pads
			(clearance 0)
		)
		(min_thickness 0.25)
		(keepout
			(tracks not_allowed)
			(vias allowed)
			(pads allowed)
			(copperpour not_allowed)
			(footprints allowed)
		)
		(placement
			(enabled no)
			(sheetname "")
		)
		(fill
			(thermal_gap 0.5)
			(thermal_bridge_width 0.5)
			(island_removal_mode 0)
		)
		(polygon
			(pts
				(xy 434.250846 -246.375174) (xy 435.749446 -246.375174) (xy 435.749446 -246.895112) (xy 434.250846 -246.895112)
			)
		)
	)
	(zone
		(layer "In2.Cu")
		(hatch none 0.5)
		(connect_pads
			(clearance 0)
		)
		(min_thickness 0.25)
		(keepout
			(tracks not_allowed)
			(vias allowed)
			(pads allowed)
			(copperpour not_allowed)
			(footprints allowed)
		)
		(placement
			(enabled no)
			(sheetname "")
		)
		(fill
			(thermal_gap 0.5)
			(thermal_bridge_width 0.5)
			(island_removal_mode 0)
		)
		(polygon
			(pts
				(xy 426.706792 -310.12511) (xy 428.205392 -310.12511) (xy 428.205392 -310.645048) (xy 426.706792 -310.645048)
			)
		)
	)
	(zone
		(layer "In2.Cu")
		(hatch none 0.5)
		(connect_pads
			(clearance 0)
		)
		(min_thickness 0.25)
		(keepout
			(tracks not_allowed)
			(vias allowed)
			(pads allowed)
			(copperpour not_allowed)
			(footprints allowed)
		)
		(placement
			(enabled no)
			(sheetname "")
		)
		(fill
			(thermal_gap 0.5)
			(thermal_bridge_width 0.5)
			(island_removal_mode 0)
		)
		(polygon
			(pts
				(arc
					(start 299.783246 -381.824484)
					(mid 299.80317 -381.83372)
					(end 299.824902 -381.83693)
				)
				(arc
					(start 300.019466 -381.83693)
					(mid 300.073348 -381.814612)
					(end 300.095666 -381.76073)
				)
				(arc
					(start 300.095666 -381.07493)
					(mid 300.073348 -381.021048)
					(end 300.019466 -380.99873)
				)
				(arc
					(start 299.824902 -380.99873)
					(mid 299.803158 -381.001898)
					(end 299.783246 -381.011176)
				)
				(arc
					(start 299.487082 -381.203962)
					(mid 299.445398 -381.216184)
					(end 299.40377 -381.203708)
				)
				(arc
					(start 299.110146 -381.011176)
					(mid 299.090222 -381.00194)
					(end 299.06849 -380.99873)
				)
				(arc
					(start 298.873926 -380.99873)
					(mid 298.820044 -381.021048)
					(end 298.797726 -381.07493)
				)
				(arc
					(start 298.797726 -381.76073)
					(mid 298.820044 -381.814612)
					(end 298.873926 -381.83693)
				)
				(arc
					(start 299.06976 -381.83693)
					(mid 299.091504 -381.833762)
					(end 299.111416 -381.824484)
				)
				(arc
					(start 299.40504 -381.631952)
					(mid 299.446696 -381.61955)
					(end 299.488352 -381.631952)
				)
			)
		)
	)
	(zone
		(layer "In2.Cu")
		(hatch none 0.5)
		(connect_pads
			(clearance 0)
		)
		(min_thickness 0.25)
		(keepout
			(tracks not_allowed)
			(vias allowed)
			(pads allowed)
			(copperpour not_allowed)
			(footprints allowed)
		)
		(placement
			(enabled no)
			(sheetname "")
		)
		(fill
			(thermal_gap 0.5)
			(thermal_bridge_width 0.5)
			(island_removal_mode 0)
		)
		(polygon
			(pts
				(xy 423.262806 -197.075298) (xy 424.761406 -197.075298) (xy 424.761406 -197.595236) (xy 423.262806 -197.595236)
			)
		)
	)
	(zone
		(layer "In2.Cu")
		(hatch none 0.5)
		(connect_pads
			(clearance 0)
		)
		(min_thickness 0.25)
		(keepout
			(tracks allowed)
			(vias allowed)
			(pads allowed)
			(copperpour allowed)
			(footprints allowed)
		)
		(placement
			(enabled no)
			(sheetname "")
		)
		(fill
			(thermal_gap 0.5)
			(thermal_bridge_width 0.5)
			(island_removal_mode 0)
		)
		(polygon
			(pts
				(xy 391.438638 -178.284632) (xy 391.438638 -179.011072) (xy 391.253218 -179.011072) (xy 391.253218 -178.284632)
			)
		)
	)
	(zone
		(layer "In2.Cu")
		(hatch none 0.5)
		(connect_pads
			(clearance 0)
		)
		(min_thickness 0.25)
		(keepout
			(tracks not_allowed)
			(vias allowed)
			(pads allowed)
			(copperpour not_allowed)
			(footprints allowed)
		)
		(placement
			(enabled no)
			(sheetname "")
		)
		(fill
			(thermal_gap 0.5)
			(thermal_bridge_width 0.5)
			(island_removal_mode 0)
		)
		(polygon
			(pts
				(xy 163.678616 -313.525154) (xy 165.177216 -313.525154) (xy 165.177216 -314.045092) (xy 163.678616 -314.045092)
			)
		)
	)
	(zone
		(layer "In2.Cu")
		(hatch none 0.5)
		(connect_pads
			(clearance 0)
		)
		(min_thickness 0.25)
		(keepout
			(tracks not_allowed)
			(vias allowed)
			(pads allowed)
			(copperpour not_allowed)
			(footprints allowed)
		)
		(placement
			(enabled no)
			(sheetname "")
		)
		(fill
			(thermal_gap 0.5)
			(thermal_bridge_width 0.5)
			(island_removal_mode 0)
		)
		(polygon
			(pts
				(xy 438.350914 -214.075264) (xy 439.849514 -214.075264) (xy 439.849514 -214.595202) (xy 438.350914 -214.595202)
			)
		)
	)
	(zone
		(layer "In2.Cu")
		(hatch none 0.5)
		(connect_pads
			(clearance 0)
		)
		(min_thickness 0.25)
		(keepout
			(tracks not_allowed)
			(vias allowed)
			(pads allowed)
			(copperpour not_allowed)
			(footprints allowed)
		)
		(placement
			(enabled no)
			(sheetname "")
		)
		(fill
			(thermal_gap 0.5)
			(thermal_bridge_width 0.5)
			(island_removal_mode 0)
		)
		(polygon
			(pts
				(xy 268.898878 -287.175194) (xy 270.397478 -287.175194) (xy 270.397478 -287.695132) (xy 268.898878 -287.695132)
			)
		)
	)
	(zone
		(layer "In2.Cu")
		(hatch none 0.5)
		(connect_pads
			(clearance 0)
		)
		(min_thickness 0.25)
		(keepout
			(tracks not_allowed)
			(vias allowed)
			(pads allowed)
			(copperpour not_allowed)
			(footprints allowed)
		)
		(placement
			(enabled no)
			(sheetname "")
		)
		(fill
			(thermal_gap 0.5)
			(thermal_bridge_width 0.5)
			(island_removal_mode 0)
		)
		(polygon
			(pts
				(xy 423.262806 -214.075264) (xy 424.761406 -214.075264) (xy 424.761406 -214.595202) (xy 423.262806 -214.595202)
			)
		)
	)
	(zone
		(layer "In2.Cu")
		(hatch none 0.5)
		(connect_pads
			(clearance 0)
		)
		(min_thickness 0.25)
		(keepout
			(tracks not_allowed)
			(vias allowed)
			(pads allowed)
			(copperpour not_allowed)
			(footprints allowed)
		)
		(placement
			(enabled no)
			(sheetname "")
		)
		(fill
			(thermal_gap 0.5)
			(thermal_bridge_width 0.5)
			(island_removal_mode 0)
		)
		(polygon
			(pts
				(arc
					(start 52.961794 -11.91768)
					(mid 52.939476 -11.971562)
					(end 52.885594 -11.99388)
				)
				(arc
					(start 51.84902 -11.99388)
					(mid 51.795138 -11.971562)
					(end 51.77282 -11.91768)
				)
				(arc
					(start 51.77282 -10.51814)
					(mid 51.795138 -10.464258)
					(end 51.84902 -10.44194)
				)
				(arc
					(start 52.885594 -10.44194)
					(mid 52.939476 -10.464258)
					(end 52.961794 -10.51814)
				)
			)
		)
	)
	(zone
		(layer "In2.Cu")
		(hatch none 0.5)
		(connect_pads
			(clearance 0)
		)
		(min_thickness 0.25)
		(keepout
			(tracks not_allowed)
			(vias allowed)
			(pads allowed)
			(copperpour not_allowed)
			(footprints allowed)
		)
		(placement
			(enabled no)
			(sheetname "")
		)
		(fill
			(thermal_gap 0.5)
			(thermal_bridge_width 0.5)
			(island_removal_mode 0)
		)
		(polygon
			(pts
				(xy 411.618684 -283.77515) (xy 413.117284 -283.77515) (xy 413.117284 -284.295088) (xy 411.618684 -284.295088)
			)
		)
	)
	(zone
		(layer "In2.Cu")
		(hatch none 0.5)
		(connect_pads
			(clearance 0)
		)
		(min_thickness 0.25)
		(keepout
			(tracks not_allowed)
			(vias allowed)
			(pads allowed)
			(copperpour not_allowed)
			(footprints allowed)
		)
		(placement
			(enabled no)
			(sheetname "")
		)
		(fill
			(thermal_gap 0.5)
			(thermal_bridge_width 0.5)
			(island_removal_mode 0)
		)
		(polygon
			(pts
				(arc
					(start 304.562256 -417.305998)
					(mid 304.58218 -417.315234)
					(end 304.603912 -417.318444)
				)
				(arc
					(start 304.798476 -417.318444)
					(mid 304.852358 -417.296126)
					(end 304.874676 -417.242244)
				)
				(arc
					(start 304.874676 -416.556444)
					(mid 304.852358 -416.502562)
					(end 304.798476 -416.480244)
				)
				(arc
					(start 304.603912 -416.480244)
					(mid 304.582168 -416.483412)
					(end 304.562256 -416.49269)
				)
				(arc
					(start 304.266092 -416.685476)
					(mid 304.224408 -416.697698)
					(end 304.18278 -416.685222)
				)
				(arc
					(start 303.889156 -416.49269)
					(mid 303.869232 -416.483454)
					(end 303.8475 -416.480244)
				)
				(arc
					(start 303.652936 -416.480244)
					(mid 303.599054 -416.502562)
					(end 303.576736 -416.556444)
				)
				(arc
					(start 303.576736 -417.242244)
					(mid 303.599054 -417.296126)
					(end 303.652936 -417.318444)
				)
				(arc
					(start 303.84877 -417.318444)
					(mid 303.870514 -417.315276)
					(end 303.890426 -417.305998)
				)
				(arc
					(start 304.18405 -417.113466)
					(mid 304.225706 -417.101064)
					(end 304.267362 -417.113466)
				)
			)
		)
	)
	(zone
		(layer "In2.Cu")
		(hatch none 0.5)
		(connect_pads
			(clearance 0)
		)
		(min_thickness 0.25)
		(keepout
			(tracks not_allowed)
			(vias allowed)
			(pads allowed)
			(copperpour not_allowed)
			(footprints allowed)
		)
		(placement
			(enabled no)
			(sheetname "")
		)
		(fill
			(thermal_gap 0.5)
			(thermal_bridge_width 0.5)
			(island_removal_mode 0)
		)
		(polygon
			(pts
				(xy 268.898878 -293.975282) (xy 270.397478 -293.975282) (xy 270.397478 -294.49522) (xy 268.898878 -294.49522)
			)
		)
	)
	(zone
		(layer "In2.Cu")
		(hatch none 0.5)
		(connect_pads
			(clearance 0)
		)
		(min_thickness 0.25)
		(keepout
			(tracks not_allowed)
			(vias allowed)
			(pads allowed)
			(copperpour not_allowed)
			(footprints allowed)
		)
		(placement
			(enabled no)
			(sheetname "")
		)
		(fill
			(thermal_gap 0.5)
			(thermal_bridge_width 0.5)
			(island_removal_mode 0)
		)
		(polygon
			(pts
				(xy 58.678826 -285.475172) (xy 60.177426 -285.475172) (xy 60.177426 -285.99511) (xy 58.678826 -285.99511)
			)
		)
	)
	(zone
		(layer "In2.Cu")
		(hatch none 0.5)
		(connect_pads
			(clearance 0)
		)
		(min_thickness 0.25)
		(keepout
			(tracks not_allowed)
			(vias allowed)
			(pads allowed)
			(copperpour not_allowed)
			(footprints allowed)
		)
		(placement
			(enabled no)
			(sheetname "")
		)
		(fill
			(thermal_gap 0.5)
			(thermal_bridge_width 0.5)
			(island_removal_mode 0)
		)
		(polygon
			(pts
				(xy 163.678616 -202.17511) (xy 165.177216 -202.17511) (xy 165.177216 -202.695048) (xy 163.678616 -202.695048)
			)
		)
	)
	(zone
		(layer "In2.Cu")
		(hatch none 0.5)
		(connect_pads
			(clearance 0)
		)
		(min_thickness 0.25)
		(keepout
			(tracks not_allowed)
			(vias allowed)
			(pads allowed)
			(copperpour not_allowed)
			(footprints allowed)
		)
		(placement
			(enabled no)
			(sheetname "")
		)
		(fill
			(thermal_gap 0.5)
			(thermal_bridge_width 0.5)
			(island_removal_mode 0)
		)
		(polygon
			(pts
				(xy 36.046664 -265.9253) (xy 37.545264 -265.9253) (xy 37.545264 -266.445238) (xy 36.046664 -266.445238)
			)
		)
	)
	(zone
		(layer "In2.Cu")
		(hatch none 0.5)
		(connect_pads
			(clearance 0)
		)
		(min_thickness 0.25)
		(keepout
			(tracks not_allowed)
			(vias allowed)
			(pads allowed)
			(copperpour not_allowed)
			(footprints allowed)
		)
		(placement
			(enabled no)
			(sheetname "")
		)
		(fill
			(thermal_gap 0.5)
			(thermal_bridge_width 0.5)
			(island_removal_mode 0)
		)
		(polygon
			(pts
				(xy 279.886664 -254.025146) (xy 281.385264 -254.025146) (xy 281.385264 -254.545084) (xy 279.886664 -254.545084)
			)
		)
	)
	(zone
		(layer "In2.Cu")
		(hatch none 0.5)
		(connect_pads
			(clearance 0)
		)
		(min_thickness 0.25)
		(keepout
			(tracks not_allowed)
			(vias allowed)
			(pads allowed)
			(copperpour not_allowed)
			(footprints allowed)
		)
		(placement
			(enabled no)
			(sheetname "")
		)
		(fill
			(thermal_gap 0.5)
			(thermal_bridge_width 0.5)
			(island_removal_mode 0)
		)
		(polygon
			(pts
				(xy 268.898878 -282.925266) (xy 270.397478 -282.925266) (xy 270.397478 -283.445204) (xy 268.898878 -283.445204)
			)
		)
	)
	(zone
		(layer "In2.Cu")
		(hatch none 0.5)
		(connect_pads
			(clearance 0)
		)
		(min_thickness 0.25)
		(keepout
			(tracks not_allowed)
			(vias allowed)
			(pads allowed)
			(copperpour not_allowed)
			(footprints allowed)
		)
		(placement
			(enabled no)
			(sheetname "")
		)
		(fill
			(thermal_gap 0.5)
			(thermal_bridge_width 0.5)
			(island_removal_mode 0)
		)
		(polygon
			(pts
				(xy 302.518826 -289.725354) (xy 304.017426 -289.725354) (xy 304.017426 -290.245292) (xy 302.518826 -290.245292)
			)
		)
	)
	(zone
		(layer "In2.Cu")
		(hatch none 0.5)
		(connect_pads
			(clearance 0)
		)
		(min_thickness 0.25)
		(keepout
			(tracks not_allowed)
			(vias allowed)
			(pads allowed)
			(copperpour not_allowed)
			(footprints allowed)
		)
		(placement
			(enabled no)
			(sheetname "")
		)
		(fill
			(thermal_gap 0.5)
			(thermal_bridge_width 0.5)
			(island_removal_mode 0)
		)
		(polygon
			(pts
				(xy 171.22267 -276.125178) (xy 172.72127 -276.125178) (xy 172.72127 -276.645116) (xy 171.22267 -276.645116)
			)
		)
	)
	(zone
		(layer "In2.Cu")
		(hatch none 0.5)
		(connect_pads
			(clearance 0)
		)
		(min_thickness 0.25)
		(keepout
			(tracks not_allowed)
			(vias allowed)
			(pads allowed)
			(copperpour not_allowed)
			(footprints allowed)
		)
		(placement
			(enabled no)
			(sheetname "")
		)
		(fill
			(thermal_gap 0.5)
			(thermal_bridge_width 0.5)
			(island_removal_mode 0)
		)
		(polygon
			(pts
				(xy 54.578758 -268.475206) (xy 56.077358 -268.475206) (xy 56.077358 -268.995144) (xy 54.578758 -268.995144)
			)
		)
	)
	(zone
		(layer "In2.Cu")
		(hatch none 0.5)
		(connect_pads
			(clearance 0)
		)
		(min_thickness 0.25)
		(keepout
			(tracks not_allowed)
			(vias allowed)
			(pads allowed)
			(copperpour not_allowed)
			(footprints allowed)
		)
		(placement
			(enabled no)
			(sheetname "")
		)
		(fill
			(thermal_gap 0.5)
			(thermal_bridge_width 0.5)
			(island_removal_mode 0)
		)
		(polygon
			(pts
				(xy 167.778684 -294.825166) (xy 169.277284 -294.825166) (xy 169.277284 -295.345104) (xy 167.778684 -295.345104)
			)
		)
	)
	(zone
		(layer "In2.Cu")
		(hatch none 0.5)
		(connect_pads
			(clearance 0)
		)
		(min_thickness 0.25)
		(keepout
			(tracks not_allowed)
			(vias allowed)
			(pads allowed)
			(copperpour not_allowed)
			(footprints allowed)
		)
		(placement
			(enabled no)
			(sheetname "")
		)
		(fill
			(thermal_gap 0.5)
			(thermal_bridge_width 0.5)
			(island_removal_mode 0)
		)
		(polygon
			(pts
				(xy 426.706792 -210.67522) (xy 428.205392 -210.67522) (xy 428.205392 -211.195158) (xy 426.706792 -211.195158)
			)
		)
	)
	(zone
		(layer "In2.Cu")
		(hatch none 0.5)
		(connect_pads
			(clearance 0)
		)
		(min_thickness 0.25)
		(keepout
			(tracks allowed)
			(vias allowed)
			(pads allowed)
			(copperpour allowed)
			(footprints allowed)
		)
		(placement
			(enabled no)
			(sheetname "")
		)
		(fill
			(thermal_gap 0.5)
			(thermal_bridge_width 0.5)
			(island_removal_mode 0)
		)
		(polygon
			(pts
				(xy 86.690962 -179.426362) (xy 86.690962 -178.880008) (xy 87.243412 -178.880008) (xy 87.243412 -179.426362)
			)
		)
	)
	(zone
		(layer "In2.Cu")
		(hatch none 0.5)
		(connect_pads
			(clearance 0)
		)
		(min_thickness 0.25)
		(keepout
			(tracks not_allowed)
			(vias allowed)
			(pads allowed)
			(copperpour not_allowed)
			(footprints allowed)
		)
		(placement
			(enabled no)
			(sheetname "")
		)
		(fill
			(thermal_gap 0.5)
			(thermal_bridge_width 0.5)
			(island_removal_mode 0)
		)
		(polygon
			(pts
				(xy 58.678826 -221.725236) (xy 60.177426 -221.725236) (xy 60.177426 -222.245174) (xy 58.678826 -222.245174)
			)
		)
	)
	(zone
		(layer "In2.Cu")
		(hatch none 0.5)
		(connect_pads
			(clearance 0)
		)
		(min_thickness 0.25)
		(keepout
			(tracks not_allowed)
			(vias allowed)
			(pads allowed)
			(copperpour not_allowed)
			(footprints allowed)
		)
		(placement
			(enabled no)
			(sheetname "")
		)
		(fill
			(thermal_gap 0.5)
			(thermal_bridge_width 0.5)
			(island_removal_mode 0)
		)
		(polygon
			(pts
				(xy 272.342864 -231.925114) (xy 273.841464 -231.925114) (xy 273.841464 -232.445052) (xy 272.342864 -232.445052)
			)
		)
	)
	(zone
		(layer "In2.Cu")
		(hatch none 0.5)
		(connect_pads
			(clearance 0)
		)
		(min_thickness 0.25)
		(keepout
			(tracks not_allowed)
			(vias allowed)
			(pads allowed)
			(copperpour not_allowed)
			(footprints allowed)
		)
		(placement
			(enabled no)
			(sheetname "")
		)
		(fill
			(thermal_gap 0.5)
			(thermal_bridge_width 0.5)
			(island_removal_mode 0)
		)
		(polygon
			(pts
				(xy 302.518826 -203.875132) (xy 304.017426 -203.875132) (xy 304.017426 -204.39507) (xy 302.518826 -204.39507)
			)
		)
	)
	(zone
		(layer "In2.Cu")
		(hatch none 0.5)
		(connect_pads
			(clearance 0)
		)
		(min_thickness 0.25)
		(keepout
			(tracks not_allowed)
			(vias allowed)
			(pads allowed)
			(copperpour not_allowed)
			(footprints allowed)
		)
		(placement
			(enabled no)
			(sheetname "")
		)
		(fill
			(thermal_gap 0.5)
			(thermal_bridge_width 0.5)
			(island_removal_mode 0)
		)
		(polygon
			(pts
				(arc
					(start 295.186354 -384.869944)
					(mid 286.953706 -384.869944)
					(end 295.186354 -384.869944)
				)
			)
		)
	)
	(zone
		(layer "In2.Cu")
		(hatch none 0.5)
		(connect_pads
			(clearance 0)
		)
		(min_thickness 0.25)
		(keepout
			(tracks not_allowed)
			(vias allowed)
			(pads allowed)
			(copperpour not_allowed)
			(footprints allowed)
		)
		(placement
			(enabled no)
			(sheetname "")
		)
		(fill
			(thermal_gap 0.5)
			(thermal_bridge_width 0.5)
			(island_removal_mode 0)
		)
		(polygon
			(pts
				(xy 426.706792 -218.325192) (xy 428.205392 -218.325192) (xy 428.205392 -218.84513) (xy 426.706792 -218.84513)
			)
		)
	)
	(zone
		(layer "In2.Cu")
		(hatch none 0.5)
		(connect_pads
			(clearance 0)
		)
		(min_thickness 0.25)
		(keepout
			(tracks allowed)
			(vias allowed)
			(pads allowed)
			(copperpour allowed)
			(footprints allowed)
		)
		(placement
			(enabled no)
			(sheetname "")
		)
		(fill
			(thermal_gap 0.5)
			(thermal_bridge_width 0.5)
			(island_removal_mode 0)
		)
		(polygon
			(pts
				(xy 302.90897 -350.590866) (xy 302.90897 -349.968566) (xy 303.46015 -349.968566) (xy 303.46015 -350.590866)
			)
		)
	)
	(zone
		(layer "In2.Cu")
		(hatch none 0.5)
		(connect_pads
			(clearance 0)
		)
		(min_thickness 0.25)
		(keepout
			(tracks not_allowed)
			(vias allowed)
			(pads allowed)
			(copperpour not_allowed)
			(footprints allowed)
		)
		(placement
			(enabled no)
			(sheetname "")
		)
		(fill
			(thermal_gap 0.5)
			(thermal_bridge_width 0.5)
			(island_removal_mode 0)
		)
		(polygon
			(pts
				(xy 125.77826 -34.271204)
				(arc
					(start 125.918468 -34.271204)
					(mid 125.98835 -34.241995)
					(end 126.01702 -34.17189)
				)
				(arc
					(start 126.01702 -33.870646)
					(mid 125.98835 -33.800541)
					(end 125.918468 -33.771332)
				)
				(xy 125.77826 -33.771332) (xy 125.77826 -33.831276)
				(arc
					(start 125.209046 -33.831276)
					(mid 125.172677 -33.787777)
					(end 125.118368 -33.771332)
				)
				(arc
					(start 124.858272 -33.771332)
					(mid 124.80388 -33.787651)
					(end 124.767594 -33.831276)
				)
				(xy 124.19838 -33.831276) (xy 124.19838 -33.771332)
				(arc
					(start 124.058172 -33.771332)
					(mid 123.98829 -33.800541)
					(end 123.95962 -33.870646)
				)
				(arc
					(start 123.95962 -34.17189)
					(mid 123.98829 -34.241995)
					(end 124.058172 -34.271204)
				)
				(xy 124.19838 -34.271204) (xy 124.19838 -34.21126)
				(arc
					(start 124.767594 -34.21126)
					(mid 124.803963 -34.254759)
					(end 124.858272 -34.271204)
				)
				(arc
					(start 125.118368 -34.271204)
					(mid 125.17276 -34.254885)
					(end 125.209046 -34.21126)
				)
				(xy 125.77826 -34.21126)
			)
		)
	)
	(zone
		(layer "In2.Cu")
		(hatch none 0.5)
		(connect_pads
			(clearance 0)
		)
		(min_thickness 0.25)
		(keepout
			(tracks not_allowed)
			(vias allowed)
			(pads allowed)
			(copperpour not_allowed)
			(footprints allowed)
		)
		(placement
			(enabled no)
			(sheetname "")
		)
		(fill
			(thermal_gap 0.5)
			(thermal_bridge_width 0.5)
			(island_removal_mode 0)
		)
		(polygon
			(pts
				(xy 453.438768 -231.07523) (xy 454.937368 -231.07523) (xy 454.937368 -231.595168) (xy 453.438768 -231.595168)
			)
		)
	)
	(zone
		(layer "In2.Cu")
		(hatch none 0.5)
		(connect_pads
			(clearance 0)
		)
		(min_thickness 0.25)
		(keepout
			(tracks not_allowed)
			(vias allowed)
			(pads allowed)
			(copperpour not_allowed)
			(footprints allowed)
		)
		(placement
			(enabled no)
			(sheetname "")
		)
		(fill
			(thermal_gap 0.5)
			(thermal_bridge_width 0.5)
			(island_removal_mode 0)
		)
		(polygon
			(pts
				(xy 36.046664 -247.225312) (xy 37.545264 -247.225312) (xy 37.545264 -247.74525) (xy 36.046664 -247.74525)
			)
		)
	)
	(zone
		(layer "In2.Cu")
		(hatch none 0.5)
		(connect_pads
			(clearance 0)
		)
		(min_thickness 0.25)
		(keepout
			(tracks not_allowed)
			(vias allowed)
			(pads allowed)
			(copperpour not_allowed)
			(footprints allowed)
		)
		(placement
			(enabled no)
			(sheetname "")
		)
		(fill
			(thermal_gap 0.5)
			(thermal_bridge_width 0.5)
			(island_removal_mode 0)
		)
		(polygon
			(pts
				(xy 306.618894 -203.025248) (xy 308.117494 -203.025248) (xy 308.117494 -203.545186) (xy 306.618894 -203.545186)
			)
		)
	)
	(zone
		(layer "In2.Cu")
		(hatch none 0.5)
		(connect_pads
			(clearance 0)
		)
		(min_thickness 0.25)
		(keepout
			(tracks not_allowed)
			(vias allowed)
			(pads allowed)
			(copperpour not_allowed)
			(footprints allowed)
		)
		(placement
			(enabled no)
			(sheetname "")
		)
		(fill
			(thermal_gap 0.5)
			(thermal_bridge_width 0.5)
			(island_removal_mode 0)
		)
		(polygon
			(pts
				(xy 283.986732 -287.175194) (xy 285.485332 -287.175194) (xy 285.485332 -287.695132) (xy 283.986732 -287.695132)
			)
		)
	)
	(zone
		(layer "In2.Cu")
		(hatch none 0.5)
		(connect_pads
			(clearance 0)
		)
		(min_thickness 0.25)
		(keepout
			(tracks not_allowed)
			(vias allowed)
			(pads allowed)
			(copperpour not_allowed)
			(footprints allowed)
		)
		(placement
			(enabled no)
			(sheetname "")
		)
		(fill
			(thermal_gap 0.5)
			(thermal_bridge_width 0.5)
			(island_removal_mode 0)
		)
		(polygon
			(pts
				(xy 167.778684 -219.17533) (xy 169.277284 -219.17533) (xy 169.277284 -219.695268) (xy 167.778684 -219.695268)
			)
		)
	)
	(zone
		(layer "In2.Cu")
		(hatch none 0.5)
		(connect_pads
			(clearance 0)
		)
		(min_thickness 0.25)
		(keepout
			(tracks not_allowed)
			(vias allowed)
			(pads allowed)
			(copperpour not_allowed)
			(footprints allowed)
		)
		(placement
			(enabled no)
			(sheetname "")
		)
		(fill
			(thermal_gap 0.5)
			(thermal_bridge_width 0.5)
			(island_removal_mode 0)
		)
		(polygon
			(pts
				(xy 449.3387 -207.275176) (xy 450.8373 -207.275176) (xy 450.8373 -207.795114) (xy 449.3387 -207.795114)
			)
		)
	)
	(zone
		(layer "In2.Cu")
		(hatch none 0.5)
		(connect_pads
			(clearance 0)
		)
		(min_thickness 0.25)
		(keepout
			(tracks not_allowed)
			(vias allowed)
			(pads allowed)
			(copperpour not_allowed)
			(footprints allowed)
		)
		(placement
			(enabled no)
			(sheetname "")
		)
		(fill
			(thermal_gap 0.5)
			(thermal_bridge_width 0.5)
			(island_removal_mode 0)
		)
		(polygon
			(pts
				(xy 31.946596 -285.475172) (xy 33.445196 -285.475172) (xy 33.445196 -285.99511) (xy 31.946596 -285.99511)
			)
		)
	)
	(zone
		(layer "In2.Cu")
		(hatch none 0.5)
		(connect_pads
			(clearance 0)
		)
		(min_thickness 0.25)
		(keepout
			(tracks not_allowed)
			(vias allowed)
			(pads allowed)
			(copperpour not_allowed)
			(footprints allowed)
		)
		(placement
			(enabled no)
			(sheetname "")
		)
		(fill
			(thermal_gap 0.5)
			(thermal_bridge_width 0.5)
			(island_removal_mode 0)
		)
		(polygon
			(pts
				(xy 438.350914 -208.125314) (xy 439.849514 -208.125314) (xy 439.849514 -208.645252) (xy 438.350914 -208.645252)
			)
		)
	)
	(zone
		(layer "In2.Cu")
		(hatch none 0.5)
		(connect_pads
			(clearance 0)
		)
		(min_thickness 0.25)
		(keepout
			(tracks not_allowed)
			(vias allowed)
			(pads allowed)
			(copperpour not_allowed)
			(footprints allowed)
		)
		(placement
			(enabled no)
			(sheetname "")
		)
		(fill
			(thermal_gap 0.5)
			(thermal_bridge_width 0.5)
			(island_removal_mode 0)
		)
		(polygon
			(pts
				(xy 449.3387 -202.17511) (xy 450.8373 -202.17511) (xy 450.8373 -202.695048) (xy 449.3387 -202.695048)
			)
		)
	)
	(zone
		(layer "In2.Cu")
		(hatch none 0.5)
		(connect_pads
			(clearance 0)
		)
		(min_thickness 0.25)
		(keepout
			(tracks not_allowed)
			(vias allowed)
			(pads allowed)
			(copperpour not_allowed)
			(footprints allowed)
		)
		(placement
			(enabled no)
			(sheetname "")
		)
		(fill
			(thermal_gap 0.5)
			(thermal_bridge_width 0.5)
			(island_removal_mode 0)
		)
		(polygon
			(pts
				(xy 415.718752 -273.575272) (xy 417.217352 -273.575272) (xy 417.217352 -274.09521) (xy 415.718752 -274.09521)
			)
		)
	)
	(zone
		(layer "In2.Cu")
		(hatch none 0.5)
		(connect_pads
			(clearance 0)
		)
		(min_thickness 0.25)
		(keepout
			(tracks not_allowed)
			(vias allowed)
			(pads allowed)
			(copperpour not_allowed)
			(footprints allowed)
		)
		(placement
			(enabled no)
			(sheetname "")
		)
		(fill
			(thermal_gap 0.5)
			(thermal_bridge_width 0.5)
			(island_removal_mode 0)
		)
		(polygon
			(pts
				(xy 201.398632 -280.375106) (xy 202.897232 -280.375106) (xy 202.897232 -280.895044) (xy 201.398632 -280.895044)
			)
		)
	)
	(zone
		(layer "In2.Cu")
		(hatch none 0.5)
		(connect_pads
			(clearance 0)
		)
		(min_thickness 0.25)
		(keepout
			(tracks not_allowed)
			(vias allowed)
			(pads allowed)
			(copperpour not_allowed)
			(footprints allowed)
		)
		(placement
			(enabled no)
			(sheetname "")
		)
		(fill
			(thermal_gap 0.5)
			(thermal_bridge_width 0.5)
			(island_removal_mode 0)
		)
		(polygon
			(pts
				(xy 186.310778 -251.47524) (xy 187.809378 -251.47524) (xy 187.809378 -251.995178) (xy 186.310778 -251.995178)
			)
		)
	)
	(zone
		(layer "In2.Cu")
		(hatch none 0.5)
		(connect_pads
			(clearance 0)
		)
		(min_thickness 0.25)
		(keepout
			(tracks not_allowed)
			(vias allowed)
			(pads allowed)
			(copperpour not_allowed)
			(footprints allowed)
		)
		(placement
			(enabled no)
			(sheetname "")
		)
		(fill
			(thermal_gap 0.5)
			(thermal_bridge_width 0.5)
			(island_removal_mode 0)
		)
		(polygon
			(pts
				(xy 415.718752 -303.325276) (xy 417.217352 -303.325276) (xy 417.217352 -303.845214) (xy 415.718752 -303.845214)
			)
		)
	)
	(zone
		(layer "In2.Cu")
		(hatch none 0.5)
		(connect_pads
			(clearance 0)
		)
		(min_thickness 0.25)
		(keepout
			(tracks not_allowed)
			(vias allowed)
			(pads allowed)
			(copperpour not_allowed)
			(footprints allowed)
		)
		(placement
			(enabled no)
			(sheetname "")
		)
		(fill
			(thermal_gap 0.5)
			(thermal_bridge_width 0.5)
			(island_removal_mode 0)
		)
		(polygon
			(pts
				(xy 430.80686 -214.075264) (xy 432.30546 -214.075264) (xy 432.30546 -214.595202) (xy 430.80686 -214.595202)
			)
		)
	)
	(zone
		(layer "In2.Cu")
		(hatch none 0.5)
		(connect_pads
			(clearance 0)
		)
		(min_thickness 0.25)
		(keepout
			(tracks not_allowed)
			(vias allowed)
			(pads allowed)
			(copperpour not_allowed)
			(footprints allowed)
		)
		(placement
			(enabled no)
			(sheetname "")
		)
		(fill
			(thermal_gap 0.5)
			(thermal_bridge_width 0.5)
			(island_removal_mode 0)
		)
		(polygon
			(pts
				(xy 193.854578 -227.675186) (xy 195.353178 -227.675186) (xy 195.353178 -228.195124) (xy 193.854578 -228.195124)
			)
		)
	)
	(zone
		(layer "In2.Cu")
		(hatch none 0.5)
		(connect_pads
			(clearance 0)
		)
		(min_thickness 0.25)
		(keepout
			(tracks not_allowed)
			(vias allowed)
			(pads allowed)
			(copperpour not_allowed)
			(footprints allowed)
		)
		(placement
			(enabled no)
			(sheetname "")
		)
		(fill
			(thermal_gap 0.5)
			(thermal_bridge_width 0.5)
			(island_removal_mode 0)
		)
		(polygon
			(pts
				(xy 24.402542 -302.475138) (xy 25.901142 -302.475138) (xy 25.901142 -302.995076) (xy 24.402542 -302.995076)
			)
		)
	)
	(zone
		(layer "In2.Cu")
		(hatch none 0.5)
		(connect_pads
			(clearance 0)
		)
		(min_thickness 0.25)
		(keepout
			(tracks not_allowed)
			(vias allowed)
			(pads allowed)
			(copperpour not_allowed)
			(footprints allowed)
		)
		(placement
			(enabled no)
			(sheetname "")
		)
		(fill
			(thermal_gap 0.5)
			(thermal_bridge_width 0.5)
			(island_removal_mode 0)
		)
		(polygon
			(pts
				(xy 283.986732 -299.925232) (xy 285.485332 -299.925232) (xy 285.485332 -300.44517) (xy 283.986732 -300.44517)
			)
		)
	)
	(zone
		(layer "In2.Cu")
		(hatch none 0.5)
		(connect_pads
			(clearance 0)
		)
		(min_thickness 0.25)
		(keepout
			(tracks not_allowed)
			(vias allowed)
			(pads allowed)
			(copperpour not_allowed)
			(footprints allowed)
		)
		(placement
			(enabled no)
			(sheetname "")
		)
		(fill
			(thermal_gap 0.5)
			(thermal_bridge_width 0.5)
			(island_removal_mode 0)
		)
		(polygon
			(pts
				(arc
					(start 51.772312 -7.672324)
					(mid 51.79463 -7.618442)
					(end 51.848512 -7.596124)
				)
				(arc
					(start 52.885086 -7.596124)
					(mid 52.938968 -7.618442)
					(end 52.961286 -7.672324)
				)
				(arc
					(start 52.961286 -9.071864)
					(mid 52.938968 -9.125746)
					(end 52.885086 -9.148064)
				)
				(arc
					(start 51.848512 -9.148064)
					(mid 51.79463 -9.125746)
					(end 51.772312 -9.071864)
				)
			)
		)
	)
	(zone
		(layer "In2.Cu")
		(hatch none 0.5)
		(connect_pads
			(clearance 0)
		)
		(min_thickness 0.25)
		(keepout
			(tracks allowed)
			(vias allowed)
			(pads allowed)
			(copperpour allowed)
			(footprints allowed)
		)
		(placement
			(enabled no)
			(sheetname "")
		)
		(fill
			(thermal_gap 0.5)
			(thermal_bridge_width 0.5)
			(island_removal_mode 0)
		)
		(polygon
			(pts
				(xy 346.6592 -343.15654) (xy 346.6592 -342.53424) (xy 347.21038 -342.53424) (xy 347.21038 -343.15654)
			)
		)
	)
	(zone
		(layer "In2.Cu")
		(hatch none 0.5)
		(connect_pads
			(clearance 0)
		)
		(min_thickness 0.25)
		(keepout
			(tracks not_allowed)
			(vias allowed)
			(pads allowed)
			(copperpour not_allowed)
			(footprints allowed)
		)
		(placement
			(enabled no)
			(sheetname "")
		)
		(fill
			(thermal_gap 0.5)
			(thermal_bridge_width 0.5)
			(island_removal_mode 0)
		)
		(polygon
			(pts
				(xy 268.898878 -219.17533) (xy 270.397478 -219.17533) (xy 270.397478 -219.695268) (xy 268.898878 -219.695268)
			)
		)
	)
	(zone
		(layer "In2.Cu")
		(hatch none 0.5)
		(connect_pads
			(clearance 0)
		)
		(min_thickness 0.25)
		(keepout
			(tracks not_allowed)
			(vias allowed)
			(pads allowed)
			(copperpour not_allowed)
			(footprints allowed)
		)
		(placement
			(enabled no)
			(sheetname "")
		)
		(fill
			(thermal_gap 0.5)
			(thermal_bridge_width 0.5)
			(island_removal_mode 0)
		)
		(polygon
			(pts
				(xy 20.95881 -265.9253) (xy 22.45741 -265.9253) (xy 22.45741 -266.445238) (xy 20.95881 -266.445238)
			)
		)
	)
	(zone
		(layer "In2.Cu")
		(hatch none 0.5)
		(connect_pads
			(clearance 0)
		)
		(min_thickness 0.25)
		(keepout
			(tracks not_allowed)
			(vias allowed)
			(pads allowed)
			(copperpour not_allowed)
			(footprints allowed)
		)
		(placement
			(enabled no)
			(sheetname "")
		)
		(fill
			(thermal_gap 0.5)
			(thermal_bridge_width 0.5)
			(island_removal_mode 0)
		)
		(polygon
			(pts
				(xy 20.95881 -315.225176) (xy 22.45741 -315.225176) (xy 22.45741 -315.745114) (xy 20.95881 -315.745114)
			)
		)
	)
	(zone
		(layer "In2.Cu")
		(hatch none 0.5)
		(connect_pads
			(clearance 0)
		)
		(min_thickness 0.25)
		(keepout
			(tracks not_allowed)
			(vias allowed)
			(pads allowed)
			(copperpour not_allowed)
			(footprints allowed)
		)
		(placement
			(enabled no)
			(sheetname "")
		)
		(fill
			(thermal_gap 0.5)
			(thermal_bridge_width 0.5)
			(island_removal_mode 0)
		)
		(polygon
			(pts
				(xy 51.134772 -200.475342) (xy 52.633372 -200.475342) (xy 52.633372 -200.99528) (xy 51.134772 -200.99528)
			)
		)
	)
	(zone
		(layer "In2.Cu")
		(hatch none 0.5)
		(connect_pads
			(clearance 0)
		)
		(min_thickness 0.25)
		(keepout
			(tracks not_allowed)
			(vias allowed)
			(pads allowed)
			(copperpour not_allowed)
			(footprints allowed)
		)
		(placement
			(enabled no)
			(sheetname "")
		)
		(fill
			(thermal_gap 0.5)
			(thermal_bridge_width 0.5)
			(island_removal_mode 0)
		)
		(polygon
			(pts
				(xy 193.854578 -274.425156) (xy 195.353178 -274.425156) (xy 195.353178 -274.945094) (xy 193.854578 -274.945094)
			)
		)
	)
	(zone
		(layer "In2.Cu")
		(hatch none 0.5)
		(connect_pads
			(clearance 0)
		)
		(min_thickness 0.25)
		(keepout
			(tracks not_allowed)
			(vias allowed)
			(pads allowed)
			(copperpour not_allowed)
			(footprints allowed)
		)
		(placement
			(enabled no)
			(sheetname "")
		)
		(fill
			(thermal_gap 0.5)
			(thermal_bridge_width 0.5)
			(island_removal_mode 0)
		)
		(polygon
			(pts
				(xy 430.80686 -270.175228) (xy 432.30546 -270.175228) (xy 432.30546 -270.695166) (xy 430.80686 -270.695166)
			)
		)
	)
	(zone
		(layer "In2.Cu")
		(hatch none 0.5)
		(connect_pads
			(clearance 0)
		)
		(min_thickness 0.25)
		(keepout
			(tracks not_allowed)
			(vias allowed)
			(pads allowed)
			(copperpour not_allowed)
			(footprints allowed)
		)
		(placement
			(enabled no)
			(sheetname "")
		)
		(fill
			(thermal_gap 0.5)
			(thermal_bridge_width 0.5)
			(island_removal_mode 0)
		)
		(polygon
			(pts
				(xy 276.442932 -281.225244) (xy 277.941532 -281.225244) (xy 277.941532 -281.745182) (xy 276.442932 -281.745182)
			)
		)
	)
	(zone
		(layer "In2.Cu")
		(hatch none 0.5)
		(connect_pads
			(clearance 0)
		)
		(min_thickness 0.25)
		(keepout
			(tracks not_allowed)
			(vias allowed)
			(pads allowed)
			(copperpour not_allowed)
			(footprints allowed)
		)
		(placement
			(enabled no)
			(sheetname "")
		)
		(fill
			(thermal_gap 0.5)
			(thermal_bridge_width 0.5)
			(island_removal_mode 0)
		)
		(polygon
			(pts
				(xy 438.350914 -305.875182) (xy 439.849514 -305.875182) (xy 439.849514 -306.39512) (xy 438.350914 -306.39512)
			)
		)
	)
	(zone
		(layer "In2.Cu")
		(hatch none 0.5)
		(connect_pads
			(clearance 0)
		)
		(min_thickness 0.25)
		(keepout
			(tracks not_allowed)
			(vias allowed)
			(pads allowed)
			(copperpour not_allowed)
			(footprints allowed)
		)
		(placement
			(enabled no)
			(sheetname "")
		)
		(fill
			(thermal_gap 0.5)
			(thermal_bridge_width 0.5)
			(island_removal_mode 0)
		)
		(polygon
			(pts
				(xy 31.946596 -274.425156) (xy 33.445196 -274.425156) (xy 33.445196 -274.945094) (xy 31.946596 -274.945094)
			)
		)
	)
	(zone
		(layer "In2.Cu")
		(hatch none 0.5)
		(connect_pads
			(clearance 0)
		)
		(min_thickness 0.25)
		(keepout
			(tracks not_allowed)
			(vias allowed)
			(pads allowed)
			(copperpour not_allowed)
			(footprints allowed)
		)
		(placement
			(enabled no)
			(sheetname "")
		)
		(fill
			(thermal_gap 0.5)
			(thermal_bridge_width 0.5)
			(island_removal_mode 0)
		)
		(polygon
			(pts
				(arc
					(start 15.316708 -16.442436)
					(mid 15.339026 -16.496318)
					(end 15.392908 -16.518636)
				)
				(arc
					(start 15.588488 -16.518636)
					(mid 15.610364 -16.515504)
					(end 15.630398 -16.50619)
				)
				(arc
					(start 15.924022 -16.313658)
					(mid 15.965678 -16.301256)
					(end 16.007334 -16.313658)
				)
				(arc
					(start 16.302228 -16.50619)
					(mid 16.322152 -16.515426)
					(end 16.343884 -16.518636)
				)
				(arc
					(start 16.538448 -16.518636)
					(mid 16.59233 -16.496318)
					(end 16.614648 -16.442436)
				)
				(arc
					(start 16.614648 -15.756636)
					(mid 16.59233 -15.702754)
					(end 16.538448 -15.680436)
				)
				(arc
					(start 16.343884 -15.680436)
					(mid 16.32214 -15.683604)
					(end 16.302228 -15.692882)
				)
				(arc
					(start 16.006064 -15.885668)
					(mid 15.96438 -15.89789)
					(end 15.922752 -15.885414)
				)
				(arc
					(start 15.629128 -15.692882)
					(mid 15.609204 -15.683646)
					(end 15.587472 -15.680436)
				)
				(arc
					(start 15.392908 -15.680436)
					(mid 15.339026 -15.702754)
					(end 15.316708 -15.756636)
				)
			)
		)
	)
	(zone
		(layer "In2.Cu")
		(hatch none 0.5)
		(connect_pads
			(clearance 0)
		)
		(min_thickness 0.25)
		(keepout
			(tracks allowed)
			(vias allowed)
			(pads allowed)
			(copperpour allowed)
			(footprints allowed)
		)
		(placement
			(enabled no)
			(sheetname "")
		)
		(fill
			(thermal_gap 0.5)
			(thermal_bridge_width 0.5)
			(island_removal_mode 0)
		)
		(polygon
			(pts
				(xy 95.083122 -180.916834) (xy 95.083122 -180.37048) (xy 95.635572 -180.37048) (xy 95.635572 -180.916834)
			)
		)
	)
	(zone
		(layer "In2.Cu")
		(hatch none 0.5)
		(connect_pads
			(clearance 0)
		)
		(min_thickness 0.25)
		(keepout
			(tracks not_allowed)
			(vias allowed)
			(pads allowed)
			(copperpour not_allowed)
			(footprints allowed)
		)
		(placement
			(enabled no)
			(sheetname "")
		)
		(fill
			(thermal_gap 0.5)
			(thermal_bridge_width 0.5)
			(island_removal_mode 0)
		)
		(polygon
			(pts
				(xy 453.438768 -315.225176) (xy 454.937368 -315.225176) (xy 454.937368 -315.745114) (xy 453.438768 -315.745114)
			)
		)
	)
	(zone
		(layer "In2.Cu")
		(hatch none 0.5)
		(connect_pads
			(clearance 0)
		)
		(min_thickness 0.25)
		(keepout
			(tracks not_allowed)
			(vias allowed)
			(pads allowed)
			(copperpour not_allowed)
			(footprints allowed)
		)
		(placement
			(enabled no)
			(sheetname "")
		)
		(fill
			(thermal_gap 0.5)
			(thermal_bridge_width 0.5)
			(island_removal_mode 0)
		)
		(polygon
			(pts
				(xy 434.250846 -289.725354) (xy 435.749446 -289.725354) (xy 435.749446 -290.245292) (xy 434.250846 -290.245292)
			)
		)
	)
	(zone
		(layer "In2.Cu")
		(hatch none 0.5)
		(connect_pads
			(clearance 0)
		)
		(min_thickness 0.25)
		(keepout
			(tracks not_allowed)
			(vias allowed)
			(pads allowed)
			(copperpour not_allowed)
			(footprints allowed)
		)
		(placement
			(enabled no)
			(sheetname "")
		)
		(fill
			(thermal_gap 0.5)
			(thermal_bridge_width 0.5)
			(island_removal_mode 0)
		)
		(polygon
			(pts
				(xy 163.678616 -248.075196) (xy 165.177216 -248.075196) (xy 165.177216 -248.595134) (xy 163.678616 -248.595134)
			)
		)
	)
	(zone
		(layer "In2.Cu")
		(hatch none 0.5)
		(connect_pads
			(clearance 0)
		)
		(min_thickness 0.25)
		(keepout
			(tracks not_allowed)
			(vias allowed)
			(pads allowed)
			(copperpour not_allowed)
			(footprints allowed)
		)
		(placement
			(enabled no)
			(sheetname "")
		)
		(fill
			(thermal_gap 0.5)
			(thermal_bridge_width 0.5)
			(island_removal_mode 0)
		)
		(polygon
			(pts
				(xy 193.854578 -299.075348) (xy 195.353178 -299.075348) (xy 195.353178 -299.595286) (xy 193.854578 -299.595286)
			)
		)
	)
	(zone
		(layer "In2.Cu")
		(hatch none 0.5)
		(connect_pads
			(clearance 0)
		)
		(min_thickness 0.25)
		(keepout
			(tracks not_allowed)
			(vias allowed)
			(pads allowed)
			(copperpour not_allowed)
			(footprints allowed)
		)
		(placement
			(enabled no)
			(sheetname "")
		)
		(fill
			(thermal_gap 0.5)
			(thermal_bridge_width 0.5)
			(island_removal_mode 0)
		)
		(polygon
			(pts
				(xy 302.518826 -272.725134) (xy 304.017426 -272.725134) (xy 304.017426 -273.245072) (xy 302.518826 -273.245072)
			)
		)
	)
	(zone
		(layer "In2.Cu")
		(hatch none 0.5)
		(connect_pads
			(clearance 0)
		)
		(min_thickness 0.25)
		(keepout
			(tracks allowed)
			(vias allowed)
			(pads allowed)
			(copperpour allowed)
			(footprints allowed)
		)
		(placement
			(enabled no)
			(sheetname "")
		)
		(fill
			(thermal_gap 0.5)
			(thermal_bridge_width 0.5)
			(island_removal_mode 0)
		)
		(polygon
			(pts
				(xy 377.08713 -179.494434) (xy 377.08713 -178.94808) (xy 377.63958 -178.94808) (xy 377.63958 -179.494434)
			)
		)
	)
	(zone
		(layer "In2.Cu")
		(hatch none 0.5)
		(connect_pads
			(clearance 0)
		)
		(min_thickness 0.25)
		(keepout
			(tracks allowed)
			(vias allowed)
			(pads allowed)
			(copperpour allowed)
			(footprints allowed)
		)
		(placement
			(enabled no)
			(sheetname "")
		)
		(fill
			(thermal_gap 0.5)
			(thermal_bridge_width 0.5)
			(island_removal_mode 0)
		)
		(polygon
			(pts
				(xy 296.473372 -349.93834) (xy 296.473372 -349.31604) (xy 297.024552 -349.31604) (xy 297.024552 -349.93834)
			)
		)
	)
	(zone
		(layer "In2.Cu")
		(hatch none 0.5)
		(connect_pads
			(clearance 0)
		)
		(min_thickness 0.25)
		(keepout
			(tracks not_allowed)
			(vias allowed)
			(pads allowed)
			(copperpour not_allowed)
			(footprints allowed)
		)
		(placement
			(enabled no)
			(sheetname "")
		)
		(fill
			(thermal_gap 0.5)
			(thermal_bridge_width 0.5)
			(island_removal_mode 0)
		)
		(polygon
			(pts
				(xy 291.530786 -267.625322) (xy 293.029386 -267.625322) (xy 293.029386 -268.14526) (xy 291.530786 -268.14526)
			)
		)
	)
	(zone
		(layer "In2.Cu")
		(hatch none 0.5)
		(connect_pads
			(clearance 0)
		)
		(min_thickness 0.25)
		(keepout
			(tracks not_allowed)
			(vias allowed)
			(pads allowed)
			(copperpour not_allowed)
			(footprints allowed)
		)
		(placement
			(enabled no)
			(sheetname "")
		)
		(fill
			(thermal_gap 0.5)
			(thermal_bridge_width 0.5)
			(island_removal_mode 0)
		)
		(polygon
			(pts
				(xy 419.162738 -225.975164) (xy 420.661338 -225.975164) (xy 420.661338 -226.495102) (xy 419.162738 -226.495102)
			)
		)
	)
	(zone
		(layer "In2.Cu")
		(hatch none 0.5)
		(connect_pads
			(clearance 0)
		)
		(min_thickness 0.25)
		(keepout
			(tracks not_allowed)
			(vias allowed)
			(pads allowed)
			(copperpour not_allowed)
			(footprints allowed)
		)
		(placement
			(enabled no)
			(sheetname "")
		)
		(fill
			(thermal_gap 0.5)
			(thermal_bridge_width 0.5)
			(island_removal_mode 0)
		)
		(polygon
			(pts
				(xy 426.706792 -305.025298) (xy 428.205392 -305.025298) (xy 428.205392 -305.545236) (xy 426.706792 -305.545236)
			)
		)
	)
	(zone
		(layer "In2.Cu")
		(hatch none 0.5)
		(connect_pads
			(clearance 0)
		)
		(min_thickness 0.25)
		(keepout
			(tracks not_allowed)
			(vias allowed)
			(pads allowed)
			(copperpour not_allowed)
			(footprints allowed)
		)
		(placement
			(enabled no)
			(sheetname "")
		)
		(fill
			(thermal_gap 0.5)
			(thermal_bridge_width 0.5)
			(island_removal_mode 0)
		)
		(polygon
			(pts
				(xy 163.678616 -251.47524) (xy 165.177216 -251.47524) (xy 165.177216 -251.995178) (xy 163.678616 -251.995178)
			)
		)
	)
	(zone
		(layer "In2.Cu")
		(hatch none 0.5)
		(connect_pads
			(clearance 0)
		)
		(min_thickness 0.25)
		(keepout
			(tracks not_allowed)
			(vias allowed)
			(pads allowed)
			(copperpour not_allowed)
			(footprints allowed)
		)
		(placement
			(enabled no)
			(sheetname "")
		)
		(fill
			(thermal_gap 0.5)
			(thermal_bridge_width 0.5)
			(island_removal_mode 0)
		)
		(polygon
			(pts
				(xy 197.954646 -247.225312) (xy 199.453246 -247.225312) (xy 199.453246 -247.74525) (xy 197.954646 -247.74525)
			)
		)
	)
	(zone
		(layer "In2.Cu")
		(hatch none 0.5)
		(connect_pads
			(clearance 0)
		)
		(min_thickness 0.25)
		(keepout
			(tracks not_allowed)
			(vias allowed)
			(pads allowed)
			(copperpour not_allowed)
			(footprints allowed)
		)
		(placement
			(enabled no)
			(sheetname "")
		)
		(fill
			(thermal_gap 0.5)
			(thermal_bridge_width 0.5)
			(island_removal_mode 0)
		)
		(polygon
			(pts
				(xy 175.322738 -260.825234) (xy 176.821338 -260.825234) (xy 176.821338 -261.345172) (xy 175.322738 -261.345172)
			)
		)
	)
	(zone
		(layer "In2.Cu")
		(hatch none 0.5)
		(connect_pads
			(clearance 0)
		)
		(min_thickness 0.25)
		(keepout
			(tracks not_allowed)
			(vias allowed)
			(pads allowed)
			(copperpour not_allowed)
			(footprints allowed)
		)
		(placement
			(enabled no)
			(sheetname "")
		)
		(fill
			(thermal_gap 0.5)
			(thermal_bridge_width 0.5)
			(island_removal_mode 0)
		)
		(polygon
			(pts
				(xy 171.22267 -253.175262) (xy 172.72127 -253.175262) (xy 172.72127 -253.6952) (xy 171.22267 -253.6952)
			)
		)
	)
	(zone
		(layer "In2.Cu")
		(hatch none 0.5)
		(connect_pads
			(clearance 0)
		)
		(min_thickness 0.25)
		(keepout
			(tracks not_allowed)
			(vias allowed)
			(pads allowed)
			(copperpour not_allowed)
			(footprints allowed)
		)
		(placement
			(enabled no)
			(sheetname "")
		)
		(fill
			(thermal_gap 0.5)
			(thermal_bridge_width 0.5)
			(island_removal_mode 0)
		)
		(polygon
			(pts
				(xy 54.578758 -229.375208) (xy 56.077358 -229.375208) (xy 56.077358 -229.895146) (xy 54.578758 -229.895146)
			)
		)
	)
	(zone
		(layer "In2.Cu")
		(hatch none 0.5)
		(connect_pads
			(clearance 0)
		)
		(min_thickness 0.25)
		(keepout
			(tracks not_allowed)
			(vias allowed)
			(pads allowed)
			(copperpour not_allowed)
			(footprints allowed)
		)
		(placement
			(enabled no)
			(sheetname "")
		)
		(fill
			(thermal_gap 0.5)
			(thermal_bridge_width 0.5)
			(island_removal_mode 0)
		)
		(polygon
			(pts
				(xy 197.954646 -309.275226) (xy 199.453246 -309.275226) (xy 199.453246 -309.795164) (xy 197.954646 -309.795164)
			)
		)
	)
	(zone
		(layer "In2.Cu")
		(hatch none 0.5)
		(connect_pads
			(clearance 0)
		)
		(min_thickness 0.25)
		(keepout
			(tracks not_allowed)
			(vias allowed)
			(pads allowed)
			(copperpour not_allowed)
			(footprints allowed)
		)
		(placement
			(enabled no)
			(sheetname "")
		)
		(fill
			(thermal_gap 0.5)
			(thermal_bridge_width 0.5)
			(island_removal_mode 0)
		)
		(polygon
			(pts
				(xy 186.310778 -314.375292) (xy 187.809378 -314.375292) (xy 187.809378 -314.89523) (xy 186.310778 -314.89523)
			)
		)
	)
	(zone
		(layer "In2.Cu")
		(hatch none 0.5)
		(connect_pads
			(clearance 0)
		)
		(min_thickness 0.25)
		(keepout
			(tracks not_allowed)
			(vias allowed)
			(pads allowed)
			(copperpour not_allowed)
			(footprints allowed)
		)
		(placement
			(enabled no)
			(sheetname "")
		)
		(fill
			(thermal_gap 0.5)
			(thermal_bridge_width 0.5)
			(island_removal_mode 0)
		)
		(polygon
			(pts
				(xy 24.402542 -282.075128) (xy 25.901142 -282.075128) (xy 25.901142 -282.595066) (xy 24.402542 -282.595066)
			)
		)
	)
	(zone
		(layer "In2.Cu")
		(hatch none 0.5)
		(connect_pads
			(clearance 0)
		)
		(min_thickness 0.25)
		(keepout
			(tracks not_allowed)
			(vias allowed)
			(pads allowed)
			(copperpour not_allowed)
			(footprints allowed)
		)
		(placement
			(enabled no)
			(sheetname "")
		)
		(fill
			(thermal_gap 0.5)
			(thermal_bridge_width 0.5)
			(island_removal_mode 0)
		)
		(polygon
			(pts
				(xy 419.162738 -282.075128) (xy 420.661338 -282.075128) (xy 420.661338 -282.595066) (xy 419.162738 -282.595066)
			)
		)
	)
	(zone
		(layer "In2.Cu")
		(hatch none 0.5)
		(connect_pads
			(clearance 0)
		)
		(min_thickness 0.25)
		(keepout
			(tracks not_allowed)
			(vias allowed)
			(pads allowed)
			(copperpour not_allowed)
			(footprints allowed)
		)
		(placement
			(enabled no)
			(sheetname "")
		)
		(fill
			(thermal_gap 0.5)
			(thermal_bridge_width 0.5)
			(island_removal_mode 0)
		)
		(polygon
			(pts
				(xy 167.778684 -267.625322) (xy 169.277284 -267.625322) (xy 169.277284 -268.14526) (xy 167.778684 -268.14526)
			)
		)
	)
	(zone
		(layer "In2.Cu")
		(hatch none 0.5)
		(connect_pads
			(clearance 0)
		)
		(min_thickness 0.25)
		(keepout
			(tracks not_allowed)
			(vias allowed)
			(pads allowed)
			(copperpour not_allowed)
			(footprints allowed)
		)
		(placement
			(enabled no)
			(sheetname "")
		)
		(fill
			(thermal_gap 0.5)
			(thermal_bridge_width 0.5)
			(island_removal_mode 0)
		)
		(polygon
			(pts
				(xy 171.22267 -213.225126) (xy 172.72127 -213.225126) (xy 172.72127 -213.745064) (xy 171.22267 -213.745064)
			)
		)
	)
	(zone
		(layer "In2.Cu")
		(hatch none 0.5)
		(connect_pads
			(clearance 0)
		)
		(min_thickness 0.25)
		(keepout
			(tracks not_allowed)
			(vias allowed)
			(pads allowed)
			(copperpour not_allowed)
			(footprints allowed)
		)
		(placement
			(enabled no)
			(sheetname "")
		)
		(fill
			(thermal_gap 0.5)
			(thermal_bridge_width 0.5)
			(island_removal_mode 0)
		)
		(polygon
			(pts
				(xy 434.250846 -205.575154) (xy 435.749446 -205.575154) (xy 435.749446 -206.095092) (xy 434.250846 -206.095092)
			)
		)
	)
	(zone
		(layer "In2.Cu")
		(hatch none 0.5)
		(connect_pads
			(clearance 0)
		)
		(min_thickness 0.25)
		(keepout
			(tracks not_allowed)
			(vias allowed)
			(pads allowed)
			(copperpour not_allowed)
			(footprints allowed)
		)
		(placement
			(enabled no)
			(sheetname "")
		)
		(fill
			(thermal_gap 0.5)
			(thermal_bridge_width 0.5)
			(island_removal_mode 0)
		)
		(polygon
			(pts
				(xy 51.134772 -197.075298) (xy 52.633372 -197.075298) (xy 52.633372 -197.595236) (xy 51.134772 -197.595236)
			)
		)
	)
	(zone
		(layer "In2.Cu")
		(hatch none 0.5)
		(connect_pads
			(clearance 0)
		)
		(min_thickness 0.25)
		(keepout
			(tracks not_allowed)
			(vias allowed)
			(pads allowed)
			(copperpour not_allowed)
			(footprints allowed)
		)
		(placement
			(enabled no)
			(sheetname "")
		)
		(fill
			(thermal_gap 0.5)
			(thermal_bridge_width 0.5)
			(island_removal_mode 0)
		)
		(polygon
			(pts
				(xy 445.894968 -267.625322) (xy 447.393568 -267.625322) (xy 447.393568 -268.14526) (xy 445.894968 -268.14526)
			)
		)
	)
	(zone
		(layer "In2.Cu")
		(hatch none 0.5)
		(connect_pads
			(clearance 0)
		)
		(min_thickness 0.25)
		(keepout
			(tracks not_allowed)
			(vias allowed)
			(pads allowed)
			(copperpour not_allowed)
			(footprints allowed)
		)
		(placement
			(enabled no)
			(sheetname "")
		)
		(fill
			(thermal_gap 0.5)
			(thermal_bridge_width 0.5)
			(island_removal_mode 0)
		)
		(polygon
			(pts
				(xy 51.134772 -209.825336) (xy 52.633372 -209.825336) (xy 52.633372 -210.345274) (xy 51.134772 -210.345274)
			)
		)
	)
	(zone
		(layer "In2.Cu")
		(hatch none 0.5)
		(connect_pads
			(clearance 0)
		)
		(min_thickness 0.25)
		(keepout
			(tracks not_allowed)
			(vias allowed)
			(pads allowed)
			(copperpour not_allowed)
			(footprints allowed)
		)
		(placement
			(enabled no)
			(sheetname "")
		)
		(fill
			(thermal_gap 0.5)
			(thermal_bridge_width 0.5)
			(island_removal_mode 0)
		)
		(polygon
			(pts
				(xy 287.430718 -237.02518) (xy 288.929318 -237.02518) (xy 288.929318 -237.545118) (xy 287.430718 -237.545118)
			)
		)
	)
	(zone
		(layer "In2.Cu")
		(hatch none 0.5)
		(connect_pads
			(clearance 0)
		)
		(min_thickness 0.25)
		(keepout
			(tracks not_allowed)
			(vias allowed)
			(pads allowed)
			(copperpour not_allowed)
			(footprints allowed)
		)
		(placement
			(enabled no)
			(sheetname "")
		)
		(fill
			(thermal_gap 0.5)
			(thermal_bridge_width 0.5)
			(island_removal_mode 0)
		)
		(polygon
			(pts
				(xy 423.262806 -264.225278) (xy 424.761406 -264.225278) (xy 424.761406 -264.745216) (xy 423.262806 -264.745216)
			)
		)
	)
	(zone
		(layer "In2.Cu")
		(hatch none 0.5)
		(connect_pads
			(clearance 0)
		)
		(min_thickness 0.25)
		(keepout
			(tracks allowed)
			(vias allowed)
			(pads allowed)
			(copperpour allowed)
			(footprints allowed)
		)
		(placement
			(enabled no)
			(sheetname "")
		)
		(fill
			(thermal_gap 0.5)
			(thermal_bridge_width 0.5)
			(island_removal_mode 0)
		)
		(polygon
			(pts
				(xy 68.09232 -166.331646) (xy 68.09232 -165.785292) (xy 68.64477 -165.785292) (xy 68.64477 -166.331646)
			)
		)
	)
	(zone
		(layer "In2.Cu")
		(hatch none 0.5)
		(connect_pads
			(clearance 0)
		)
		(min_thickness 0.25)
		(keepout
			(tracks not_allowed)
			(vias allowed)
			(pads allowed)
			(copperpour not_allowed)
			(footprints allowed)
		)
		(placement
			(enabled no)
			(sheetname "")
		)
		(fill
			(thermal_gap 0.5)
			(thermal_bridge_width 0.5)
			(island_removal_mode 0)
		)
		(polygon
			(pts
				(xy 54.578758 -248.075196) (xy 56.077358 -248.075196) (xy 56.077358 -248.595134) (xy 54.578758 -248.595134)
			)
		)
	)
	(zone
		(layer "In2.Cu")
		(hatch none 0.5)
		(connect_pads
			(clearance 0)
		)
		(min_thickness 0.25)
		(keepout
			(tracks not_allowed)
			(vias allowed)
			(pads allowed)
			(copperpour not_allowed)
			(footprints allowed)
		)
		(placement
			(enabled no)
			(sheetname "")
		)
		(fill
			(thermal_gap 0.5)
			(thermal_bridge_width 0.5)
			(island_removal_mode 0)
		)
		(polygon
			(pts
				(xy 201.398632 -276.975316) (xy 202.897232 -276.975316) (xy 202.897232 -277.495254) (xy 201.398632 -277.495254)
			)
		)
	)
	(zone
		(layer "In2.Cu")
		(hatch none 0.5)
		(connect_pads
			(clearance 0)
		)
		(min_thickness 0.25)
		(keepout
			(tracks not_allowed)
			(vias allowed)
			(pads allowed)
			(copperpour not_allowed)
			(footprints allowed)
		)
		(placement
			(enabled no)
			(sheetname "")
		)
		(fill
			(thermal_gap 0.5)
			(thermal_bridge_width 0.5)
			(island_removal_mode 0)
		)
		(polygon
			(pts
				(xy 426.706792 -197.925182) (xy 428.205392 -197.925182) (xy 428.205392 -198.44512) (xy 426.706792 -198.44512)
			)
		)
	)
	(zone
		(layer "In2.Cu")
		(hatch none 0.5)
		(connect_pads
			(clearance 0)
		)
		(min_thickness 0.25)
		(keepout
			(tracks not_allowed)
			(vias allowed)
			(pads allowed)
			(copperpour not_allowed)
			(footprints allowed)
		)
		(placement
			(enabled no)
			(sheetname "")
		)
		(fill
			(thermal_gap 0.5)
			(thermal_bridge_width 0.5)
			(island_removal_mode 0)
		)
		(polygon
			(pts
				(xy 423.262806 -296.525188) (xy 424.761406 -296.525188) (xy 424.761406 -297.045126) (xy 423.262806 -297.045126)
			)
		)
	)
	(zone
		(layer "In2.Cu")
		(hatch none 0.5)
		(connect_pads
			(clearance 0)
		)
		(min_thickness 0.25)
		(keepout
			(tracks not_allowed)
			(vias allowed)
			(pads allowed)
			(copperpour not_allowed)
			(footprints allowed)
		)
		(placement
			(enabled no)
			(sheetname "")
		)
		(fill
			(thermal_gap 0.5)
			(thermal_bridge_width 0.5)
			(island_removal_mode 0)
		)
		(polygon
			(pts
				(arc
					(start 40.768524 -17.966436)
					(mid 40.790842 -18.020318)
					(end 40.844724 -18.042636)
				)
				(arc
					(start 41.040304 -18.042636)
					(mid 41.06218 -18.039504)
					(end 41.082214 -18.03019)
				)
				(arc
					(start 41.375838 -17.837658)
					(mid 41.417494 -17.825256)
					(end 41.45915 -17.837658)
				)
				(arc
					(start 41.754044 -18.03019)
					(mid 41.773968 -18.039426)
					(end 41.7957 -18.042636)
				)
				(arc
					(start 41.990264 -18.042636)
					(mid 42.044146 -18.020318)
					(end 42.066464 -17.966436)
				)
				(arc
					(start 42.066464 -17.280636)
					(mid 42.044146 -17.226754)
					(end 41.990264 -17.204436)
				)
				(arc
					(start 41.7957 -17.204436)
					(mid 41.773956 -17.207604)
					(end 41.754044 -17.216882)
				)
				(arc
					(start 41.45788 -17.409668)
					(mid 41.416196 -17.42189)
					(end 41.374568 -17.409414)
				)
				(arc
					(start 41.080944 -17.216882)
					(mid 41.06102 -17.207646)
					(end 41.039288 -17.204436)
				)
				(arc
					(start 40.844724 -17.204436)
					(mid 40.790842 -17.226754)
					(end 40.768524 -17.280636)
				)
			)
		)
	)
	(zone
		(layer "In2.Cu")
		(hatch none 0.5)
		(connect_pads
			(clearance 0)
		)
		(min_thickness 0.25)
		(keepout
			(tracks not_allowed)
			(vias allowed)
			(pads allowed)
			(copperpour not_allowed)
			(footprints allowed)
		)
		(placement
			(enabled no)
			(sheetname "")
		)
		(fill
			(thermal_gap 0.5)
			(thermal_bridge_width 0.5)
			(island_removal_mode 0)
		)
		(polygon
			(pts
				(xy 276.442932 -307.575204) (xy 277.941532 -307.575204) (xy 277.941532 -308.095142) (xy 276.442932 -308.095142)
			)
		)
	)
	(zone
		(layer "In2.Cu")
		(hatch none 0.5)
		(connect_pads
			(clearance 0)
		)
		(min_thickness 0.25)
		(keepout
			(tracks not_allowed)
			(vias allowed)
			(pads allowed)
			(copperpour not_allowed)
			(footprints allowed)
		)
		(placement
			(enabled no)
			(sheetname "")
		)
		(fill
			(thermal_gap 0.5)
			(thermal_bridge_width 0.5)
			(island_removal_mode 0)
		)
		(polygon
			(pts
				(xy 201.398632 -211.525104) (xy 202.897232 -211.525104) (xy 202.897232 -212.045042) (xy 201.398632 -212.045042)
			)
		)
	)
	(zone
		(layer "In2.Cu")
		(hatch none 0.5)
		(connect_pads
			(clearance 0)
		)
		(min_thickness 0.25)
		(keepout
			(tracks allowed)
			(vias allowed)
			(pads allowed)
			(copperpour allowed)
			(footprints allowed)
		)
		(placement
			(enabled no)
			(sheetname "")
		)
		(fill
			(thermal_gap 0.5)
			(thermal_bridge_width 0.5)
			(island_removal_mode 0)
		)
		(polygon
			(pts
				(xy 100.10775 -340.826852) (xy 100.10775 -341.644732) (xy 99.98837 -341.644732) (xy 99.98837 -340.826852)
			)
		)
	)
	(zone
		(layer "In2.Cu")
		(hatch none 0.5)
		(connect_pads
			(clearance 0)
		)
		(min_thickness 0.25)
		(keepout
			(tracks not_allowed)
			(vias allowed)
			(pads allowed)
			(copperpour not_allowed)
			(footprints allowed)
		)
		(placement
			(enabled no)
			(sheetname "")
		)
		(fill
			(thermal_gap 0.5)
			(thermal_bridge_width 0.5)
			(island_removal_mode 0)
		)
		(polygon
			(pts
				(xy 294.974772 -210.67522) (xy 296.473372 -210.67522) (xy 296.473372 -211.195158) (xy 294.974772 -211.195158)
			)
		)
	)
	(zone
		(layer "In2.Cu")
		(hatch none 0.5)
		(connect_pads
			(clearance 0)
		)
		(min_thickness 0.25)
		(keepout
			(tracks not_allowed)
			(vias allowed)
			(pads allowed)
			(copperpour not_allowed)
			(footprints allowed)
		)
		(placement
			(enabled no)
			(sheetname "")
		)
		(fill
			(thermal_gap 0.5)
			(thermal_bridge_width 0.5)
			(island_removal_mode 0)
		)
		(polygon
			(pts
				(xy 190.410846 -242.125246) (xy 191.909446 -242.125246) (xy 191.909446 -242.645184) (xy 190.410846 -242.645184)
			)
		)
	)
	(zone
		(layer "In2.Cu")
		(hatch none 0.5)
		(connect_pads
			(clearance 0)
		)
		(min_thickness 0.25)
		(keepout
			(tracks allowed)
			(vias allowed)
			(pads allowed)
			(copperpour allowed)
			(footprints allowed)
		)
		(placement
			(enabled no)
			(sheetname "")
		)
		(fill
			(thermal_gap 0.5)
			(thermal_bridge_width 0.5)
			(island_removal_mode 0)
		)
		(polygon
			(pts
				(xy 279.810972 -349.93834) (xy 279.810972 -349.31604) (xy 280.362152 -349.31604) (xy 280.362152 -349.93834)
			)
		)
	)
	(zone
		(layer "In2.Cu")
		(hatch none 0.5)
		(connect_pads
			(clearance 0)
		)
		(min_thickness 0.25)
		(keepout
			(tracks not_allowed)
			(vias allowed)
			(pads allowed)
			(copperpour not_allowed)
			(footprints allowed)
		)
		(placement
			(enabled no)
			(sheetname "")
		)
		(fill
			(thermal_gap 0.5)
			(thermal_bridge_width 0.5)
			(island_removal_mode 0)
		)
		(polygon
			(pts
				(xy 306.618894 -285.475172) (xy 308.117494 -285.475172) (xy 308.117494 -285.99511) (xy 306.618894 -285.99511)
			)
		)
	)
	(zone
		(layer "In2.Cu")
		(hatch none 0.5)
		(connect_pads
			(clearance 0)
		)
		(min_thickness 0.25)
		(keepout
			(tracks not_allowed)
			(vias allowed)
			(pads allowed)
			(copperpour not_allowed)
			(footprints allowed)
		)
		(placement
			(enabled no)
			(sheetname "")
		)
		(fill
			(thermal_gap 0.5)
			(thermal_bridge_width 0.5)
			(island_removal_mode 0)
		)
		(polygon
			(pts
				(xy 449.3387 -208.975198) (xy 450.8373 -208.975198) (xy 450.8373 -209.495136) (xy 449.3387 -209.495136)
			)
		)
	)
	(zone
		(layer "In2.Cu")
		(hatch none 0.5)
		(connect_pads
			(clearance 0)
		)
		(min_thickness 0.25)
		(keepout
			(tracks not_allowed)
			(vias allowed)
			(pads allowed)
			(copperpour not_allowed)
			(footprints allowed)
		)
		(placement
			(enabled no)
			(sheetname "")
		)
		(fill
			(thermal_gap 0.5)
			(thermal_bridge_width 0.5)
			(island_removal_mode 0)
		)
		(polygon
			(pts
				(xy 163.678616 -210.67522) (xy 165.177216 -210.67522) (xy 165.177216 -211.195158) (xy 163.678616 -211.195158)
			)
		)
	)
	(zone
		(layer "In2.Cu")
		(hatch none 0.5)
		(connect_pads
			(clearance 0)
		)
		(min_thickness 0.25)
		(keepout
			(tracks not_allowed)
			(vias allowed)
			(pads allowed)
			(copperpour not_allowed)
			(footprints allowed)
		)
		(placement
			(enabled no)
			(sheetname "")
		)
		(fill
			(thermal_gap 0.5)
			(thermal_bridge_width 0.5)
			(island_removal_mode 0)
		)
		(polygon
			(pts
				(xy 438.350914 -232.775252) (xy 439.849514 -232.775252) (xy 439.849514 -233.29519) (xy 438.350914 -233.29519)
			)
		)
	)
	(zone
		(layer "In2.Cu")
		(hatch none 0.5)
		(connect_pads
			(clearance 0)
		)
		(min_thickness 0.25)
		(keepout
			(tracks not_allowed)
			(vias allowed)
			(pads allowed)
			(copperpour not_allowed)
			(footprints allowed)
		)
		(placement
			(enabled no)
			(sheetname "")
		)
		(fill
			(thermal_gap 0.5)
			(thermal_bridge_width 0.5)
			(island_removal_mode 0)
		)
		(polygon
			(pts
				(xy 201.398632 -297.375326) (xy 202.897232 -297.375326) (xy 202.897232 -297.895264) (xy 201.398632 -297.895264)
			)
		)
	)
	(zone
		(layer "In2.Cu")
		(hatch none 0.5)
		(connect_pads
			(clearance 0)
		)
		(min_thickness 0.25)
		(keepout
			(tracks not_allowed)
			(vias allowed)
			(pads allowed)
			(copperpour not_allowed)
			(footprints allowed)
		)
		(placement
			(enabled no)
			(sheetname "")
		)
		(fill
			(thermal_gap 0.5)
			(thermal_bridge_width 0.5)
			(island_removal_mode 0)
		)
		(polygon
			(pts
				(xy 28.50261 -217.475308) (xy 30.00121 -217.475308) (xy 30.00121 -217.995246) (xy 28.50261 -217.995246)
			)
		)
	)
	(zone
		(layer "In2.Cu")
		(hatch none 0.5)
		(connect_pads
			(clearance 0)
		)
		(min_thickness 0.25)
		(keepout
			(tracks allowed)
			(vias allowed)
			(pads allowed)
			(copperpour allowed)
			(footprints allowed)
		)
		(placement
			(enabled no)
			(sheetname "")
		)
		(fill
			(thermal_gap 0.5)
			(thermal_bridge_width 0.5)
			(island_removal_mode 0)
		)
		(polygon
			(pts
				(xy 86.690962 -180.162962) (xy 86.690962 -179.616608) (xy 87.243412 -179.616608) (xy 87.243412 -180.162962)
			)
		)
	)
	(zone
		(layer "In2.Cu")
		(hatch none 0.5)
		(connect_pads
			(clearance 0)
		)
		(min_thickness 0.25)
		(keepout
			(tracks not_allowed)
			(vias allowed)
			(pads allowed)
			(copperpour not_allowed)
			(footprints allowed)
		)
		(placement
			(enabled no)
			(sheetname "")
		)
		(fill
			(thermal_gap 0.5)
			(thermal_bridge_width 0.5)
			(island_removal_mode 0)
		)
		(polygon
			(pts
				(xy 193.854578 -278.675338) (xy 195.353178 -278.675338) (xy 195.353178 -279.195276) (xy 193.854578 -279.195276)
			)
		)
	)
	(zone
		(layer "In2.Cu")
		(hatch none 0.5)
		(connect_pads
			(clearance 0)
		)
		(min_thickness 0.25)
		(keepout
			(tracks not_allowed)
			(vias allowed)
			(pads allowed)
			(copperpour not_allowed)
			(footprints allowed)
		)
		(placement
			(enabled no)
			(sheetname "")
		)
		(fill
			(thermal_gap 0.5)
			(thermal_bridge_width 0.5)
			(island_removal_mode 0)
		)
		(polygon
			(pts
				(xy 449.3387 -286.32531) (xy 450.8373 -286.32531) (xy 450.8373 -286.845248) (xy 449.3387 -286.845248)
			)
		)
	)
	(zone
		(layer "In2.Cu")
		(hatch none 0.5)
		(connect_pads
			(clearance 0)
		)
		(min_thickness 0.25)
		(keepout
			(tracks not_allowed)
			(vias allowed)
			(pads allowed)
			(copperpour not_allowed)
			(footprints allowed)
		)
		(placement
			(enabled no)
			(sheetname "")
		)
		(fill
			(thermal_gap 0.5)
			(thermal_bridge_width 0.5)
			(island_removal_mode 0)
		)
		(polygon
			(pts
				(xy 163.678616 -231.925114) (xy 165.177216 -231.925114) (xy 165.177216 -232.445052) (xy 163.678616 -232.445052)
			)
		)
	)
	(zone
		(layer "In2.Cu")
		(hatch none 0.5)
		(connect_pads
			(clearance 0)
		)
		(min_thickness 0.25)
		(keepout
			(tracks not_allowed)
			(vias allowed)
			(pads allowed)
			(copperpour not_allowed)
			(footprints allowed)
		)
		(placement
			(enabled no)
			(sheetname "")
		)
		(fill
			(thermal_gap 0.5)
			(thermal_bridge_width 0.5)
			(island_removal_mode 0)
		)
		(polygon
			(pts
				(xy 291.530786 -212.375242) (xy 293.029386 -212.375242) (xy 293.029386 -212.89518) (xy 291.530786 -212.89518)
			)
		)
	)
	(zone
		(layer "In2.Cu")
		(hatch none 0.5)
		(connect_pads
			(clearance 0)
		)
		(min_thickness 0.25)
		(keepout
			(tracks not_allowed)
			(vias allowed)
			(pads allowed)
			(copperpour not_allowed)
			(footprints allowed)
		)
		(placement
			(enabled no)
			(sheetname "")
		)
		(fill
			(thermal_gap 0.5)
			(thermal_bridge_width 0.5)
			(island_removal_mode 0)
		)
		(polygon
			(pts
				(xy 193.854578 -238.725202) (xy 195.353178 -238.725202) (xy 195.353178 -239.24514) (xy 193.854578 -239.24514)
			)
		)
	)
	(zone
		(layer "In2.Cu")
		(hatch none 0.5)
		(connect_pads
			(clearance 0)
		)
		(min_thickness 0.25)
		(keepout
			(tracks not_allowed)
			(vias allowed)
			(pads allowed)
			(copperpour not_allowed)
			(footprints allowed)
		)
		(placement
			(enabled no)
			(sheetname "")
		)
		(fill
			(thermal_gap 0.5)
			(thermal_bridge_width 0.5)
			(island_removal_mode 0)
		)
		(polygon
			(pts
				(xy 51.134772 -316.925198) (xy 52.633372 -316.925198) (xy 52.633372 -317.445136) (xy 51.134772 -317.445136)
			)
		)
	)
	(zone
		(layer "In2.Cu")
		(hatch none 0.5)
		(connect_pads
			(clearance 0)
		)
		(min_thickness 0.25)
		(keepout
			(tracks not_allowed)
			(vias allowed)
			(pads allowed)
			(copperpour not_allowed)
			(footprints allowed)
		)
		(placement
			(enabled no)
			(sheetname "")
		)
		(fill
			(thermal_gap 0.5)
			(thermal_bridge_width 0.5)
			(island_removal_mode 0)
		)
		(polygon
			(pts
				(xy 445.894968 -208.125314) (xy 447.393568 -208.125314) (xy 447.393568 -208.645252) (xy 445.894968 -208.645252)
			)
		)
	)
	(zone
		(layer "In2.Cu")
		(hatch none 0.5)
		(connect_pads
			(clearance 0)
		)
		(min_thickness 0.25)
		(keepout
			(tracks not_allowed)
			(vias allowed)
			(pads allowed)
			(copperpour not_allowed)
			(footprints allowed)
		)
		(placement
			(enabled no)
			(sheetname "")
		)
		(fill
			(thermal_gap 0.5)
			(thermal_bridge_width 0.5)
			(island_removal_mode 0)
		)
		(polygon
			(pts
				(xy 415.718752 -296.525188) (xy 417.217352 -296.525188) (xy 417.217352 -297.045126) (xy 415.718752 -297.045126)
			)
		)
	)
	(zone
		(layer "In2.Cu")
		(hatch none 0.5)
		(connect_pads
			(clearance 0)
		)
		(min_thickness 0.25)
		(keepout
			(tracks not_allowed)
			(vias allowed)
			(pads allowed)
			(copperpour not_allowed)
			(footprints allowed)
		)
		(placement
			(enabled no)
			(sheetname "")
		)
		(fill
			(thermal_gap 0.5)
			(thermal_bridge_width 0.5)
			(island_removal_mode 0)
		)
		(polygon
			(pts
				(xy 423.262806 -210.67522) (xy 424.761406 -210.67522) (xy 424.761406 -211.195158) (xy 423.262806 -211.195158)
			)
		)
	)
	(zone
		(layer "In2.Cu")
		(hatch none 0.5)
		(connect_pads
			(clearance 0)
		)
		(min_thickness 0.25)
		(keepout
			(tracks allowed)
			(vias allowed)
			(pads allowed)
			(copperpour allowed)
			(footprints allowed)
		)
		(placement
			(enabled no)
			(sheetname "")
		)
		(fill
			(thermal_gap 0.5)
			(thermal_bridge_width 0.5)
			(island_removal_mode 0)
		)
		(polygon
			(pts
				(xy 48.61941 -349.859092) (xy 48.61941 -349.236792) (xy 49.17059 -349.236792) (xy 49.17059 -349.859092)
			)
		)
	)
	(zone
		(layer "In2.Cu")
		(hatch none 0.5)
		(connect_pads
			(clearance 0)
		)
		(min_thickness 0.25)
		(keepout
			(tracks not_allowed)
			(vias allowed)
			(pads allowed)
			(copperpour not_allowed)
			(footprints allowed)
		)
		(placement
			(enabled no)
			(sheetname "")
		)
		(fill
			(thermal_gap 0.5)
			(thermal_bridge_width 0.5)
			(island_removal_mode 0)
		)
		(polygon
			(pts
				(xy 171.22267 -230.225346) (xy 172.72127 -230.225346) (xy 172.72127 -230.745284) (xy 171.22267 -230.745284)
			)
		)
	)
	(zone
		(layer "In2.Cu")
		(hatch none 0.5)
		(connect_pads
			(clearance 0)
		)
		(min_thickness 0.25)
		(keepout
			(tracks not_allowed)
			(vias allowed)
			(pads allowed)
			(copperpour not_allowed)
			(footprints allowed)
		)
		(placement
			(enabled no)
			(sheetname "")
		)
		(fill
			(thermal_gap 0.5)
			(thermal_bridge_width 0.5)
			(island_removal_mode 0)
		)
		(polygon
			(pts
				(xy 175.322738 -271.87525) (xy 176.821338 -271.87525) (xy 176.821338 -272.395188) (xy 175.322738 -272.395188)
			)
		)
	)
	(zone
		(layer "In2.Cu")
		(hatch none 0.5)
		(connect_pads
			(clearance 0)
		)
		(min_thickness 0.25)
		(keepout
			(tracks not_allowed)
			(vias allowed)
			(pads allowed)
			(copperpour not_allowed)
			(footprints allowed)
		)
		(placement
			(enabled no)
			(sheetname "")
		)
		(fill
			(thermal_gap 0.5)
			(thermal_bridge_width 0.5)
			(island_removal_mode 0)
		)
		(polygon
			(pts
				(xy 20.95881 -307.575204) (xy 22.45741 -307.575204) (xy 22.45741 -308.095142) (xy 20.95881 -308.095142)
			)
		)
	)
	(zone
		(layer "In2.Cu")
		(hatch none 0.5)
		(connect_pads
			(clearance 0)
		)
		(min_thickness 0.25)
		(keepout
			(tracks not_allowed)
			(vias allowed)
			(pads allowed)
			(copperpour not_allowed)
			(footprints allowed)
		)
		(placement
			(enabled no)
			(sheetname "")
		)
		(fill
			(thermal_gap 0.5)
			(thermal_bridge_width 0.5)
			(island_removal_mode 0)
		)
		(polygon
			(pts
				(xy 453.438768 -313.525154) (xy 454.937368 -313.525154) (xy 454.937368 -314.045092) (xy 453.438768 -314.045092)
			)
		)
	)
	(zone
		(layer "In2.Cu")
		(hatch none 0.5)
		(connect_pads
			(clearance 0)
		)
		(min_thickness 0.25)
		(keepout
			(tracks allowed)
			(vias allowed)
			(pads allowed)
			(copperpour allowed)
			(footprints allowed)
		)
		(placement
			(enabled no)
			(sheetname "")
		)
		(fill
			(thermal_gap 0.5)
			(thermal_bridge_width 0.5)
			(island_removal_mode 0)
		)
		(polygon
			(pts
				(xy 304.804572 -349.93834) (xy 304.804572 -349.31604) (xy 305.355752 -349.31604) (xy 305.355752 -349.93834)
			)
		)
	)
	(zone
		(layer "In2.Cu")
		(hatch none 0.5)
		(connect_pads
			(clearance 0)
		)
		(min_thickness 0.25)
		(keepout
			(tracks not_allowed)
			(vias allowed)
			(pads allowed)
			(copperpour not_allowed)
			(footprints allowed)
		)
		(placement
			(enabled no)
			(sheetname "")
		)
		(fill
			(thermal_gap 0.5)
			(thermal_bridge_width 0.5)
			(island_removal_mode 0)
		)
		(polygon
			(pts
				(xy 453.438768 -204.72527) (xy 454.937368 -204.72527) (xy 454.937368 -205.245208) (xy 453.438768 -205.245208)
			)
		)
	)
	(zone
		(layer "In2.Cu")
		(hatch none 0.5)
		(connect_pads
			(clearance 0)
		)
		(min_thickness 0.25)
		(keepout
			(tracks not_allowed)
			(vias allowed)
			(pads allowed)
			(copperpour not_allowed)
			(footprints allowed)
		)
		(placement
			(enabled no)
			(sheetname "")
		)
		(fill
			(thermal_gap 0.5)
			(thermal_bridge_width 0.5)
			(island_removal_mode 0)
		)
		(polygon
			(pts
				(xy 28.50261 -214.075264) (xy 30.00121 -214.075264) (xy 30.00121 -214.595202) (xy 28.50261 -214.595202)
			)
		)
	)
	(zone
		(layer "In2.Cu")
		(hatch none 0.5)
		(connect_pads
			(clearance 0)
		)
		(min_thickness 0.25)
		(keepout
			(tracks allowed)
			(vias allowed)
			(pads allowed)
			(copperpour allowed)
			(footprints allowed)
		)
		(placement
			(enabled no)
			(sheetname "")
		)
		(fill
			(thermal_gap 0.5)
			(thermal_bridge_width 0.5)
			(island_removal_mode 0)
		)
		(polygon
			(pts
				(xy 268.774418 -332.201012) (xy 267.326618 -332.201012) (xy 267.174218 -332.353412) (xy 267.174218 -332.785212)
				(xy 267.352018 -332.963012) (xy 268.545818 -332.963012) (xy 269.206218 -333.623412) (xy 269.206218 -345.561412)
				(xy 269.409418 -345.764612) (xy 269.409418 -349.447612) (xy 267.479018 -351.378012) (xy 267.479018 -353.689412)
				(xy 279.086818 -365.297212) (xy 302.556418 -365.297212) (xy 302.886618 -364.967012) (xy 302.886618 -364.789212)
				(xy 302.531018 -364.433612) (xy 279.391618 -364.433612) (xy 268.317218 -353.359212) (xy 268.317218 -351.581212)
				(xy 270.222218 -349.676212) (xy 270.222218 -345.358212) (xy 269.968218 -345.104212) (xy 269.968218 -333.394812)
			)
		)
	)
	(zone
		(layer "In2.Cu")
		(hatch none 0.5)
		(connect_pads
			(clearance 0)
		)
		(min_thickness 0.25)
		(keepout
			(tracks not_allowed)
			(vias allowed)
			(pads allowed)
			(copperpour not_allowed)
			(footprints allowed)
		)
		(placement
			(enabled no)
			(sheetname "")
		)
		(fill
			(thermal_gap 0.5)
			(thermal_bridge_width 0.5)
			(island_removal_mode 0)
		)
		(polygon
			(pts
				(xy 426.706792 -261.675118) (xy 428.205392 -261.675118) (xy 428.205392 -262.195056) (xy 426.706792 -262.195056)
			)
		)
	)
	(zone
		(layer "In2.Cu")
		(hatch none 0.5)
		(connect_pads
			(clearance 0)
		)
		(min_thickness 0.25)
		(keepout
			(tracks not_allowed)
			(vias allowed)
			(pads allowed)
			(copperpour not_allowed)
			(footprints allowed)
		)
		(placement
			(enabled no)
			(sheetname "")
		)
		(fill
			(thermal_gap 0.5)
			(thermal_bridge_width 0.5)
			(island_removal_mode 0)
		)
		(polygon
			(pts
				(xy 268.898878 -264.225278) (xy 270.397478 -264.225278) (xy 270.397478 -264.745216) (xy 268.898878 -264.745216)
			)
		)
	)
	(zone
		(layer "In2.Cu")
		(hatch none 0.5)
		(connect_pads
			(clearance 0)
		)
		(min_thickness 0.25)
		(keepout
			(tracks not_allowed)
			(vias allowed)
			(pads allowed)
			(copperpour not_allowed)
			(footprints allowed)
		)
		(placement
			(enabled no)
			(sheetname "")
		)
		(fill
			(thermal_gap 0.5)
			(thermal_bridge_width 0.5)
			(island_removal_mode 0)
		)
		(polygon
			(pts
				(xy 272.342864 -208.975198) (xy 273.841464 -208.975198) (xy 273.841464 -209.495136) (xy 272.342864 -209.495136)
			)
		)
	)
	(zone
		(layer "In2.Cu")
		(hatch none 0.5)
		(connect_pads
			(clearance 0)
		)
		(min_thickness 0.25)
		(keepout
			(tracks not_allowed)
			(vias allowed)
			(pads allowed)
			(copperpour not_allowed)
			(footprints allowed)
		)
		(placement
			(enabled no)
			(sheetname "")
		)
		(fill
			(thermal_gap 0.5)
			(thermal_bridge_width 0.5)
			(island_removal_mode 0)
		)
		(polygon
			(pts
				(xy 16.858742 -224.275142) (xy 18.357342 -224.275142) (xy 18.357342 -224.79508) (xy 16.858742 -224.79508)
			)
		)
	)
	(zone
		(layer "In2.Cu")
		(hatch none 0.5)
		(connect_pads
			(clearance 0)
		)
		(min_thickness 0.25)
		(keepout
			(tracks not_allowed)
			(vias allowed)
			(pads allowed)
			(copperpour not_allowed)
			(footprints allowed)
		)
		(placement
			(enabled no)
			(sheetname "")
		)
		(fill
			(thermal_gap 0.5)
			(thermal_bridge_width 0.5)
			(island_removal_mode 0)
		)
		(polygon
			(pts
				(xy 426.706792 -244.675152) (xy 428.205392 -244.675152) (xy 428.205392 -245.19509) (xy 426.706792 -245.19509)
			)
		)
	)
	(zone
		(layer "In2.Cu")
		(hatch none 0.5)
		(connect_pads
			(clearance 0)
		)
		(min_thickness 0.25)
		(keepout
			(tracks not_allowed)
			(vias allowed)
			(pads allowed)
			(copperpour not_allowed)
			(footprints allowed)
		)
		(placement
			(enabled no)
			(sheetname "")
		)
		(fill
			(thermal_gap 0.5)
			(thermal_bridge_width 0.5)
			(island_removal_mode 0)
		)
		(polygon
			(pts
				(xy 171.22267 -274.425156) (xy 172.72127 -274.425156) (xy 172.72127 -274.945094) (xy 171.22267 -274.945094)
			)
		)
	)
	(zone
		(layer "In2.Cu")
		(hatch none 0.5)
		(connect_pads
			(clearance 0)
		)
		(min_thickness 0.25)
		(keepout
			(tracks not_allowed)
			(vias allowed)
			(pads allowed)
			(copperpour not_allowed)
			(footprints allowed)
		)
		(placement
			(enabled no)
			(sheetname "")
		)
		(fill
			(thermal_gap 0.5)
			(thermal_bridge_width 0.5)
			(island_removal_mode 0)
		)
		(polygon
			(pts
				(xy 434.250846 -199.625204) (xy 435.749446 -199.625204) (xy 435.749446 -200.145142) (xy 434.250846 -200.145142)
			)
		)
	)
	(zone
		(layer "In2.Cu")
		(hatch none 0.5)
		(connect_pads
			(clearance 0)
		)
		(min_thickness 0.25)
		(keepout
			(tracks not_allowed)
			(vias allowed)
			(pads allowed)
			(copperpour not_allowed)
			(footprints allowed)
		)
		(placement
			(enabled no)
			(sheetname "")
		)
		(fill
			(thermal_gap 0.5)
			(thermal_bridge_width 0.5)
			(island_removal_mode 0)
		)
		(polygon
			(pts
				(xy 163.678616 -224.275142) (xy 165.177216 -224.275142) (xy 165.177216 -224.79508) (xy 163.678616 -224.79508)
			)
		)
	)
	(zone
		(layer "In2.Cu")
		(hatch none 0.5)
		(connect_pads
			(clearance 0)
		)
		(min_thickness 0.25)
		(keepout
			(tracks not_allowed)
			(vias allowed)
			(pads allowed)
			(copperpour not_allowed)
			(footprints allowed)
		)
		(placement
			(enabled no)
			(sheetname "")
		)
		(fill
			(thermal_gap 0.5)
			(thermal_bridge_width 0.5)
			(island_removal_mode 0)
		)
		(polygon
			(pts
				(xy 411.618684 -202.17511) (xy 413.117284 -202.17511) (xy 413.117284 -202.695048) (xy 411.618684 -202.695048)
			)
		)
	)
	(zone
		(layer "In2.Cu")
		(hatch none 0.5)
		(connect_pads
			(clearance 0)
		)
		(min_thickness 0.25)
		(keepout
			(tracks not_allowed)
			(vias allowed)
			(pads allowed)
			(copperpour not_allowed)
			(footprints allowed)
		)
		(placement
			(enabled no)
			(sheetname "")
		)
		(fill
			(thermal_gap 0.5)
			(thermal_bridge_width 0.5)
			(island_removal_mode 0)
		)
		(polygon
			(pts
				(xy 47.034704 -308.425342) (xy 48.533304 -308.425342) (xy 48.533304 -308.94528) (xy 47.034704 -308.94528)
			)
		)
	)
	(zone
		(layer "In2.Cu")
		(hatch none 0.5)
		(connect_pads
			(clearance 0)
		)
		(min_thickness 0.25)
		(keepout
			(tracks not_allowed)
			(vias allowed)
			(pads allowed)
			(copperpour not_allowed)
			(footprints allowed)
		)
		(placement
			(enabled no)
			(sheetname "")
		)
		(fill
			(thermal_gap 0.5)
			(thermal_bridge_width 0.5)
			(island_removal_mode 0)
		)
		(polygon
			(pts
				(xy 419.162738 -211.525104) (xy 420.661338 -211.525104) (xy 420.661338 -212.045042) (xy 419.162738 -212.045042)
			)
		)
	)
	(zone
		(layer "In2.Cu")
		(hatch none 0.5)
		(connect_pads
			(clearance 0)
		)
		(min_thickness 0.25)
		(keepout
			(tracks not_allowed)
			(vias allowed)
			(pads allowed)
			(copperpour not_allowed)
			(footprints allowed)
		)
		(placement
			(enabled no)
			(sheetname "")
		)
		(fill
			(thermal_gap 0.5)
			(thermal_bridge_width 0.5)
			(island_removal_mode 0)
		)
		(polygon
			(pts
				(xy 441.7949 -235.325158) (xy 443.2935 -235.325158) (xy 443.2935 -235.845096) (xy 441.7949 -235.845096)
			)
		)
	)
	(zone
		(layer "In2.Cu")
		(hatch none 0.5)
		(connect_pads
			(clearance 0)
		)
		(min_thickness 0.25)
		(keepout
			(tracks not_allowed)
			(vias allowed)
			(pads allowed)
			(copperpour not_allowed)
			(footprints allowed)
		)
		(placement
			(enabled no)
			(sheetname "")
		)
		(fill
			(thermal_gap 0.5)
			(thermal_bridge_width 0.5)
			(island_removal_mode 0)
		)
		(polygon
			(pts
				(xy 419.162738 -263.37514) (xy 420.661338 -263.37514) (xy 420.661338 -263.895078) (xy 419.162738 -263.895078)
			)
		)
	)
	(zone
		(layer "In2.Cu")
		(hatch none 0.5)
		(connect_pads
			(clearance 0)
		)
		(min_thickness 0.25)
		(keepout
			(tracks not_allowed)
			(vias allowed)
			(pads allowed)
			(copperpour not_allowed)
			(footprints allowed)
		)
		(placement
			(enabled no)
			(sheetname "")
		)
		(fill
			(thermal_gap 0.5)
			(thermal_bridge_width 0.5)
			(island_removal_mode 0)
		)
		(polygon
			(pts
				(xy 268.898878 -234.475274) (xy 270.397478 -234.475274) (xy 270.397478 -234.995212) (xy 268.898878 -234.995212)
			)
		)
	)
	(zone
		(layer "In2.Cu")
		(hatch none 0.5)
		(connect_pads
			(clearance 0)
		)
		(min_thickness 0.25)
		(keepout
			(tracks not_allowed)
			(vias allowed)
			(pads allowed)
			(copperpour not_allowed)
			(footprints allowed)
		)
		(placement
			(enabled no)
			(sheetname "")
		)
		(fill
			(thermal_gap 0.5)
			(thermal_bridge_width 0.5)
			(island_removal_mode 0)
		)
		(polygon
			(pts
				(xy 430.80686 -219.17533) (xy 432.30546 -219.17533) (xy 432.30546 -219.695268) (xy 430.80686 -219.695268)
			)
		)
	)
	(zone
		(layer "In2.Cu")
		(hatch none 0.5)
		(connect_pads
			(clearance 0)
		)
		(min_thickness 0.25)
		(keepout
			(tracks not_allowed)
			(vias allowed)
			(pads allowed)
			(copperpour not_allowed)
			(footprints allowed)
		)
		(placement
			(enabled no)
			(sheetname "")
		)
		(fill
			(thermal_gap 0.5)
			(thermal_bridge_width 0.5)
			(island_removal_mode 0)
		)
		(polygon
			(pts
				(xy 20.95881 -285.475172) (xy 22.45741 -285.475172) (xy 22.45741 -285.99511) (xy 20.95881 -285.99511)
			)
		)
	)
	(zone
		(layer "In2.Cu")
		(hatch none 0.5)
		(connect_pads
			(clearance 0)
		)
		(min_thickness 0.25)
		(keepout
			(tracks not_allowed)
			(vias allowed)
			(pads allowed)
			(copperpour not_allowed)
			(footprints allowed)
		)
		(placement
			(enabled no)
			(sheetname "")
		)
		(fill
			(thermal_gap 0.5)
			(thermal_bridge_width 0.5)
			(island_removal_mode 0)
		)
		(polygon
			(pts
				(xy 47.034704 -233.625136) (xy 48.533304 -233.625136) (xy 48.533304 -234.145074) (xy 47.034704 -234.145074)
			)
		)
	)
	(zone
		(layer "In2.Cu")
		(hatch none 0.5)
		(connect_pads
			(clearance 0)
		)
		(min_thickness 0.25)
		(keepout
			(tracks not_allowed)
			(vias allowed)
			(pads allowed)
			(copperpour not_allowed)
			(footprints allowed)
		)
		(placement
			(enabled no)
			(sheetname "")
		)
		(fill
			(thermal_gap 0.5)
			(thermal_bridge_width 0.5)
			(island_removal_mode 0)
		)
		(polygon
			(pts
				(xy 20.95881 -226.825302) (xy 22.45741 -226.825302) (xy 22.45741 -227.34524) (xy 20.95881 -227.34524)
			)
		)
	)
	(zone
		(layer "In2.Cu")
		(hatch none 0.5)
		(connect_pads
			(clearance 0)
		)
		(min_thickness 0.25)
		(keepout
			(tracks not_allowed)
			(vias allowed)
			(pads allowed)
			(copperpour not_allowed)
			(footprints allowed)
		)
		(placement
			(enabled no)
			(sheetname "")
		)
		(fill
			(thermal_gap 0.5)
			(thermal_bridge_width 0.5)
			(island_removal_mode 0)
		)
		(polygon
			(pts
				(xy 51.134772 -273.575272) (xy 52.633372 -273.575272) (xy 52.633372 -274.09521) (xy 51.134772 -274.09521)
			)
		)
	)
	(zone
		(layer "In2.Cu")
		(hatch none 0.5)
		(connect_pads
			(clearance 0)
		)
		(min_thickness 0.25)
		(keepout
			(tracks not_allowed)
			(vias allowed)
			(pads allowed)
			(copperpour not_allowed)
			(footprints allowed)
		)
		(placement
			(enabled no)
			(sheetname "")
		)
		(fill
			(thermal_gap 0.5)
			(thermal_bridge_width 0.5)
			(island_removal_mode 0)
		)
		(polygon
			(pts
				(xy 423.262806 -312.67527) (xy 424.761406 -312.67527) (xy 424.761406 -313.195208) (xy 423.262806 -313.195208)
			)
		)
	)
	(zone
		(layer "In2.Cu")
		(hatch none 0.5)
		(connect_pads
			(clearance 0)
		)
		(min_thickness 0.25)
		(keepout
			(tracks not_allowed)
			(vias allowed)
			(pads allowed)
			(copperpour not_allowed)
			(footprints allowed)
		)
		(placement
			(enabled no)
			(sheetname "")
		)
		(fill
			(thermal_gap 0.5)
			(thermal_bridge_width 0.5)
			(island_removal_mode 0)
		)
		(polygon
			(pts
				(xy 51.134772 -298.22521) (xy 52.633372 -298.22521) (xy 52.633372 -298.745148) (xy 51.134772 -298.745148)
			)
		)
	)
	(zone
		(layer "In2.Cu")
		(hatch none 0.5)
		(connect_pads
			(clearance 0)
		)
		(min_thickness 0.25)
		(keepout
			(tracks not_allowed)
			(vias allowed)
			(pads allowed)
			(copperpour not_allowed)
			(footprints allowed)
		)
		(placement
			(enabled no)
			(sheetname "")
		)
		(fill
			(thermal_gap 0.5)
			(thermal_bridge_width 0.5)
			(island_removal_mode 0)
		)
		(polygon
			(pts
				(xy 430.80686 -265.9253) (xy 432.30546 -265.9253) (xy 432.30546 -266.445238) (xy 430.80686 -266.445238)
			)
		)
	)
	(zone
		(layer "In2.Cu")
		(hatch none 0.5)
		(connect_pads
			(clearance 0)
		)
		(min_thickness 0.25)
		(keepout
			(tracks not_allowed)
			(vias allowed)
			(pads allowed)
			(copperpour not_allowed)
			(footprints allowed)
		)
		(placement
			(enabled no)
			(sheetname "")
		)
		(fill
			(thermal_gap 0.5)
			(thermal_bridge_width 0.5)
			(island_removal_mode 0)
		)
		(polygon
			(pts
				(xy 419.162738 -305.025298) (xy 420.661338 -305.025298) (xy 420.661338 -305.545236) (xy 419.162738 -305.545236)
			)
		)
	)
	(zone
		(layer "In2.Cu")
		(hatch none 0.5)
		(connect_pads
			(clearance 0)
		)
		(min_thickness 0.25)
		(keepout
			(tracks not_allowed)
			(vias allowed)
			(pads allowed)
			(copperpour not_allowed)
			(footprints allowed)
		)
		(placement
			(enabled no)
			(sheetname "")
		)
		(fill
			(thermal_gap 0.5)
			(thermal_bridge_width 0.5)
			(island_removal_mode 0)
		)
		(polygon
			(pts
				(xy 419.162738 -203.875132) (xy 420.661338 -203.875132) (xy 420.661338 -204.39507) (xy 419.162738 -204.39507)
			)
		)
	)
	(zone
		(layer "In2.Cu")
		(hatch none 0.5)
		(connect_pads
			(clearance 0)
		)
		(min_thickness 0.25)
		(keepout
			(tracks not_allowed)
			(vias allowed)
			(pads allowed)
			(copperpour not_allowed)
			(footprints allowed)
		)
		(placement
			(enabled no)
			(sheetname "")
		)
		(fill
			(thermal_gap 0.5)
			(thermal_bridge_width 0.5)
			(island_removal_mode 0)
		)
		(polygon
			(pts
				(xy 306.618894 -290.575238) (xy 308.117494 -290.575238) (xy 308.117494 -291.095176) (xy 306.618894 -291.095176)
			)
		)
	)
	(zone
		(layer "In2.Cu")
		(hatch none 0.5)
		(connect_pads
			(clearance 0)
		)
		(min_thickness 0.25)
		(keepout
			(tracks not_allowed)
			(vias allowed)
			(pads allowed)
			(copperpour not_allowed)
			(footprints allowed)
		)
		(placement
			(enabled no)
			(sheetname "")
		)
		(fill
			(thermal_gap 0.5)
			(thermal_bridge_width 0.5)
			(island_removal_mode 0)
		)
		(polygon
			(pts
				(xy 276.442932 -252.325124) (xy 277.941532 -252.325124) (xy 277.941532 -252.845062) (xy 276.442932 -252.845062)
			)
		)
	)
	(zone
		(layer "In2.Cu")
		(hatch none 0.5)
		(connect_pads
			(clearance 0)
		)
		(min_thickness 0.25)
		(keepout
			(tracks not_allowed)
			(vias allowed)
			(pads allowed)
			(copperpour not_allowed)
			(footprints allowed)
		)
		(placement
			(enabled no)
			(sheetname "")
		)
		(fill
			(thermal_gap 0.5)
			(thermal_bridge_width 0.5)
			(island_removal_mode 0)
		)
		(polygon
			(pts
				(xy 54.578758 -313.525154) (xy 56.077358 -313.525154) (xy 56.077358 -314.045092) (xy 54.578758 -314.045092)
			)
		)
	)
	(zone
		(layer "In2.Cu")
		(hatch none 0.5)
		(connect_pads
			(clearance 0)
		)
		(min_thickness 0.25)
		(keepout
			(tracks not_allowed)
			(vias allowed)
			(pads allowed)
			(copperpour not_allowed)
			(footprints allowed)
		)
		(placement
			(enabled no)
			(sheetname "")
		)
		(fill
			(thermal_gap 0.5)
			(thermal_bridge_width 0.5)
			(island_removal_mode 0)
		)
		(polygon
			(pts
				(xy 190.410846 -270.175228) (xy 191.909446 -270.175228) (xy 191.909446 -270.695166) (xy 190.410846 -270.695166)
			)
		)
	)
	(zone
		(layer "In2.Cu")
		(hatch none 0.5)
		(connect_pads
			(clearance 0)
		)
		(min_thickness 0.25)
		(keepout
			(tracks not_allowed)
			(vias allowed)
			(pads allowed)
			(copperpour not_allowed)
			(footprints allowed)
		)
		(placement
			(enabled no)
			(sheetname "")
		)
		(fill
			(thermal_gap 0.5)
			(thermal_bridge_width 0.5)
			(island_removal_mode 0)
		)
		(polygon
			(pts
				(xy 201.398632 -238.725202) (xy 202.897232 -238.725202) (xy 202.897232 -239.24514) (xy 201.398632 -239.24514)
			)
		)
	)
	(zone
		(layer "In2.Cu")
		(hatch none 0.5)
		(connect_pads
			(clearance 0)
		)
		(min_thickness 0.25)
		(keepout
			(tracks not_allowed)
			(vias allowed)
			(pads allowed)
			(copperpour not_allowed)
			(footprints allowed)
		)
		(placement
			(enabled no)
			(sheetname "")
		)
		(fill
			(thermal_gap 0.5)
			(thermal_bridge_width 0.5)
			(island_removal_mode 0)
		)
		(polygon
			(pts
				(xy 411.618684 -230.225346) (xy 413.117284 -230.225346) (xy 413.117284 -230.745284) (xy 411.618684 -230.745284)
			)
		)
	)
	(zone
		(layer "In2.Cu")
		(hatch none 0.5)
		(connect_pads
			(clearance 0)
		)
		(min_thickness 0.25)
		(keepout
			(tracks not_allowed)
			(vias allowed)
			(pads allowed)
			(copperpour not_allowed)
			(footprints allowed)
		)
		(placement
			(enabled no)
			(sheetname "")
		)
		(fill
			(thermal_gap 0.5)
			(thermal_bridge_width 0.5)
			(island_removal_mode 0)
		)
		(polygon
			(pts
				(xy 186.310778 -317.775336) (xy 187.809378 -317.775336) (xy 187.809378 -318.295274) (xy 186.310778 -318.295274)
			)
		)
	)
	(zone
		(layer "In2.Cu")
		(hatch none 0.5)
		(connect_pads
			(clearance 0)
		)
		(min_thickness 0.25)
		(keepout
			(tracks not_allowed)
			(vias allowed)
			(pads allowed)
			(copperpour not_allowed)
			(footprints allowed)
		)
		(placement
			(enabled no)
			(sheetname "")
		)
		(fill
			(thermal_gap 0.5)
			(thermal_bridge_width 0.5)
			(island_removal_mode 0)
		)
		(polygon
			(pts
				(xy 272.342864 -213.225126) (xy 273.841464 -213.225126) (xy 273.841464 -213.745064) (xy 272.342864 -213.745064)
			)
		)
	)
	(zone
		(layer "In2.Cu")
		(hatch none 0.5)
		(connect_pads
			(clearance 0)
		)
		(min_thickness 0.25)
		(keepout
			(tracks not_allowed)
			(vias allowed)
			(pads allowed)
			(copperpour not_allowed)
			(footprints allowed)
		)
		(placement
			(enabled no)
			(sheetname "")
		)
		(fill
			(thermal_gap 0.5)
			(thermal_bridge_width 0.5)
			(island_removal_mode 0)
		)
		(polygon
			(pts
				(xy 430.80686 -262.525256) (xy 432.30546 -262.525256) (xy 432.30546 -263.045194) (xy 430.80686 -263.045194)
			)
		)
	)
	(zone
		(layer "In2.Cu")
		(hatch none 0.5)
		(connect_pads
			(clearance 0)
		)
		(min_thickness 0.25)
		(keepout
			(tracks not_allowed)
			(vias allowed)
			(pads allowed)
			(copperpour not_allowed)
			(footprints allowed)
		)
		(placement
			(enabled no)
			(sheetname "")
		)
		(fill
			(thermal_gap 0.5)
			(thermal_bridge_width 0.5)
			(island_removal_mode 0)
		)
		(polygon
			(pts
				(xy 268.898878 -198.77532) (xy 270.397478 -198.77532) (xy 270.397478 -199.295258) (xy 268.898878 -199.295258)
			)
		)
	)
	(zone
		(layer "In2.Cu")
		(hatch none 0.5)
		(connect_pads
			(clearance 0)
		)
		(min_thickness 0.25)
		(keepout
			(tracks not_allowed)
			(vias allowed)
			(pads allowed)
			(copperpour not_allowed)
			(footprints allowed)
		)
		(placement
			(enabled no)
			(sheetname "")
		)
		(fill
			(thermal_gap 0.5)
			(thermal_bridge_width 0.5)
			(island_removal_mode 0)
		)
		(polygon
			(pts
				(xy 163.678616 -295.675304) (xy 165.177216 -295.675304) (xy 165.177216 -296.195242) (xy 163.678616 -296.195242)
			)
		)
	)
	(zone
		(layer "In2.Cu")
		(hatch none 0.5)
		(connect_pads
			(clearance 0)
		)
		(min_thickness 0.25)
		(keepout
			(tracks not_allowed)
			(vias allowed)
			(pads allowed)
			(copperpour not_allowed)
			(footprints allowed)
		)
		(placement
			(enabled no)
			(sheetname "")
		)
		(fill
			(thermal_gap 0.5)
			(thermal_bridge_width 0.5)
			(island_removal_mode 0)
		)
		(polygon
			(pts
				(xy 430.80686 -303.325276) (xy 432.30546 -303.325276) (xy 432.30546 -303.845214) (xy 430.80686 -303.845214)
			)
		)
	)
	(zone
		(layer "In2.Cu")
		(hatch none 0.5)
		(connect_pads
			(clearance 0)
		)
		(min_thickness 0.25)
		(keepout
			(tracks not_allowed)
			(vias allowed)
			(pads allowed)
			(copperpour not_allowed)
			(footprints allowed)
		)
		(placement
			(enabled no)
			(sheetname "")
		)
		(fill
			(thermal_gap 0.5)
			(thermal_bridge_width 0.5)
			(island_removal_mode 0)
		)
		(polygon
			(pts
				(xy 299.07484 -279.525222) (xy 300.57344 -279.525222) (xy 300.57344 -280.04516) (xy 299.07484 -280.04516)
			)
		)
	)
	(zone
		(layer "In2.Cu")
		(hatch none 0.5)
		(connect_pads
			(clearance 0)
		)
		(min_thickness 0.25)
		(keepout
			(tracks not_allowed)
			(vias allowed)
			(pads allowed)
			(copperpour not_allowed)
			(footprints allowed)
		)
		(placement
			(enabled no)
			(sheetname "")
		)
		(fill
			(thermal_gap 0.5)
			(thermal_bridge_width 0.5)
			(island_removal_mode 0)
		)
		(polygon
			(pts
				(xy 197.954646 -228.525324) (xy 199.453246 -228.525324) (xy 199.453246 -229.045262) (xy 197.954646 -229.045262)
			)
		)
	)
	(zone
		(layer "In2.Cu")
		(hatch none 0.5)
		(connect_pads
			(clearance 0)
		)
		(min_thickness 0.25)
		(keepout
			(tracks not_allowed)
			(vias allowed)
			(pads allowed)
			(copperpour not_allowed)
			(footprints allowed)
		)
		(placement
			(enabled no)
			(sheetname "")
		)
		(fill
			(thermal_gap 0.5)
			(thermal_bridge_width 0.5)
			(island_removal_mode 0)
		)
		(polygon
			(pts
				(xy 36.046664 -210.67522) (xy 37.545264 -210.67522) (xy 37.545264 -211.195158) (xy 36.046664 -211.195158)
			)
		)
	)
	(zone
		(layer "In2.Cu")
		(hatch none 0.5)
		(connect_pads
			(clearance 0)
		)
		(min_thickness 0.25)
		(keepout
			(tracks not_allowed)
			(vias allowed)
			(pads allowed)
			(copperpour not_allowed)
			(footprints allowed)
		)
		(placement
			(enabled no)
			(sheetname "")
		)
		(fill
			(thermal_gap 0.5)
			(thermal_bridge_width 0.5)
			(island_removal_mode 0)
		)
		(polygon
			(pts
				(xy 441.7949 -237.02518) (xy 443.2935 -237.02518) (xy 443.2935 -237.545118) (xy 441.7949 -237.545118)
			)
		)
	)
	(zone
		(layer "In2.Cu")
		(hatch none 0.5)
		(connect_pads
			(clearance 0)
		)
		(min_thickness 0.25)
		(keepout
			(tracks not_allowed)
			(vias allowed)
			(pads allowed)
			(copperpour not_allowed)
			(footprints allowed)
		)
		(placement
			(enabled no)
			(sheetname "")
		)
		(fill
			(thermal_gap 0.5)
			(thermal_bridge_width 0.5)
			(island_removal_mode 0)
		)
		(polygon
			(pts
				(xy 16.858742 -265.075162) (xy 18.357342 -265.075162) (xy 18.357342 -265.5951) (xy 16.858742 -265.5951)
			)
		)
	)
	(zone
		(layer "In2.Cu")
		(hatch none 0.5)
		(connect_pads
			(clearance 0)
		)
		(min_thickness 0.25)
		(keepout
			(tracks not_allowed)
			(vias allowed)
			(pads allowed)
			(copperpour not_allowed)
			(footprints allowed)
		)
		(placement
			(enabled no)
			(sheetname "")
		)
		(fill
			(thermal_gap 0.5)
			(thermal_bridge_width 0.5)
			(island_removal_mode 0)
		)
		(polygon
			(pts
				(xy 283.986732 -221.725236) (xy 285.485332 -221.725236) (xy 285.485332 -222.245174) (xy 283.986732 -222.245174)
			)
		)
	)
	(zone
		(layer "In2.Cu")
		(hatch none 0.5)
		(connect_pads
			(clearance 0)
		)
		(min_thickness 0.25)
		(keepout
			(tracks allowed)
			(vias allowed)
			(pads allowed)
			(copperpour allowed)
			(footprints allowed)
		)
		(placement
			(enabled no)
			(sheetname "")
		)
		(fill
			(thermal_gap 0.5)
			(thermal_bridge_width 0.5)
			(island_removal_mode 0)
		)
		(polygon
			(pts
				(xy 294.55237 -350.590866) (xy 294.55237 -349.968566) (xy 295.10355 -349.968566) (xy 295.10355 -350.590866)
			)
		)
	)
	(zone
		(layer "In2.Cu")
		(hatch none 0.5)
		(connect_pads
			(clearance 0)
		)
		(min_thickness 0.25)
		(keepout
			(tracks allowed)
			(vias allowed)
			(pads allowed)
			(copperpour allowed)
			(footprints allowed)
		)
		(placement
			(enabled no)
			(sheetname "")
		)
		(fill
			(thermal_gap 0.5)
			(thermal_bridge_width 0.5)
			(island_removal_mode 0)
		)
		(polygon
			(pts
				(xy 58.871612 -349.943166) (xy 58.871612 -349.320866) (xy 59.422792 -349.320866) (xy 59.422792 -349.943166)
			)
		)
	)
	(zone
		(layer "In2.Cu")
		(hatch none 0.5)
		(connect_pads
			(clearance 0)
		)
		(min_thickness 0.25)
		(keepout
			(tracks not_allowed)
			(vias allowed)
			(pads allowed)
			(copperpour not_allowed)
			(footprints allowed)
		)
		(placement
			(enabled no)
			(sheetname "")
		)
		(fill
			(thermal_gap 0.5)
			(thermal_bridge_width 0.5)
			(island_removal_mode 0)
		)
		(polygon
			(pts
				(xy 438.350914 -236.175296) (xy 439.849514 -236.175296) (xy 439.849514 -236.695234) (xy 438.350914 -236.695234)
			)
		)
	)
	(zone
		(layer "In2.Cu")
		(hatch none 0.5)
		(connect_pads
			(clearance 0)
		)
		(min_thickness 0.25)
		(keepout
			(tracks not_allowed)
			(vias allowed)
			(pads allowed)
			(copperpour not_allowed)
			(footprints allowed)
		)
		(placement
			(enabled no)
			(sheetname "")
		)
		(fill
			(thermal_gap 0.5)
			(thermal_bridge_width 0.5)
			(island_removal_mode 0)
		)
		(polygon
			(pts
				(arc
					(start 57.56656 -17.966436)
					(mid 57.588878 -18.020318)
					(end 57.64276 -18.042636)
				)
				(arc
					(start 57.83834 -18.042636)
					(mid 57.860216 -18.039504)
					(end 57.88025 -18.03019)
				)
				(arc
					(start 58.173874 -17.837658)
					(mid 58.21553 -17.825256)
					(end 58.257186 -17.837658)
				)
				(arc
					(start 58.55208 -18.03019)
					(mid 58.572004 -18.039426)
					(end 58.593736 -18.042636)
				)
				(arc
					(start 58.7883 -18.042636)
					(mid 58.842182 -18.020318)
					(end 58.8645 -17.966436)
				)
				(arc
					(start 58.8645 -17.280636)
					(mid 58.842182 -17.226754)
					(end 58.7883 -17.204436)
				)
				(arc
					(start 58.593736 -17.204436)
					(mid 58.571992 -17.207604)
					(end 58.55208 -17.216882)
				)
				(arc
					(start 58.255916 -17.409668)
					(mid 58.214232 -17.42189)
					(end 58.172604 -17.409414)
				)
				(arc
					(start 57.87898 -17.216882)
					(mid 57.859056 -17.207646)
					(end 57.837324 -17.204436)
				)
				(arc
					(start 57.64276 -17.204436)
					(mid 57.588878 -17.226754)
					(end 57.56656 -17.280636)
				)
			)
		)
	)
	(zone
		(layer "In2.Cu")
		(hatch none 0.5)
		(connect_pads
			(clearance 0)
		)
		(min_thickness 0.25)
		(keepout
			(tracks not_allowed)
			(vias allowed)
			(pads allowed)
			(copperpour not_allowed)
			(footprints allowed)
		)
		(placement
			(enabled no)
			(sheetname "")
		)
		(fill
			(thermal_gap 0.5)
			(thermal_bridge_width 0.5)
			(island_removal_mode 0)
		)
		(polygon
			(pts
				(xy 415.718752 -223.425258) (xy 417.217352 -223.425258) (xy 417.217352 -223.945196) (xy 415.718752 -223.945196)
			)
		)
	)
	(zone
		(layer "In2.Cu")
		(hatch none 0.5)
		(connect_pads
			(clearance 0)
		)
		(min_thickness 0.25)
		(keepout
			(tracks not_allowed)
			(vias allowed)
			(pads allowed)
			(copperpour not_allowed)
			(footprints allowed)
		)
		(placement
			(enabled no)
			(sheetname "")
		)
		(fill
			(thermal_gap 0.5)
			(thermal_bridge_width 0.5)
			(island_removal_mode 0)
		)
		(polygon
			(pts
				(xy 175.322738 -269.325344) (xy 176.821338 -269.325344) (xy 176.821338 -269.845282) (xy 175.322738 -269.845282)
			)
		)
	)
	(zone
		(layer "In2.Cu")
		(hatch none 0.5)
		(connect_pads
			(clearance 0)
		)
		(min_thickness 0.25)
		(keepout
			(tracks not_allowed)
			(vias allowed)
			(pads allowed)
			(copperpour not_allowed)
			(footprints allowed)
		)
		(placement
			(enabled no)
			(sheetname "")
		)
		(fill
			(thermal_gap 0.5)
			(thermal_bridge_width 0.5)
			(island_removal_mode 0)
		)
		(polygon
			(pts
				(xy 272.342864 -227.675186) (xy 273.841464 -227.675186) (xy 273.841464 -228.195124) (xy 272.342864 -228.195124)
			)
		)
	)
	(zone
		(layer "In2.Cu")
		(hatch none 0.5)
		(connect_pads
			(clearance 0)
		)
		(min_thickness 0.25)
		(keepout
			(tracks not_allowed)
			(vias allowed)
			(pads allowed)
			(copperpour not_allowed)
			(footprints allowed)
		)
		(placement
			(enabled no)
			(sheetname "")
		)
		(fill
			(thermal_gap 0.5)
			(thermal_bridge_width 0.5)
			(island_removal_mode 0)
		)
		(polygon
			(pts
				(xy 51.134772 -247.225312) (xy 52.633372 -247.225312) (xy 52.633372 -247.74525) (xy 51.134772 -247.74525)
			)
		)
	)
	(zone
		(layer "In2.Cu")
		(hatch none 0.5)
		(connect_pads
			(clearance 0)
		)
		(min_thickness 0.25)
		(keepout
			(tracks not_allowed)
			(vias allowed)
			(pads allowed)
			(copperpour not_allowed)
			(footprints allowed)
		)
		(placement
			(enabled no)
			(sheetname "")
		)
		(fill
			(thermal_gap 0.5)
			(thermal_bridge_width 0.5)
			(island_removal_mode 0)
		)
		(polygon
			(pts
				(xy 190.410846 -296.525188) (xy 191.909446 -296.525188) (xy 191.909446 -297.045126) (xy 190.410846 -297.045126)
			)
		)
	)
	(zone
		(layer "In2.Cu")
		(hatch none 0.5)
		(connect_pads
			(clearance 0)
		)
		(min_thickness 0.25)
		(keepout
			(tracks not_allowed)
			(vias allowed)
			(pads allowed)
			(copperpour not_allowed)
			(footprints allowed)
		)
		(placement
			(enabled no)
			(sheetname "")
		)
		(fill
			(thermal_gap 0.5)
			(thermal_bridge_width 0.5)
			(island_removal_mode 0)
		)
		(polygon
			(pts
				(xy 279.886664 -233.625136) (xy 281.385264 -233.625136) (xy 281.385264 -234.145074) (xy 279.886664 -234.145074)
			)
		)
	)
	(zone
		(layer "In2.Cu")
		(hatch none 0.5)
		(connect_pads
			(clearance 0)
		)
		(min_thickness 0.25)
		(keepout
			(tracks not_allowed)
			(vias allowed)
			(pads allowed)
			(copperpour not_allowed)
			(footprints allowed)
		)
		(placement
			(enabled no)
			(sheetname "")
		)
		(fill
			(thermal_gap 0.5)
			(thermal_bridge_width 0.5)
			(island_removal_mode 0)
		)
		(polygon
			(pts
				(xy 135.88365 -36.962334) (xy 135.88365 -36.384484) (xy 137.20445 -36.384484) (xy 137.20445 -36.962334)
			)
		)
	)
	(zone
		(layer "In2.Cu")
		(hatch none 0.5)
		(connect_pads
			(clearance 0)
		)
		(min_thickness 0.25)
		(keepout
			(tracks not_allowed)
			(vias allowed)
			(pads allowed)
			(copperpour not_allowed)
			(footprints allowed)
		)
		(placement
			(enabled no)
			(sheetname "")
		)
		(fill
			(thermal_gap 0.5)
			(thermal_bridge_width 0.5)
			(island_removal_mode 0)
		)
		(polygon
			(pts
				(xy 276.442932 -299.925232) (xy 277.941532 -299.925232) (xy 277.941532 -300.44517) (xy 276.442932 -300.44517)
			)
		)
	)
	(zone
		(layer "In2.Cu")
		(hatch none 0.5)
		(connect_pads
			(clearance 0)
		)
		(min_thickness 0.25)
		(keepout
			(tracks not_allowed)
			(vias allowed)
			(pads allowed)
			(copperpour not_allowed)
			(footprints allowed)
		)
		(placement
			(enabled no)
			(sheetname "")
		)
		(fill
			(thermal_gap 0.5)
			(thermal_bridge_width 0.5)
			(island_removal_mode 0)
		)
		(polygon
			(pts
				(xy 20.95881 -220.025214) (xy 22.45741 -220.025214) (xy 22.45741 -220.545152) (xy 20.95881 -220.545152)
			)
		)
	)
	(zone
		(layer "In2.Cu")
		(hatch none 0.5)
		(connect_pads
			(clearance 0)
		)
		(min_thickness 0.25)
		(keepout
			(tracks allowed)
			(vias allowed)
			(pads allowed)
			(copperpour allowed)
			(footprints allowed)
		)
		(placement
			(enabled no)
			(sheetname "")
		)
		(fill
			(thermal_gap 0.5)
			(thermal_bridge_width 0.5)
			(island_removal_mode 0)
		)
		(polygon
			(pts
				(xy 400.268948 -174.5742) (xy 400.268948 -174.027846) (xy 400.821398 -174.027846) (xy 400.821398 -174.5742)
			)
		)
	)
	(zone
		(layer "In2.Cu")
		(hatch none 0.5)
		(connect_pads
			(clearance 0)
		)
		(min_thickness 0.25)
		(keepout
			(tracks not_allowed)
			(vias allowed)
			(pads allowed)
			(copperpour not_allowed)
			(footprints allowed)
		)
		(placement
			(enabled no)
			(sheetname "")
		)
		(fill
			(thermal_gap 0.5)
			(thermal_bridge_width 0.5)
			(island_removal_mode 0)
		)
		(polygon
			(pts
				(xy 441.7949 -289.725354) (xy 443.2935 -289.725354) (xy 443.2935 -290.245292) (xy 441.7949 -290.245292)
			)
		)
	)
	(zone
		(layer "In2.Cu")
		(hatch none 0.5)
		(connect_pads
			(clearance 0)
		)
		(min_thickness 0.25)
		(keepout
			(tracks not_allowed)
			(vias allowed)
			(pads allowed)
			(copperpour not_allowed)
			(footprints allowed)
		)
		(placement
			(enabled no)
			(sheetname "")
		)
		(fill
			(thermal_gap 0.5)
			(thermal_bridge_width 0.5)
			(island_removal_mode 0)
		)
		(polygon
			(pts
				(xy 302.518826 -237.02518) (xy 304.017426 -237.02518) (xy 304.017426 -237.545118) (xy 302.518826 -237.545118)
			)
		)
	)
	(zone
		(layer "In2.Cu")
		(hatch none 0.5)
		(connect_pads
			(clearance 0)
		)
		(min_thickness 0.25)
		(keepout
			(tracks allowed)
			(vias allowed)
			(pads allowed)
			(copperpour allowed)
			(footprints allowed)
		)
		(placement
			(enabled no)
			(sheetname "")
		)
		(fill
			(thermal_gap 0.5)
			(thermal_bridge_width 0.5)
			(island_removal_mode 0)
		)
		(polygon
			(pts
				(xy 385.41833 -180.231034) (xy 385.41833 -179.68468) (xy 385.97078 -179.68468) (xy 385.97078 -180.231034)
			)
		)
	)
	(zone
		(layer "In2.Cu")
		(hatch none 0.5)
		(connect_pads
			(clearance 0)
		)
		(min_thickness 0.25)
		(keepout
			(tracks not_allowed)
			(vias allowed)
			(pads allowed)
			(copperpour not_allowed)
			(footprints allowed)
		)
		(placement
			(enabled no)
			(sheetname "")
		)
		(fill
			(thermal_gap 0.5)
			(thermal_bridge_width 0.5)
			(island_removal_mode 0)
		)
		(polygon
			(pts
				(xy 294.974772 -249.775218) (xy 296.473372 -249.775218) (xy 296.473372 -250.295156) (xy 294.974772 -250.295156)
			)
		)
	)
	(zone
		(layer "In2.Cu")
		(hatch none 0.5)
		(connect_pads
			(clearance 0)
		)
		(min_thickness 0.25)
		(keepout
			(tracks not_allowed)
			(vias allowed)
			(pads allowed)
			(copperpour not_allowed)
			(footprints allowed)
		)
		(placement
			(enabled no)
			(sheetname "")
		)
		(fill
			(thermal_gap 0.5)
			(thermal_bridge_width 0.5)
			(island_removal_mode 0)
		)
		(polygon
			(pts
				(xy 24.402542 -208.975198) (xy 25.901142 -208.975198) (xy 25.901142 -209.495136) (xy 24.402542 -209.495136)
			)
		)
	)
	(zone
		(layer "In2.Cu")
		(hatch none 0.5)
		(connect_pads
			(clearance 0)
		)
		(min_thickness 0.25)
		(keepout
			(tracks not_allowed)
			(vias allowed)
			(pads allowed)
			(copperpour not_allowed)
			(footprints allowed)
		)
		(placement
			(enabled no)
			(sheetname "")
		)
		(fill
			(thermal_gap 0.5)
			(thermal_bridge_width 0.5)
			(island_removal_mode 0)
		)
		(polygon
			(pts
				(xy 190.410846 -307.575204) (xy 191.909446 -307.575204) (xy 191.909446 -308.095142) (xy 190.410846 -308.095142)
			)
		)
	)
	(zone
		(layer "In2.Cu")
		(hatch none 0.5)
		(connect_pads
			(clearance 0)
		)
		(min_thickness 0.25)
		(keepout
			(tracks not_allowed)
			(vias allowed)
			(pads allowed)
			(copperpour not_allowed)
			(footprints allowed)
		)
		(placement
			(enabled no)
			(sheetname "")
		)
		(fill
			(thermal_gap 0.5)
			(thermal_bridge_width 0.5)
			(island_removal_mode 0)
		)
		(polygon
			(pts
				(xy 163.678616 -249.775218) (xy 165.177216 -249.775218) (xy 165.177216 -250.295156) (xy 163.678616 -250.295156)
			)
		)
	)
	(zone
		(layer "In2.Cu")
		(hatch none 0.5)
		(connect_pads
			(clearance 0)
		)
		(min_thickness 0.25)
		(keepout
			(tracks not_allowed)
			(vias allowed)
			(pads allowed)
			(copperpour not_allowed)
			(footprints allowed)
		)
		(placement
			(enabled no)
			(sheetname "")
		)
		(fill
			(thermal_gap 0.5)
			(thermal_bridge_width 0.5)
			(island_removal_mode 0)
		)
		(polygon
			(pts
				(xy 287.430718 -238.725202) (xy 288.929318 -238.725202) (xy 288.929318 -239.24514) (xy 287.430718 -239.24514)
			)
		)
	)
	(zone
		(layer "In2.Cu")
		(hatch none 0.5)
		(connect_pads
			(clearance 0)
		)
		(min_thickness 0.25)
		(keepout
			(tracks not_allowed)
			(vias allowed)
			(pads allowed)
			(copperpour not_allowed)
			(footprints allowed)
		)
		(placement
			(enabled no)
			(sheetname "")
		)
		(fill
			(thermal_gap 0.5)
			(thermal_bridge_width 0.5)
			(island_removal_mode 0)
		)
		(polygon
			(pts
				(xy 411.618684 -299.075348) (xy 413.117284 -299.075348) (xy 413.117284 -299.595286) (xy 411.618684 -299.595286)
			)
		)
	)
	(zone
		(layer "In2.Cu")
		(hatch none 0.5)
		(connect_pads
			(clearance 0)
		)
		(min_thickness 0.25)
		(keepout
			(tracks not_allowed)
			(vias allowed)
			(pads allowed)
			(copperpour not_allowed)
			(footprints allowed)
		)
		(placement
			(enabled no)
			(sheetname "")
		)
		(fill
			(thermal_gap 0.5)
			(thermal_bridge_width 0.5)
			(island_removal_mode 0)
		)
		(polygon
			(pts
				(xy 268.898878 -225.12528) (xy 270.397478 -225.12528) (xy 270.397478 -225.645218) (xy 268.898878 -225.645218)
			)
		)
	)
	(zone
		(layer "In2.Cu")
		(hatch none 0.5)
		(connect_pads
			(clearance 0)
		)
		(min_thickness 0.25)
		(keepout
			(tracks allowed)
			(vias allowed)
			(pads allowed)
			(copperpour allowed)
			(footprints allowed)
		)
		(placement
			(enabled no)
			(sheetname "")
		)
		(fill
			(thermal_gap 0.5)
			(thermal_bridge_width 0.5)
			(island_removal_mode 0)
		)
		(polygon
			(pts
				(xy 328.130154 -337.38947) (xy 328.130154 -336.76717) (xy 328.681334 -336.76717) (xy 328.681334 -337.38947)
			)
		)
	)
	(zone
		(layer "In2.Cu")
		(hatch none 0.5)
		(connect_pads
			(clearance 0)
		)
		(min_thickness 0.25)
		(keepout
			(tracks not_allowed)
			(vias allowed)
			(pads allowed)
			(copperpour not_allowed)
			(footprints allowed)
		)
		(placement
			(enabled no)
			(sheetname "")
		)
		(fill
			(thermal_gap 0.5)
			(thermal_bridge_width 0.5)
			(island_removal_mode 0)
		)
		(polygon
			(pts
				(xy 197.954646 -232.775252) (xy 199.453246 -232.775252) (xy 199.453246 -233.29519) (xy 197.954646 -233.29519)
			)
		)
	)
	(zone
		(layer "In2.Cu")
		(hatch none 0.5)
		(connect_pads
			(clearance 0)
		)
		(min_thickness 0.25)
		(keepout
			(tracks not_allowed)
			(vias allowed)
			(pads allowed)
			(copperpour not_allowed)
			(footprints allowed)
		)
		(placement
			(enabled no)
			(sheetname "")
		)
		(fill
			(thermal_gap 0.5)
			(thermal_bridge_width 0.5)
			(island_removal_mode 0)
		)
		(polygon
			(pts
				(xy 411.618684 -246.375174) (xy 413.117284 -246.375174) (xy 413.117284 -246.895112) (xy 411.618684 -246.895112)
			)
		)
	)
	(zone
		(layer "In2.Cu")
		(hatch none 0.5)
		(connect_pads
			(clearance 0)
		)
		(min_thickness 0.25)
		(keepout
			(tracks not_allowed)
			(vias allowed)
			(pads allowed)
			(copperpour not_allowed)
			(footprints allowed)
		)
		(placement
			(enabled no)
			(sheetname "")
		)
		(fill
			(thermal_gap 0.5)
			(thermal_bridge_width 0.5)
			(island_removal_mode 0)
		)
		(polygon
			(pts
				(xy 193.854578 -235.325158) (xy 195.353178 -235.325158) (xy 195.353178 -235.845096) (xy 193.854578 -235.845096)
			)
		)
	)
	(zone
		(layer "In2.Cu")
		(hatch none 0.5)
		(connect_pads
			(clearance 0)
		)
		(min_thickness 0.25)
		(keepout
			(tracks not_allowed)
			(vias allowed)
			(pads allowed)
			(copperpour not_allowed)
			(footprints allowed)
		)
		(placement
			(enabled no)
			(sheetname "")
		)
		(fill
			(thermal_gap 0.5)
			(thermal_bridge_width 0.5)
			(island_removal_mode 0)
		)
		(polygon
			(pts
				(xy 279.886664 -220.875098) (xy 281.385264 -220.875098) (xy 281.385264 -221.395036) (xy 279.886664 -221.395036)
			)
		)
	)
	(zone
		(layer "In2.Cu")
		(hatch none 0.5)
		(connect_pads
			(clearance 0)
		)
		(min_thickness 0.25)
		(keepout
			(tracks not_allowed)
			(vias allowed)
			(pads allowed)
			(copperpour not_allowed)
			(footprints allowed)
		)
		(placement
			(enabled no)
			(sheetname "")
		)
		(fill
			(thermal_gap 0.5)
			(thermal_bridge_width 0.5)
			(island_removal_mode 0)
		)
		(polygon
			(pts
				(xy 283.986732 -229.375208) (xy 285.485332 -229.375208) (xy 285.485332 -229.895146) (xy 283.986732 -229.895146)
			)
		)
	)
	(zone
		(layer "In2.Cu")
		(hatch none 0.5)
		(connect_pads
			(clearance 0)
		)
		(min_thickness 0.25)
		(keepout
			(tracks not_allowed)
			(vias allowed)
			(pads allowed)
			(copperpour not_allowed)
			(footprints allowed)
		)
		(placement
			(enabled no)
			(sheetname "")
		)
		(fill
			(thermal_gap 0.5)
			(thermal_bridge_width 0.5)
			(island_removal_mode 0)
		)
		(polygon
			(pts
				(xy 279.886664 -227.675186) (xy 281.385264 -227.675186) (xy 281.385264 -228.195124) (xy 279.886664 -228.195124)
			)
		)
	)
	(zone
		(layer "In2.Cu")
		(hatch none 0.5)
		(connect_pads
			(clearance 0)
		)
		(min_thickness 0.25)
		(keepout
			(tracks not_allowed)
			(vias allowed)
			(pads allowed)
			(copperpour not_allowed)
			(footprints allowed)
		)
		(placement
			(enabled no)
			(sheetname "")
		)
		(fill
			(thermal_gap 0.5)
			(thermal_bridge_width 0.5)
			(island_removal_mode 0)
		)
		(polygon
			(pts
				(xy 449.3387 -294.825166) (xy 450.8373 -294.825166) (xy 450.8373 -295.345104) (xy 449.3387 -295.345104)
			)
		)
	)
	(zone
		(layer "In2.Cu")
		(hatch none 0.5)
		(connect_pads
			(clearance 0)
		)
		(min_thickness 0.25)
		(keepout
			(tracks not_allowed)
			(vias allowed)
			(pads allowed)
			(copperpour not_allowed)
			(footprints allowed)
		)
		(placement
			(enabled no)
			(sheetname "")
		)
		(fill
			(thermal_gap 0.5)
			(thermal_bridge_width 0.5)
			(island_removal_mode 0)
		)
		(polygon
			(pts
				(xy 434.250846 -311.825132) (xy 435.749446 -311.825132) (xy 435.749446 -312.34507) (xy 434.250846 -312.34507)
			)
		)
	)
	(zone
		(layer "In2.Cu")
		(hatch none 0.5)
		(connect_pads
			(clearance 0)
		)
		(min_thickness 0.25)
		(keepout
			(tracks not_allowed)
			(vias allowed)
			(pads allowed)
			(copperpour not_allowed)
			(footprints allowed)
		)
		(placement
			(enabled no)
			(sheetname "")
		)
		(fill
			(thermal_gap 0.5)
			(thermal_bridge_width 0.5)
			(island_removal_mode 0)
		)
		(polygon
			(pts
				(xy 190.410846 -312.67527) (xy 191.909446 -312.67527) (xy 191.909446 -313.195208) (xy 190.410846 -313.195208)
			)
		)
	)
	(zone
		(layer "In2.Cu")
		(hatch none 0.5)
		(connect_pads
			(clearance 0)
		)
		(min_thickness 0.25)
		(keepout
			(tracks not_allowed)
			(vias allowed)
			(pads allowed)
			(copperpour not_allowed)
			(footprints allowed)
		)
		(placement
			(enabled no)
			(sheetname "")
		)
		(fill
			(thermal_gap 0.5)
			(thermal_bridge_width 0.5)
			(island_removal_mode 0)
		)
		(polygon
			(pts
				(xy 453.438768 -237.875318) (xy 454.937368 -237.875318) (xy 454.937368 -238.395256) (xy 453.438768 -238.395256)
			)
		)
	)
	(zone
		(layer "In2.Cu")
		(hatch none 0.5)
		(connect_pads
			(clearance 0)
		)
		(min_thickness 0.25)
		(keepout
			(tracks not_allowed)
			(vias allowed)
			(pads allowed)
			(copperpour not_allowed)
			(footprints allowed)
		)
		(placement
			(enabled no)
			(sheetname "")
		)
		(fill
			(thermal_gap 0.5)
			(thermal_bridge_width 0.5)
			(island_removal_mode 0)
		)
		(polygon
			(pts
				(xy 279.886664 -248.075196) (xy 281.385264 -248.075196) (xy 281.385264 -248.595134) (xy 279.886664 -248.595134)
			)
		)
	)
	(zone
		(layer "In2.Cu")
		(hatch none 0.5)
		(connect_pads
			(clearance 0)
		)
		(min_thickness 0.25)
		(keepout
			(tracks not_allowed)
			(vias allowed)
			(pads allowed)
			(copperpour not_allowed)
			(footprints allowed)
		)
		(placement
			(enabled no)
			(sheetname "")
		)
		(fill
			(thermal_gap 0.5)
			(thermal_bridge_width 0.5)
			(island_removal_mode 0)
		)
		(polygon
			(pts
				(xy 419.162738 -300.775116) (xy 420.661338 -300.775116) (xy 420.661338 -301.295054) (xy 419.162738 -301.295054)
			)
		)
	)
	(zone
		(layer "In2.Cu")
		(hatch none 0.5)
		(connect_pads
			(clearance 0)
		)
		(min_thickness 0.25)
		(keepout
			(tracks not_allowed)
			(vias allowed)
			(pads allowed)
			(copperpour not_allowed)
			(footprints allowed)
		)
		(placement
			(enabled no)
			(sheetname "")
		)
		(fill
			(thermal_gap 0.5)
			(thermal_bridge_width 0.5)
			(island_removal_mode 0)
		)
		(polygon
			(pts
				(xy 423.262806 -240.425224) (xy 424.761406 -240.425224) (xy 424.761406 -240.945162) (xy 423.262806 -240.945162)
			)
		)
	)
	(zone
		(layer "In2.Cu")
		(hatch none 0.5)
		(connect_pads
			(clearance 0)
		)
		(min_thickness 0.25)
		(keepout
			(tracks not_allowed)
			(vias allowed)
			(pads allowed)
			(copperpour not_allowed)
			(footprints allowed)
		)
		(placement
			(enabled no)
			(sheetname "")
		)
		(fill
			(thermal_gap 0.5)
			(thermal_bridge_width 0.5)
			(island_removal_mode 0)
		)
		(polygon
			(pts
				(xy 283.986732 -237.875318) (xy 285.485332 -237.875318) (xy 285.485332 -238.395256) (xy 283.986732 -238.395256)
			)
		)
	)
	(zone
		(layer "In2.Cu")
		(hatch none 0.5)
		(connect_pads
			(clearance 0)
		)
		(min_thickness 0.25)
		(keepout
			(tracks not_allowed)
			(vias allowed)
			(pads allowed)
			(copperpour not_allowed)
			(footprints allowed)
		)
		(placement
			(enabled no)
			(sheetname "")
		)
		(fill
			(thermal_gap 0.5)
			(thermal_bridge_width 0.5)
			(island_removal_mode 0)
		)
		(polygon
			(pts
				(xy 58.678826 -265.9253) (xy 60.177426 -265.9253) (xy 60.177426 -266.445238) (xy 58.678826 -266.445238)
			)
		)
	)
	(zone
		(layer "In2.Cu")
		(hatch none 0.5)
		(connect_pads
			(clearance 0)
		)
		(min_thickness 0.25)
		(keepout
			(tracks not_allowed)
			(vias allowed)
			(pads allowed)
			(copperpour not_allowed)
			(footprints allowed)
		)
		(placement
			(enabled no)
			(sheetname "")
		)
		(fill
			(thermal_gap 0.5)
			(thermal_bridge_width 0.5)
			(island_removal_mode 0)
		)
		(polygon
			(pts
				(xy 426.706792 -283.77515) (xy 428.205392 -283.77515) (xy 428.205392 -284.295088) (xy 426.706792 -284.295088)
			)
		)
	)
	(zone
		(layer "In2.Cu")
		(hatch none 0.5)
		(connect_pads
			(clearance 0)
		)
		(min_thickness 0.25)
		(keepout
			(tracks not_allowed)
			(vias allowed)
			(pads allowed)
			(copperpour not_allowed)
			(footprints allowed)
		)
		(placement
			(enabled no)
			(sheetname "")
		)
		(fill
			(thermal_gap 0.5)
			(thermal_bridge_width 0.5)
			(island_removal_mode 0)
		)
		(polygon
			(pts
				(xy 20.95881 -198.77532) (xy 22.45741 -198.77532) (xy 22.45741 -199.295258) (xy 20.95881 -199.295258)
			)
		)
	)
	(zone
		(layer "In2.Cu")
		(hatch none 0.5)
		(connect_pads
			(clearance 0)
		)
		(min_thickness 0.25)
		(keepout
			(tracks not_allowed)
			(vias allowed)
			(pads allowed)
			(copperpour not_allowed)
			(footprints allowed)
		)
		(placement
			(enabled no)
			(sheetname "")
		)
		(fill
			(thermal_gap 0.5)
			(thermal_bridge_width 0.5)
			(island_removal_mode 0)
		)
		(polygon
			(pts
				(xy 445.894968 -265.9253) (xy 447.393568 -265.9253) (xy 447.393568 -266.445238) (xy 445.894968 -266.445238)
			)
		)
	)
	(zone
		(layer "In2.Cu")
		(hatch none 0.5)
		(connect_pads
			(clearance 0)
		)
		(min_thickness 0.25)
		(keepout
			(tracks not_allowed)
			(vias allowed)
			(pads allowed)
			(copperpour not_allowed)
			(footprints allowed)
		)
		(placement
			(enabled no)
			(sheetname "")
		)
		(fill
			(thermal_gap 0.5)
			(thermal_bridge_width 0.5)
			(island_removal_mode 0)
		)
		(polygon
			(pts
				(xy 426.706792 -293.125144) (xy 428.205392 -293.125144) (xy 428.205392 -293.645082) (xy 426.706792 -293.645082)
			)
		)
	)
	(zone
		(layer "In2.Cu")
		(hatch none 0.5)
		(connect_pads
			(clearance 0)
		)
		(min_thickness 0.25)
		(keepout
			(tracks not_allowed)
			(vias allowed)
			(pads allowed)
			(copperpour not_allowed)
			(footprints allowed)
		)
		(placement
			(enabled no)
			(sheetname "")
		)
		(fill
			(thermal_gap 0.5)
			(thermal_bridge_width 0.5)
			(island_removal_mode 0)
		)
		(polygon
			(pts
				(xy 201.398632 -294.825166) (xy 202.897232 -294.825166) (xy 202.897232 -295.345104) (xy 201.398632 -295.345104)
			)
		)
	)
	(zone
		(layer "In2.Cu")
		(hatch none 0.5)
		(connect_pads
			(clearance 0)
		)
		(min_thickness 0.25)
		(keepout
			(tracks not_allowed)
			(vias allowed)
			(pads allowed)
			(copperpour not_allowed)
			(footprints allowed)
		)
		(placement
			(enabled no)
			(sheetname "")
		)
		(fill
			(thermal_gap 0.5)
			(thermal_bridge_width 0.5)
			(island_removal_mode 0)
		)
		(polygon
			(pts
				(xy 28.50261 -282.925266) (xy 30.00121 -282.925266) (xy 30.00121 -283.445204) (xy 28.50261 -283.445204)
			)
		)
	)
	(zone
		(layer "In2.Cu")
		(hatch none 0.5)
		(connect_pads
			(clearance 0)
		)
		(min_thickness 0.25)
		(keepout
			(tracks not_allowed)
			(vias allowed)
			(pads allowed)
			(copperpour not_allowed)
			(footprints allowed)
		)
		(placement
			(enabled no)
			(sheetname "")
		)
		(fill
			(thermal_gap 0.5)
			(thermal_bridge_width 0.5)
			(island_removal_mode 0)
		)
		(polygon
			(pts
				(xy 193.854578 -317.775336) (xy 195.353178 -317.775336) (xy 195.353178 -318.295274) (xy 193.854578 -318.295274)
			)
		)
	)
	(zone
		(layer "In2.Cu")
		(hatch none 0.5)
		(connect_pads
			(clearance 0)
		)
		(min_thickness 0.25)
		(keepout
			(tracks not_allowed)
			(vias allowed)
			(pads allowed)
			(copperpour not_allowed)
			(footprints allowed)
		)
		(placement
			(enabled no)
			(sheetname "")
		)
		(fill
			(thermal_gap 0.5)
			(thermal_bridge_width 0.5)
			(island_removal_mode 0)
		)
		(polygon
			(pts
				(xy 54.578758 -214.925148) (xy 56.077358 -214.925148) (xy 56.077358 -215.445086) (xy 54.578758 -215.445086)
			)
		)
	)
	(zone
		(layer "In2.Cu")
		(hatch none 0.5)
		(connect_pads
			(clearance 0)
		)
		(min_thickness 0.25)
		(keepout
			(tracks not_allowed)
			(vias allowed)
			(pads allowed)
			(copperpour not_allowed)
			(footprints allowed)
		)
		(placement
			(enabled no)
			(sheetname "")
		)
		(fill
			(thermal_gap 0.5)
			(thermal_bridge_width 0.5)
			(island_removal_mode 0)
		)
		(polygon
			(pts
				(xy 272.342864 -235.325158) (xy 273.841464 -235.325158) (xy 273.841464 -235.845096) (xy 272.342864 -235.845096)
			)
		)
	)
	(zone
		(layer "In2.Cu")
		(hatch none 0.5)
		(connect_pads
			(clearance 0)
		)
		(min_thickness 0.25)
		(keepout
			(tracks not_allowed)
			(vias allowed)
			(pads allowed)
			(copperpour not_allowed)
			(footprints allowed)
		)
		(placement
			(enabled no)
			(sheetname "")
		)
		(fill
			(thermal_gap 0.5)
			(thermal_bridge_width 0.5)
			(island_removal_mode 0)
		)
		(polygon
			(pts
				(xy 283.986732 -303.325276) (xy 285.485332 -303.325276) (xy 285.485332 -303.845214) (xy 283.986732 -303.845214)
			)
		)
	)
	(zone
		(layer "In2.Cu")
		(hatch none 0.5)
		(connect_pads
			(clearance 0)
		)
		(min_thickness 0.25)
		(keepout
			(tracks not_allowed)
			(vias allowed)
			(pads allowed)
			(copperpour not_allowed)
			(footprints allowed)
		)
		(placement
			(enabled no)
			(sheetname "")
		)
		(fill
			(thermal_gap 0.5)
			(thermal_bridge_width 0.5)
			(island_removal_mode 0)
		)
		(polygon
			(pts
				(xy 299.07484 -296.525188) (xy 300.57344 -296.525188) (xy 300.57344 -297.045126) (xy 299.07484 -297.045126)
			)
		)
	)
	(zone
		(layer "In2.Cu")
		(hatch none 0.5)
		(connect_pads
			(clearance 0)
		)
		(min_thickness 0.25)
		(keepout
			(tracks not_allowed)
			(vias allowed)
			(pads allowed)
			(copperpour not_allowed)
			(footprints allowed)
		)
		(placement
			(enabled no)
			(sheetname "")
		)
		(fill
			(thermal_gap 0.5)
			(thermal_bridge_width 0.5)
			(island_removal_mode 0)
		)
		(polygon
			(pts
				(xy 294.974772 -230.225346) (xy 296.473372 -230.225346) (xy 296.473372 -230.745284) (xy 294.974772 -230.745284)
			)
		)
	)
	(zone
		(layer "In2.Cu")
		(hatch none 0.5)
		(connect_pads
			(clearance 0)
		)
		(min_thickness 0.25)
		(keepout
			(tracks not_allowed)
			(vias allowed)
			(pads allowed)
			(copperpour not_allowed)
			(footprints allowed)
		)
		(placement
			(enabled no)
			(sheetname "")
		)
		(fill
			(thermal_gap 0.5)
			(thermal_bridge_width 0.5)
			(island_removal_mode 0)
		)
		(polygon
			(pts
				(xy 171.22267 -224.275142) (xy 172.72127 -224.275142) (xy 172.72127 -224.79508) (xy 171.22267 -224.79508)
			)
		)
	)
	(zone
		(layer "In2.Cu")
		(hatch none 0.5)
		(connect_pads
			(clearance 0)
		)
		(min_thickness 0.25)
		(keepout
			(tracks not_allowed)
			(vias allowed)
			(pads allowed)
			(copperpour not_allowed)
			(footprints allowed)
		)
		(placement
			(enabled no)
			(sheetname "")
		)
		(fill
			(thermal_gap 0.5)
			(thermal_bridge_width 0.5)
			(island_removal_mode 0)
		)
		(polygon
			(pts
				(xy 426.706792 -263.37514) (xy 428.205392 -263.37514) (xy 428.205392 -263.895078) (xy 426.706792 -263.895078)
			)
		)
	)
	(zone
		(layer "In2.Cu")
		(hatch none 0.5)
		(connect_pads
			(clearance 0)
		)
		(min_thickness 0.25)
		(keepout
			(tracks not_allowed)
			(vias allowed)
			(pads allowed)
			(copperpour not_allowed)
			(footprints allowed)
		)
		(placement
			(enabled no)
			(sheetname "")
		)
		(fill
			(thermal_gap 0.5)
			(thermal_bridge_width 0.5)
			(island_removal_mode 0)
		)
		(polygon
			(pts
				(xy 279.886664 -253.175262) (xy 281.385264 -253.175262) (xy 281.385264 -253.6952) (xy 279.886664 -253.6952)
			)
		)
	)
	(zone
		(layer "In2.Cu")
		(hatch none 0.5)
		(connect_pads
			(clearance 0)
		)
		(min_thickness 0.25)
		(keepout
			(tracks not_allowed)
			(vias allowed)
			(pads allowed)
			(copperpour not_allowed)
			(footprints allowed)
		)
		(placement
			(enabled no)
			(sheetname "")
		)
		(fill
			(thermal_gap 0.5)
			(thermal_bridge_width 0.5)
			(island_removal_mode 0)
		)
		(polygon
			(pts
				(xy 441.7949 -201.325226) (xy 443.2935 -201.325226) (xy 443.2935 -201.845164) (xy 441.7949 -201.845164)
			)
		)
	)
	(zone
		(layer "In2.Cu")
		(hatch none 0.5)
		(connect_pads
			(clearance 0)
		)
		(min_thickness 0.25)
		(keepout
			(tracks not_allowed)
			(vias allowed)
			(pads allowed)
			(copperpour not_allowed)
			(footprints allowed)
		)
		(placement
			(enabled no)
			(sheetname "")
		)
		(fill
			(thermal_gap 0.5)
			(thermal_bridge_width 0.5)
			(island_removal_mode 0)
		)
		(polygon
			(pts
				(xy 268.898878 -301.625254) (xy 270.397478 -301.625254) (xy 270.397478 -302.145192) (xy 268.898878 -302.145192)
			)
		)
	)
	(zone
		(layer "In2.Cu")
		(hatch none 0.5)
		(connect_pads
			(clearance 0)
		)
		(min_thickness 0.25)
		(keepout
			(tracks not_allowed)
			(vias allowed)
			(pads allowed)
			(copperpour not_allowed)
			(footprints allowed)
		)
		(placement
			(enabled no)
			(sheetname "")
		)
		(fill
			(thermal_gap 0.5)
			(thermal_bridge_width 0.5)
			(island_removal_mode 0)
		)
		(polygon
			(pts
				(xy 287.430718 -201.325226) (xy 288.929318 -201.325226) (xy 288.929318 -201.845164) (xy 287.430718 -201.845164)
			)
		)
	)
	(zone
		(layer "In2.Cu")
		(hatch none 0.5)
		(connect_pads
			(clearance 0)
		)
		(min_thickness 0.25)
		(keepout
			(tracks not_allowed)
			(vias allowed)
			(pads allowed)
			(copperpour not_allowed)
			(footprints allowed)
		)
		(placement
			(enabled no)
			(sheetname "")
		)
		(fill
			(thermal_gap 0.5)
			(thermal_bridge_width 0.5)
			(island_removal_mode 0)
		)
		(polygon
			(pts
				(xy 186.310778 -238.725202) (xy 187.809378 -238.725202) (xy 187.809378 -239.24514) (xy 186.310778 -239.24514)
			)
		)
	)
	(zone
		(layer "In2.Cu")
		(hatch none 0.5)
		(connect_pads
			(clearance 0)
		)
		(min_thickness 0.25)
		(keepout
			(tracks allowed)
			(vias allowed)
			(pads allowed)
			(copperpour allowed)
			(footprints allowed)
		)
		(placement
			(enabled no)
			(sheetname "")
		)
		(fill
			(thermal_gap 0.5)
			(thermal_bridge_width 0.5)
			(island_removal_mode 0)
		)
		(polygon
			(pts
				(xy 85.26145 -338.662772) (xy 85.26145 -339.612732) (xy 85.03793 -339.612732) (xy 85.03793 -338.662772)
			)
		)
	)
	(zone
		(layer "In2.Cu")
		(hatch none 0.5)
		(connect_pads
			(clearance 0)
		)
		(min_thickness 0.25)
		(keepout
			(tracks not_allowed)
			(vias allowed)
			(pads allowed)
			(copperpour not_allowed)
			(footprints allowed)
		)
		(placement
			(enabled no)
			(sheetname "")
		)
		(fill
			(thermal_gap 0.5)
			(thermal_bridge_width 0.5)
			(island_removal_mode 0)
		)
		(polygon
			(pts
				(xy 31.946596 -238.725202) (xy 33.445196 -238.725202) (xy 33.445196 -239.24514) (xy 31.946596 -239.24514)
			)
		)
	)
	(zone
		(layer "In2.Cu")
		(hatch none 0.5)
		(connect_pads
			(clearance 0)
		)
		(min_thickness 0.25)
		(keepout
			(tracks not_allowed)
			(vias allowed)
			(pads allowed)
			(copperpour not_allowed)
			(footprints allowed)
		)
		(placement
			(enabled no)
			(sheetname "")
		)
		(fill
			(thermal_gap 0.5)
			(thermal_bridge_width 0.5)
			(island_removal_mode 0)
		)
		(polygon
			(pts
				(xy 175.322738 -313.525154) (xy 176.821338 -313.525154) (xy 176.821338 -314.045092) (xy 175.322738 -314.045092)
			)
		)
	)
	(zone
		(layer "In2.Cu")
		(hatch none 0.5)
		(connect_pads
			(clearance 0)
		)
		(min_thickness 0.25)
		(keepout
			(tracks not_allowed)
			(vias allowed)
			(pads allowed)
			(copperpour not_allowed)
			(footprints allowed)
		)
		(placement
			(enabled no)
			(sheetname "")
		)
		(fill
			(thermal_gap 0.5)
			(thermal_bridge_width 0.5)
			(island_removal_mode 0)
		)
		(polygon
			(pts
				(xy 190.410846 -232.775252) (xy 191.909446 -232.775252) (xy 191.909446 -233.29519) (xy 190.410846 -233.29519)
			)
		)
	)
	(zone
		(layer "In2.Cu")
		(hatch none 0.5)
		(connect_pads
			(clearance 0)
		)
		(min_thickness 0.25)
		(keepout
			(tracks not_allowed)
			(vias allowed)
			(pads allowed)
			(copperpour not_allowed)
			(footprints allowed)
		)
		(placement
			(enabled no)
			(sheetname "")
		)
		(fill
			(thermal_gap 0.5)
			(thermal_bridge_width 0.5)
			(island_removal_mode 0)
		)
		(polygon
			(pts
				(xy 201.398632 -304.17516) (xy 202.897232 -304.17516) (xy 202.897232 -304.695098) (xy 201.398632 -304.695098)
			)
		)
	)
	(zone
		(layer "In2.Cu")
		(hatch none 0.5)
		(connect_pads
			(clearance 0)
		)
		(min_thickness 0.25)
		(keepout
			(tracks not_allowed)
			(vias allowed)
			(pads allowed)
			(copperpour not_allowed)
			(footprints allowed)
		)
		(placement
			(enabled no)
			(sheetname "")
		)
		(fill
			(thermal_gap 0.5)
			(thermal_bridge_width 0.5)
			(island_removal_mode 0)
		)
		(polygon
			(pts
				(xy 423.262806 -290.575238) (xy 424.761406 -290.575238) (xy 424.761406 -291.095176) (xy 423.262806 -291.095176)
			)
		)
	)
	(zone
		(layer "In2.Cu")
		(hatch none 0.5)
		(connect_pads
			(clearance 0)
		)
		(min_thickness 0.25)
		(keepout
			(tracks not_allowed)
			(vias allowed)
			(pads allowed)
			(copperpour not_allowed)
			(footprints allowed)
		)
		(placement
			(enabled no)
			(sheetname "")
		)
		(fill
			(thermal_gap 0.5)
			(thermal_bridge_width 0.5)
			(island_removal_mode 0)
		)
		(polygon
			(pts
				(xy 193.854578 -308.425342) (xy 195.353178 -308.425342) (xy 195.353178 -308.94528) (xy 193.854578 -308.94528)
			)
		)
	)
	(zone
		(layer "In2.Cu")
		(hatch none 0.5)
		(connect_pads
			(clearance 0)
		)
		(min_thickness 0.25)
		(keepout
			(tracks not_allowed)
			(vias allowed)
			(pads allowed)
			(copperpour not_allowed)
			(footprints allowed)
		)
		(placement
			(enabled no)
			(sheetname "")
		)
		(fill
			(thermal_gap 0.5)
			(thermal_bridge_width 0.5)
			(island_removal_mode 0)
		)
		(polygon
			(pts
				(xy 276.442932 -221.725236) (xy 277.941532 -221.725236) (xy 277.941532 -222.245174) (xy 276.442932 -222.245174)
			)
		)
	)
	(zone
		(layer "In2.Cu")
		(hatch none 0.5)
		(connect_pads
			(clearance 0)
		)
		(min_thickness 0.25)
		(keepout
			(tracks not_allowed)
			(vias allowed)
			(pads allowed)
			(copperpour not_allowed)
			(footprints allowed)
		)
		(placement
			(enabled no)
			(sheetname "")
		)
		(fill
			(thermal_gap 0.5)
			(thermal_bridge_width 0.5)
			(island_removal_mode 0)
		)
		(polygon
			(pts
				(xy 58.678826 -206.425292) (xy 60.177426 -206.425292) (xy 60.177426 -206.94523) (xy 58.678826 -206.94523)
			)
		)
	)
	(zone
		(layer "In2.Cu")
		(hatch none 0.5)
		(connect_pads
			(clearance 0)
		)
		(min_thickness 0.25)
		(keepout
			(tracks not_allowed)
			(vias allowed)
			(pads allowed)
			(copperpour not_allowed)
			(footprints allowed)
		)
		(placement
			(enabled no)
			(sheetname "")
		)
		(fill
			(thermal_gap 0.5)
			(thermal_bridge_width 0.5)
			(island_removal_mode 0)
		)
		(polygon
			(pts
				(xy 411.618684 -285.475172) (xy 413.117284 -285.475172) (xy 413.117284 -285.99511) (xy 411.618684 -285.99511)
			)
		)
	)
	(zone
		(layer "In2.Cu")
		(hatch none 0.5)
		(connect_pads
			(clearance 0)
		)
		(min_thickness 0.25)
		(keepout
			(tracks not_allowed)
			(vias allowed)
			(pads allowed)
			(copperpour not_allowed)
			(footprints allowed)
		)
		(placement
			(enabled no)
			(sheetname "")
		)
		(fill
			(thermal_gap 0.5)
			(thermal_bridge_width 0.5)
			(island_removal_mode 0)
		)
		(polygon
			(pts
				(xy 28.50261 -212.375242) (xy 30.00121 -212.375242) (xy 30.00121 -212.89518) (xy 28.50261 -212.89518)
			)
		)
	)
	(zone
		(layer "In2.Cu")
		(hatch none 0.5)
		(connect_pads
			(clearance 0)
		)
		(min_thickness 0.25)
		(keepout
			(tracks not_allowed)
			(vias allowed)
			(pads allowed)
			(copperpour not_allowed)
			(footprints allowed)
		)
		(placement
			(enabled no)
			(sheetname "")
		)
		(fill
			(thermal_gap 0.5)
			(thermal_bridge_width 0.5)
			(island_removal_mode 0)
		)
		(polygon
			(pts
				(xy 167.778684 -201.325226) (xy 169.277284 -201.325226) (xy 169.277284 -201.845164) (xy 167.778684 -201.845164)
			)
		)
	)
	(zone
		(layer "In2.Cu")
		(hatch none 0.5)
		(connect_pads
			(clearance 0)
		)
		(min_thickness 0.25)
		(keepout
			(tracks not_allowed)
			(vias allowed)
			(pads allowed)
			(copperpour not_allowed)
			(footprints allowed)
		)
		(placement
			(enabled no)
			(sheetname "")
		)
		(fill
			(thermal_gap 0.5)
			(thermal_bridge_width 0.5)
			(island_removal_mode 0)
		)
		(polygon
			(pts
				(xy 423.262806 -221.725236) (xy 424.761406 -221.725236) (xy 424.761406 -222.245174) (xy 423.262806 -222.245174)
			)
		)
	)
	(zone
		(layer "In2.Cu")
		(hatch none 0.5)
		(connect_pads
			(clearance 0)
		)
		(min_thickness 0.25)
		(keepout
			(tracks not_allowed)
			(vias allowed)
			(pads allowed)
			(copperpour not_allowed)
			(footprints allowed)
		)
		(placement
			(enabled no)
			(sheetname "")
		)
		(fill
			(thermal_gap 0.5)
			(thermal_bridge_width 0.5)
			(island_removal_mode 0)
		)
		(polygon
			(pts
				(xy 306.618894 -304.17516) (xy 308.117494 -304.17516) (xy 308.117494 -304.695098) (xy 306.618894 -304.695098)
			)
		)
	)
	(zone
		(layer "In2.Cu")
		(hatch none 0.5)
		(connect_pads
			(clearance 0)
		)
		(min_thickness 0.25)
		(keepout
			(tracks not_allowed)
			(vias allowed)
			(pads allowed)
			(copperpour not_allowed)
			(footprints allowed)
		)
		(placement
			(enabled no)
			(sheetname "")
		)
		(fill
			(thermal_gap 0.5)
			(thermal_bridge_width 0.5)
			(island_removal_mode 0)
		)
		(polygon
			(pts
				(xy 283.986732 -281.225244) (xy 285.485332 -281.225244) (xy 285.485332 -281.745182) (xy 283.986732 -281.745182)
			)
		)
	)
	(zone
		(layer "In2.Cu")
		(hatch none 0.5)
		(connect_pads
			(clearance 0)
		)
		(min_thickness 0.25)
		(keepout
			(tracks not_allowed)
			(vias allowed)
			(pads allowed)
			(copperpour not_allowed)
			(footprints allowed)
		)
		(placement
			(enabled no)
			(sheetname "")
		)
		(fill
			(thermal_gap 0.5)
			(thermal_bridge_width 0.5)
			(island_removal_mode 0)
		)
		(polygon
			(pts
				(xy 167.778684 -236.175296) (xy 169.277284 -236.175296) (xy 169.277284 -236.695234) (xy 167.778684 -236.695234)
			)
		)
	)
	(zone
		(layer "In2.Cu")
		(hatch none 0.5)
		(connect_pads
			(clearance 0)
		)
		(min_thickness 0.25)
		(keepout
			(tracks not_allowed)
			(vias allowed)
			(pads allowed)
			(copperpour not_allowed)
			(footprints allowed)
		)
		(placement
			(enabled no)
			(sheetname "")
		)
		(fill
			(thermal_gap 0.5)
			(thermal_bridge_width 0.5)
			(island_removal_mode 0)
		)
		(polygon
			(pts
				(xy 175.322738 -301.625254) (xy 176.821338 -301.625254) (xy 176.821338 -302.145192) (xy 175.322738 -302.145192)
			)
		)
	)
	(zone
		(layer "In2.Cu")
		(hatch none 0.5)
		(connect_pads
			(clearance 0)
		)
		(min_thickness 0.25)
		(keepout
			(tracks not_allowed)
			(vias allowed)
			(pads allowed)
			(copperpour not_allowed)
			(footprints allowed)
		)
		(placement
			(enabled no)
			(sheetname "")
		)
		(fill
			(thermal_gap 0.5)
			(thermal_bridge_width 0.5)
			(island_removal_mode 0)
		)
		(polygon
			(pts
				(xy 58.678826 -292.27526) (xy 60.177426 -292.27526) (xy 60.177426 -292.795198) (xy 58.678826 -292.795198)
			)
		)
	)
	(zone
		(layer "In2.Cu")
		(hatch none 0.5)
		(connect_pads
			(clearance 0)
		)
		(min_thickness 0.25)
		(keepout
			(tracks not_allowed)
			(vias allowed)
			(pads allowed)
			(copperpour not_allowed)
			(footprints allowed)
		)
		(placement
			(enabled no)
			(sheetname "")
		)
		(fill
			(thermal_gap 0.5)
			(thermal_bridge_width 0.5)
			(island_removal_mode 0)
		)
		(polygon
			(pts
				(xy 167.778684 -273.575272) (xy 169.277284 -273.575272) (xy 169.277284 -274.09521) (xy 167.778684 -274.09521)
			)
		)
	)
	(zone
		(layer "In2.Cu")
		(hatch none 0.5)
		(connect_pads
			(clearance 0)
		)
		(min_thickness 0.25)
		(keepout
			(tracks not_allowed)
			(vias allowed)
			(pads allowed)
			(copperpour not_allowed)
			(footprints allowed)
		)
		(placement
			(enabled no)
			(sheetname "")
		)
		(fill
			(thermal_gap 0.5)
			(thermal_bridge_width 0.5)
			(island_removal_mode 0)
		)
		(polygon
			(pts
				(xy 415.718752 -275.275294) (xy 417.217352 -275.275294) (xy 417.217352 -275.795232) (xy 415.718752 -275.795232)
			)
		)
	)
	(zone
		(layer "In2.Cu")
		(hatch none 0.5)
		(connect_pads
			(clearance 0)
		)
		(min_thickness 0.25)
		(keepout
			(tracks not_allowed)
			(vias allowed)
			(pads allowed)
			(copperpour not_allowed)
			(footprints allowed)
		)
		(placement
			(enabled no)
			(sheetname "")
		)
		(fill
			(thermal_gap 0.5)
			(thermal_bridge_width 0.5)
			(island_removal_mode 0)
		)
		(polygon
			(pts
				(xy 419.162738 -242.97513) (xy 420.661338 -242.97513) (xy 420.661338 -243.495068) (xy 419.162738 -243.495068)
			)
		)
	)
	(zone
		(layer "In2.Cu")
		(hatch none 0.5)
		(connect_pads
			(clearance 0)
		)
		(min_thickness 0.25)
		(keepout
			(tracks not_allowed)
			(vias allowed)
			(pads allowed)
			(copperpour not_allowed)
			(footprints allowed)
		)
		(placement
			(enabled no)
			(sheetname "")
		)
		(fill
			(thermal_gap 0.5)
			(thermal_bridge_width 0.5)
			(island_removal_mode 0)
		)
		(polygon
			(pts
				(xy 16.858742 -246.375174) (xy 18.357342 -246.375174) (xy 18.357342 -246.895112) (xy 16.858742 -246.895112)
			)
		)
	)
	(zone
		(layer "In2.Cu")
		(hatch none 0.5)
		(connect_pads
			(clearance 0)
		)
		(min_thickness 0.25)
		(keepout
			(tracks not_allowed)
			(vias allowed)
			(pads allowed)
			(copperpour not_allowed)
			(footprints allowed)
		)
		(placement
			(enabled no)
			(sheetname "")
		)
		(fill
			(thermal_gap 0.5)
			(thermal_bridge_width 0.5)
			(island_removal_mode 0)
		)
		(polygon
			(pts
				(xy 306.618894 -208.125314) (xy 308.117494 -208.125314) (xy 308.117494 -208.645252) (xy 306.618894 -208.645252)
			)
		)
	)
	(zone
		(layer "In2.Cu")
		(hatch none 0.5)
		(connect_pads
			(clearance 0)
		)
		(min_thickness 0.25)
		(keepout
			(tracks not_allowed)
			(vias allowed)
			(pads allowed)
			(copperpour not_allowed)
			(footprints allowed)
		)
		(placement
			(enabled no)
			(sheetname "")
		)
		(fill
			(thermal_gap 0.5)
			(thermal_bridge_width 0.5)
			(island_removal_mode 0)
		)
		(polygon
			(pts
				(xy 193.854578 -313.525154) (xy 195.353178 -313.525154) (xy 195.353178 -314.045092) (xy 193.854578 -314.045092)
			)
		)
	)
	(zone
		(layer "In2.Cu")
		(hatch none 0.5)
		(connect_pads
			(clearance 0)
		)
		(min_thickness 0.25)
		(keepout
			(tracks not_allowed)
			(vias allowed)
			(pads allowed)
			(copperpour not_allowed)
			(footprints allowed)
		)
		(placement
			(enabled no)
			(sheetname "")
		)
		(fill
			(thermal_gap 0.5)
			(thermal_bridge_width 0.5)
			(island_removal_mode 0)
		)
		(polygon
			(pts
				(xy 167.778684 -242.125246) (xy 169.277284 -242.125246) (xy 169.277284 -242.645184) (xy 167.778684 -242.645184)
			)
		)
	)
	(zone
		(layer "In2.Cu")
		(hatch none 0.5)
		(connect_pads
			(clearance 0)
		)
		(min_thickness 0.25)
		(keepout
			(tracks not_allowed)
			(vias allowed)
			(pads allowed)
			(copperpour not_allowed)
			(footprints allowed)
		)
		(placement
			(enabled no)
			(sheetname "")
		)
		(fill
			(thermal_gap 0.5)
			(thermal_bridge_width 0.5)
			(island_removal_mode 0)
		)
		(polygon
			(pts
				(xy 51.134772 -250.625102) (xy 52.633372 -250.625102) (xy 52.633372 -251.14504) (xy 51.134772 -251.14504)
			)
		)
	)
	(zone
		(layer "In2.Cu")
		(hatch none 0.5)
		(connect_pads
			(clearance 0)
		)
		(min_thickness 0.25)
		(keepout
			(tracks not_allowed)
			(vias allowed)
			(pads allowed)
			(copperpour not_allowed)
			(footprints allowed)
		)
		(placement
			(enabled no)
			(sheetname "")
		)
		(fill
			(thermal_gap 0.5)
			(thermal_bridge_width 0.5)
			(island_removal_mode 0)
		)
		(polygon
			(pts
				(xy 445.894968 -215.775286) (xy 447.393568 -215.775286) (xy 447.393568 -216.295224) (xy 445.894968 -216.295224)
			)
		)
	)
	(zone
		(layer "In2.Cu")
		(hatch none 0.5)
		(connect_pads
			(clearance 0)
		)
		(min_thickness 0.25)
		(keepout
			(tracks not_allowed)
			(vias allowed)
			(pads allowed)
			(copperpour not_allowed)
			(footprints allowed)
		)
		(placement
			(enabled no)
			(sheetname "")
		)
		(fill
			(thermal_gap 0.5)
			(thermal_bridge_width 0.5)
			(island_removal_mode 0)
		)
		(polygon
			(pts
				(xy 423.262806 -273.575272) (xy 424.761406 -273.575272) (xy 424.761406 -274.09521) (xy 423.262806 -274.09521)
			)
		)
	)
	(zone
		(layer "In2.Cu")
		(hatch none 0.5)
		(connect_pads
			(clearance 0)
		)
		(min_thickness 0.25)
		(keepout
			(tracks not_allowed)
			(vias allowed)
			(pads allowed)
			(copperpour not_allowed)
			(footprints allowed)
		)
		(placement
			(enabled no)
			(sheetname "")
		)
		(fill
			(thermal_gap 0.5)
			(thermal_bridge_width 0.5)
			(island_removal_mode 0)
		)
		(polygon
			(pts
				(xy 419.162738 -297.375326) (xy 420.661338 -297.375326) (xy 420.661338 -297.895264) (xy 419.162738 -297.895264)
			)
		)
	)
	(zone
		(layer "In2.Cu")
		(hatch none 0.5)
		(connect_pads
			(clearance 0)
		)
		(min_thickness 0.25)
		(keepout
			(tracks allowed)
			(vias allowed)
			(pads allowed)
			(copperpour allowed)
			(footprints allowed)
		)
		(placement
			(enabled no)
			(sheetname "")
		)
		(fill
			(thermal_gap 0.5)
			(thermal_bridge_width 0.5)
			(island_removal_mode 0)
		)
		(polygon
			(pts
				(xy 374.809258 -178.132232) (xy 374.809258 -179.003452) (xy 374.499378 -179.003452) (xy 374.499378 -178.132232)
			)
		)
	)
	(zone
		(layer "In2.Cu")
		(hatch none 0.5)
		(connect_pads
			(clearance 0)
		)
		(min_thickness 0.25)
		(keepout
			(tracks not_allowed)
			(vias allowed)
			(pads allowed)
			(copperpour not_allowed)
			(footprints allowed)
		)
		(placement
			(enabled no)
			(sheetname "")
		)
		(fill
			(thermal_gap 0.5)
			(thermal_bridge_width 0.5)
			(island_removal_mode 0)
		)
		(polygon
			(pts
				(xy 268.898878 -290.575238) (xy 270.397478 -290.575238) (xy 270.397478 -291.095176) (xy 268.898878 -291.095176)
			)
		)
	)
	(zone
		(layer "In2.Cu")
		(hatch none 0.5)
		(connect_pads
			(clearance 0)
		)
		(min_thickness 0.25)
		(keepout
			(tracks not_allowed)
			(vias allowed)
			(pads allowed)
			(copperpour not_allowed)
			(footprints allowed)
		)
		(placement
			(enabled no)
			(sheetname "")
		)
		(fill
			(thermal_gap 0.5)
			(thermal_bridge_width 0.5)
			(island_removal_mode 0)
		)
		(polygon
			(pts
				(xy 190.410846 -304.17516) (xy 191.909446 -304.17516) (xy 191.909446 -304.695098) (xy 190.410846 -304.695098)
			)
		)
	)
	(zone
		(layer "In2.Cu")
		(hatch none 0.5)
		(connect_pads
			(clearance 0)
		)
		(min_thickness 0.25)
		(keepout
			(tracks not_allowed)
			(vias allowed)
			(pads allowed)
			(copperpour not_allowed)
			(footprints allowed)
		)
		(placement
			(enabled no)
			(sheetname "")
		)
		(fill
			(thermal_gap 0.5)
			(thermal_bridge_width 0.5)
			(island_removal_mode 0)
		)
		(polygon
			(pts
				(xy 426.706792 -227.675186) (xy 428.205392 -227.675186) (xy 428.205392 -228.195124) (xy 426.706792 -228.195124)
			)
		)
	)
	(zone
		(layer "In2.Cu")
		(hatch none 0.5)
		(connect_pads
			(clearance 0)
		)
		(min_thickness 0.25)
		(keepout
			(tracks not_allowed)
			(vias allowed)
			(pads allowed)
			(copperpour not_allowed)
			(footprints allowed)
		)
		(placement
			(enabled no)
			(sheetname "")
		)
		(fill
			(thermal_gap 0.5)
			(thermal_bridge_width 0.5)
			(island_removal_mode 0)
		)
		(polygon
			(pts
				(xy 36.046664 -309.275226) (xy 37.545264 -309.275226) (xy 37.545264 -309.795164) (xy 36.046664 -309.795164)
			)
		)
	)
	(zone
		(layer "In2.Cu")
		(hatch none 0.5)
		(connect_pads
			(clearance 0)
		)
		(min_thickness 0.25)
		(keepout
			(tracks not_allowed)
			(vias allowed)
			(pads allowed)
			(copperpour not_allowed)
			(footprints allowed)
		)
		(placement
			(enabled no)
			(sheetname "")
		)
		(fill
			(thermal_gap 0.5)
			(thermal_bridge_width 0.5)
			(island_removal_mode 0)
		)
		(polygon
			(pts
				(xy 47.034704 -316.075314) (xy 48.533304 -316.075314) (xy 48.533304 -316.595252) (xy 47.034704 -316.595252)
			)
		)
	)
	(zone
		(layer "In2.Cu")
		(hatch none 0.5)
		(connect_pads
			(clearance 0)
		)
		(min_thickness 0.25)
		(keepout
			(tracks not_allowed)
			(vias allowed)
			(pads allowed)
			(copperpour not_allowed)
			(footprints allowed)
		)
		(placement
			(enabled no)
			(sheetname "")
		)
		(fill
			(thermal_gap 0.5)
			(thermal_bridge_width 0.5)
			(island_removal_mode 0)
		)
		(polygon
			(pts
				(xy 16.858742 -220.875098) (xy 18.357342 -220.875098) (xy 18.357342 -221.395036) (xy 16.858742 -221.395036)
			)
		)
	)
	(zone
		(layer "In2.Cu")
		(hatch none 0.5)
		(connect_pads
			(clearance 0)
		)
		(min_thickness 0.25)
		(keepout
			(tracks not_allowed)
			(vias allowed)
			(pads allowed)
			(copperpour not_allowed)
			(footprints allowed)
		)
		(placement
			(enabled no)
			(sheetname "")
		)
		(fill
			(thermal_gap 0.5)
			(thermal_bridge_width 0.5)
			(island_removal_mode 0)
		)
		(polygon
			(pts
				(xy 20.95881 -231.07523) (xy 22.45741 -231.07523) (xy 22.45741 -231.595168) (xy 20.95881 -231.595168)
			)
		)
	)
	(zone
		(layer "In2.Cu")
		(hatch none 0.5)
		(connect_pads
			(clearance 0)
		)
		(min_thickness 0.25)
		(keepout
			(tracks allowed)
			(vias allowed)
			(pads allowed)
			(copperpour allowed)
			(footprints allowed)
		)
		(placement
			(enabled no)
			(sheetname "")
		)
		(fill
			(thermal_gap 0.5)
			(thermal_bridge_width 0.5)
			(island_removal_mode 0)
		)
		(polygon
			(pts
				(xy 34.95675 -350.473772) (xy 34.95675 -351.278952) (xy 34.82467 -351.278952) (xy 34.82467 -350.473772)
			)
		)
	)
	(zone
		(layer "In2.Cu")
		(hatch none 0.5)
		(connect_pads
			(clearance 0)
		)
		(min_thickness 0.25)
		(keepout
			(tracks not_allowed)
			(vias allowed)
			(pads allowed)
			(copperpour not_allowed)
			(footprints allowed)
		)
		(placement
			(enabled no)
			(sheetname "")
		)
		(fill
			(thermal_gap 0.5)
			(thermal_bridge_width 0.5)
			(island_removal_mode 0)
		)
		(polygon
			(pts
				(xy 31.946596 -313.525154) (xy 33.445196 -313.525154) (xy 33.445196 -314.045092) (xy 31.946596 -314.045092)
			)
		)
	)
	(zone
		(layer "In2.Cu")
		(hatch none 0.5)
		(connect_pads
			(clearance 0)
		)
		(min_thickness 0.25)
		(keepout
			(tracks not_allowed)
			(vias allowed)
			(pads allowed)
			(copperpour not_allowed)
			(footprints allowed)
		)
		(placement
			(enabled no)
			(sheetname "")
		)
		(fill
			(thermal_gap 0.5)
			(thermal_bridge_width 0.5)
			(island_removal_mode 0)
		)
		(polygon
			(pts
				(xy 31.946596 -276.125178) (xy 33.445196 -276.125178) (xy 33.445196 -276.645116) (xy 31.946596 -276.645116)
			)
		)
	)
	(zone
		(layer "In2.Cu")
		(hatch none 0.5)
		(connect_pads
			(clearance 0)
		)
		(min_thickness 0.25)
		(keepout
			(tracks not_allowed)
			(vias allowed)
			(pads allowed)
			(copperpour not_allowed)
			(footprints allowed)
		)
		(placement
			(enabled no)
			(sheetname "")
		)
		(fill
			(thermal_gap 0.5)
			(thermal_bridge_width 0.5)
			(island_removal_mode 0)
		)
		(polygon
			(pts
				(xy 16.858742 -227.675186) (xy 18.357342 -227.675186) (xy 18.357342 -228.195124) (xy 16.858742 -228.195124)
			)
		)
	)
	(zone
		(layer "In2.Cu")
		(hatch none 0.5)
		(connect_pads
			(clearance 0)
		)
		(min_thickness 0.25)
		(keepout
			(tracks not_allowed)
			(vias allowed)
			(pads allowed)
			(copperpour not_allowed)
			(footprints allowed)
		)
		(placement
			(enabled no)
			(sheetname "")
		)
		(fill
			(thermal_gap 0.5)
			(thermal_bridge_width 0.5)
			(island_removal_mode 0)
		)
		(polygon
			(pts
				(xy 193.854578 -289.725354) (xy 195.353178 -289.725354) (xy 195.353178 -290.245292) (xy 193.854578 -290.245292)
			)
		)
	)
	(zone
		(layer "In2.Cu")
		(hatch none 0.5)
		(connect_pads
			(clearance 0)
		)
		(min_thickness 0.25)
		(keepout
			(tracks not_allowed)
			(vias allowed)
			(pads allowed)
			(copperpour not_allowed)
			(footprints allowed)
		)
		(placement
			(enabled no)
			(sheetname "")
		)
		(fill
			(thermal_gap 0.5)
			(thermal_bridge_width 0.5)
			(island_removal_mode 0)
		)
		(polygon
			(pts
				(xy 201.398632 -317.775336) (xy 202.897232 -317.775336) (xy 202.897232 -318.295274) (xy 201.398632 -318.295274)
			)
		)
	)
	(zone
		(layer "In2.Cu")
		(hatch none 0.5)
		(connect_pads
			(clearance 0)
		)
		(min_thickness 0.25)
		(keepout
			(tracks not_allowed)
			(vias allowed)
			(pads allowed)
			(copperpour not_allowed)
			(footprints allowed)
		)
		(placement
			(enabled no)
			(sheetname "")
		)
		(fill
			(thermal_gap 0.5)
			(thermal_bridge_width 0.5)
			(island_removal_mode 0)
		)
		(polygon
			(pts
				(xy 54.578758 -251.47524) (xy 56.077358 -251.47524) (xy 56.077358 -251.995178) (xy 54.578758 -251.995178)
			)
		)
	)
	(zone
		(layer "In2.Cu")
		(hatch none 0.5)
		(connect_pads
			(clearance 0)
		)
		(min_thickness 0.25)
		(keepout
			(tracks not_allowed)
			(vias allowed)
			(pads allowed)
			(copperpour not_allowed)
			(footprints allowed)
		)
		(placement
			(enabled no)
			(sheetname "")
		)
		(fill
			(thermal_gap 0.5)
			(thermal_bridge_width 0.5)
			(island_removal_mode 0)
		)
		(polygon
			(pts
				(xy 426.706792 -272.725134) (xy 428.205392 -272.725134) (xy 428.205392 -273.245072) (xy 426.706792 -273.245072)
			)
		)
	)
	(zone
		(layer "In2.Cu")
		(hatch none 0.5)
		(connect_pads
			(clearance 0)
		)
		(min_thickness 0.25)
		(keepout
			(tracks not_allowed)
			(vias allowed)
			(pads allowed)
			(copperpour not_allowed)
			(footprints allowed)
		)
		(placement
			(enabled no)
			(sheetname "")
		)
		(fill
			(thermal_gap 0.5)
			(thermal_bridge_width 0.5)
			(island_removal_mode 0)
		)
		(polygon
			(pts
				(xy 167.778684 -240.425224) (xy 169.277284 -240.425224) (xy 169.277284 -240.945162) (xy 167.778684 -240.945162)
			)
		)
	)
	(zone
		(layer "In2.Cu")
		(hatch none 0.5)
		(connect_pads
			(clearance 0)
		)
		(min_thickness 0.25)
		(keepout
			(tracks not_allowed)
			(vias allowed)
			(pads allowed)
			(copperpour not_allowed)
			(footprints allowed)
		)
		(placement
			(enabled no)
			(sheetname "")
		)
		(fill
			(thermal_gap 0.5)
			(thermal_bridge_width 0.5)
			(island_removal_mode 0)
		)
		(polygon
			(pts
				(xy 441.7949 -205.575154) (xy 443.2935 -205.575154) (xy 443.2935 -206.095092) (xy 441.7949 -206.095092)
			)
		)
	)
	(zone
		(layer "In2.Cu")
		(hatch none 0.5)
		(connect_pads
			(clearance 0)
		)
		(min_thickness 0.25)
		(keepout
			(tracks not_allowed)
			(vias allowed)
			(pads allowed)
			(copperpour not_allowed)
			(footprints allowed)
		)
		(placement
			(enabled no)
			(sheetname "")
		)
		(fill
			(thermal_gap 0.5)
			(thermal_bridge_width 0.5)
			(island_removal_mode 0)
		)
		(polygon
			(pts
				(xy 453.438768 -247.225312) (xy 454.937368 -247.225312) (xy 454.937368 -247.74525) (xy 453.438768 -247.74525)
			)
		)
	)
	(zone
		(layer "In2.Cu")
		(hatch none 0.5)
		(connect_pads
			(clearance 0)
		)
		(min_thickness 0.25)
		(keepout
			(tracks not_allowed)
			(vias allowed)
			(pads allowed)
			(copperpour not_allowed)
			(footprints allowed)
		)
		(placement
			(enabled no)
			(sheetname "")
		)
		(fill
			(thermal_gap 0.5)
			(thermal_bridge_width 0.5)
			(island_removal_mode 0)
		)
		(polygon
			(pts
				(xy 445.894968 -316.925198) (xy 447.393568 -316.925198) (xy 447.393568 -317.445136) (xy 445.894968 -317.445136)
			)
		)
	)
	(zone
		(layer "In2.Cu")
		(hatch none 0.5)
		(connect_pads
			(clearance 0)
		)
		(min_thickness 0.25)
		(keepout
			(tracks allowed)
			(vias allowed)
			(pads allowed)
			(copperpour allowed)
			(footprints allowed)
		)
		(placement
			(enabled no)
			(sheetname "")
		)
		(fill
			(thermal_gap 0.5)
			(thermal_bridge_width 0.5)
			(island_removal_mode 0)
		)
		(polygon
			(pts
				(xy 186.352434 -355.169978) (xy 186.352434 -354.547678) (xy 186.903614 -354.547678) (xy 186.903614 -355.169978)
			)
		)
	)
	(zone
		(layer "In2.Cu")
		(hatch none 0.5)
		(connect_pads
			(clearance 0)
		)
		(min_thickness 0.25)
		(keepout
			(tracks not_allowed)
			(vias allowed)
			(pads allowed)
			(copperpour not_allowed)
			(footprints allowed)
		)
		(placement
			(enabled no)
			(sheetname "")
		)
		(fill
			(thermal_gap 0.5)
			(thermal_bridge_width 0.5)
			(island_removal_mode 0)
		)
		(polygon
			(pts
				(xy 31.946596 -297.375326) (xy 33.445196 -297.375326) (xy 33.445196 -297.895264) (xy 31.946596 -297.895264)
			)
		)
	)
	(zone
		(layer "In2.Cu")
		(hatch none 0.5)
		(connect_pads
			(clearance 0)
		)
		(min_thickness 0.25)
		(keepout
			(tracks not_allowed)
			(vias allowed)
			(pads allowed)
			(copperpour not_allowed)
			(footprints allowed)
		)
		(placement
			(enabled no)
			(sheetname "")
		)
		(fill
			(thermal_gap 0.5)
			(thermal_bridge_width 0.5)
			(island_removal_mode 0)
		)
		(polygon
			(pts
				(xy 449.3387 -229.375208) (xy 450.8373 -229.375208) (xy 450.8373 -229.895146) (xy 449.3387 -229.895146)
			)
		)
	)
	(zone
		(layer "In2.Cu")
		(hatch none 0.5)
		(connect_pads
			(clearance 0)
		)
		(min_thickness 0.25)
		(keepout
			(tracks not_allowed)
			(vias allowed)
			(pads allowed)
			(copperpour not_allowed)
			(footprints allowed)
		)
		(placement
			(enabled no)
			(sheetname "")
		)
		(fill
			(thermal_gap 0.5)
			(thermal_bridge_width 0.5)
			(island_removal_mode 0)
		)
		(polygon
			(pts
				(xy 302.518826 -211.525104) (xy 304.017426 -211.525104) (xy 304.017426 -212.045042) (xy 302.518826 -212.045042)
			)
		)
	)
	(zone
		(layer "In2.Cu")
		(hatch none 0.5)
		(connect_pads
			(clearance 0)
		)
		(min_thickness 0.25)
		(keepout
			(tracks not_allowed)
			(vias allowed)
			(pads allowed)
			(copperpour not_allowed)
			(footprints allowed)
		)
		(placement
			(enabled no)
			(sheetname "")
		)
		(fill
			(thermal_gap 0.5)
			(thermal_bridge_width 0.5)
			(island_removal_mode 0)
		)
		(polygon
			(pts
				(xy 51.134772 -312.67527) (xy 52.633372 -312.67527) (xy 52.633372 -313.195208) (xy 51.134772 -313.195208)
			)
		)
	)
	(zone
		(layer "In2.Cu")
		(hatch none 0.5)
		(connect_pads
			(clearance 0)
		)
		(min_thickness 0.25)
		(keepout
			(tracks not_allowed)
			(vias allowed)
			(pads allowed)
			(copperpour not_allowed)
			(footprints allowed)
		)
		(placement
			(enabled no)
			(sheetname "")
		)
		(fill
			(thermal_gap 0.5)
			(thermal_bridge_width 0.5)
			(island_removal_mode 0)
		)
		(polygon
			(pts
				(xy 190.410846 -284.625288) (xy 191.909446 -284.625288) (xy 191.909446 -285.145226) (xy 190.410846 -285.145226)
			)
		)
	)
	(zone
		(layer "In2.Cu")
		(hatch none 0.5)
		(connect_pads
			(clearance 0)
		)
		(min_thickness 0.25)
		(keepout
			(tracks not_allowed)
			(vias allowed)
			(pads allowed)
			(copperpour not_allowed)
			(footprints allowed)
		)
		(placement
			(enabled no)
			(sheetname "")
		)
		(fill
			(thermal_gap 0.5)
			(thermal_bridge_width 0.5)
			(island_removal_mode 0)
		)
		(polygon
			(pts
				(xy 283.986732 -293.975282) (xy 285.485332 -293.975282) (xy 285.485332 -294.49522) (xy 283.986732 -294.49522)
			)
		)
	)
	(zone
		(layer "In2.Cu")
		(hatch none 0.5)
		(connect_pads
			(clearance 0)
		)
		(min_thickness 0.25)
		(keepout
			(tracks not_allowed)
			(vias allowed)
			(pads allowed)
			(copperpour not_allowed)
			(footprints allowed)
		)
		(placement
			(enabled no)
			(sheetname "")
		)
		(fill
			(thermal_gap 0.5)
			(thermal_bridge_width 0.5)
			(island_removal_mode 0)
		)
		(polygon
			(pts
				(xy 276.442932 -231.07523) (xy 277.941532 -231.07523) (xy 277.941532 -231.595168) (xy 276.442932 -231.595168)
			)
		)
	)
	(zone
		(layer "In2.Cu")
		(hatch none 0.5)
		(connect_pads
			(clearance 0)
		)
		(min_thickness 0.25)
		(keepout
			(tracks not_allowed)
			(vias allowed)
			(pads allowed)
			(copperpour not_allowed)
			(footprints allowed)
		)
		(placement
			(enabled no)
			(sheetname "")
		)
		(fill
			(thermal_gap 0.5)
			(thermal_bridge_width 0.5)
			(island_removal_mode 0)
		)
		(polygon
			(pts
				(xy 31.946596 -207.275176) (xy 33.445196 -207.275176) (xy 33.445196 -207.795114) (xy 31.946596 -207.795114)
			)
		)
	)
	(zone
		(layer "In2.Cu")
		(hatch none 0.5)
		(connect_pads
			(clearance 0)
		)
		(min_thickness 0.25)
		(keepout
			(tracks not_allowed)
			(vias allowed)
			(pads allowed)
			(copperpour not_allowed)
			(footprints allowed)
		)
		(placement
			(enabled no)
			(sheetname "")
		)
		(fill
			(thermal_gap 0.5)
			(thermal_bridge_width 0.5)
			(island_removal_mode 0)
		)
		(polygon
			(pts
				(xy 283.986732 -225.12528) (xy 285.485332 -225.12528) (xy 285.485332 -225.645218) (xy 283.986732 -225.645218)
			)
		)
	)
	(zone
		(layer "In2.Cu")
		(hatch none 0.5)
		(connect_pads
			(clearance 0)
		)
		(min_thickness 0.25)
		(keepout
			(tracks not_allowed)
			(vias allowed)
			(pads allowed)
			(copperpour not_allowed)
			(footprints allowed)
		)
		(placement
			(enabled no)
			(sheetname "")
		)
		(fill
			(thermal_gap 0.5)
			(thermal_bridge_width 0.5)
			(island_removal_mode 0)
		)
		(polygon
			(pts
				(xy 175.322738 -292.27526) (xy 176.821338 -292.27526) (xy 176.821338 -292.795198) (xy 175.322738 -292.795198)
			)
		)
	)
	(zone
		(layer "In2.Cu")
		(hatch none 0.5)
		(connect_pads
			(clearance 0)
		)
		(min_thickness 0.25)
		(keepout
			(tracks not_allowed)
			(vias allowed)
			(pads allowed)
			(copperpour not_allowed)
			(footprints allowed)
		)
		(placement
			(enabled no)
			(sheetname "")
		)
		(fill
			(thermal_gap 0.5)
			(thermal_bridge_width 0.5)
			(island_removal_mode 0)
		)
		(polygon
			(pts
				(xy 423.262806 -281.225244) (xy 424.761406 -281.225244) (xy 424.761406 -281.745182) (xy 423.262806 -281.745182)
			)
		)
	)
	(zone
		(layer "In2.Cu")
		(hatch none 0.5)
		(connect_pads
			(clearance 0)
		)
		(min_thickness 0.25)
		(keepout
			(tracks not_allowed)
			(vias allowed)
			(pads allowed)
			(copperpour not_allowed)
			(footprints allowed)
		)
		(placement
			(enabled no)
			(sheetname "")
		)
		(fill
			(thermal_gap 0.5)
			(thermal_bridge_width 0.5)
			(island_removal_mode 0)
		)
		(polygon
			(pts
				(xy 441.7949 -266.775184) (xy 443.2935 -266.775184) (xy 443.2935 -267.295122) (xy 441.7949 -267.295122)
			)
		)
	)
	(zone
		(layer "In2.Cu")
		(hatch none 0.5)
		(connect_pads
			(clearance 0)
		)
		(min_thickness 0.25)
		(keepout
			(tracks not_allowed)
			(vias allowed)
			(pads allowed)
			(copperpour not_allowed)
			(footprints allowed)
		)
		(placement
			(enabled no)
			(sheetname "")
		)
		(fill
			(thermal_gap 0.5)
			(thermal_bridge_width 0.5)
			(island_removal_mode 0)
		)
		(polygon
			(pts
				(xy 445.894968 -226.825302) (xy 447.393568 -226.825302) (xy 447.393568 -227.34524) (xy 445.894968 -227.34524)
			)
		)
	)
	(zone
		(layer "In2.Cu")
		(hatch none 0.5)
		(connect_pads
			(clearance 0)
		)
		(min_thickness 0.25)
		(keepout
			(tracks not_allowed)
			(vias allowed)
			(pads allowed)
			(copperpour not_allowed)
			(footprints allowed)
		)
		(placement
			(enabled no)
			(sheetname "")
		)
		(fill
			(thermal_gap 0.5)
			(thermal_bridge_width 0.5)
			(island_removal_mode 0)
		)
		(polygon
			(pts
				(xy 36.046664 -298.22521) (xy 37.545264 -298.22521) (xy 37.545264 -298.745148) (xy 36.046664 -298.745148)
			)
		)
	)
	(zone
		(layer "In2.Cu")
		(hatch none 0.5)
		(connect_pads
			(clearance 0)
		)
		(min_thickness 0.25)
		(keepout
			(tracks not_allowed)
			(vias allowed)
			(pads allowed)
			(copperpour not_allowed)
			(footprints allowed)
		)
		(placement
			(enabled no)
			(sheetname "")
		)
		(fill
			(thermal_gap 0.5)
			(thermal_bridge_width 0.5)
			(island_removal_mode 0)
		)
		(polygon
			(pts
				(xy 135.88365 -35.762438) (xy 135.88365 -35.184588) (xy 137.20445 -35.184588) (xy 137.20445 -35.762438)
			)
		)
	)
	(zone
		(layer "In2.Cu")
		(hatch none 0.5)
		(connect_pads
			(clearance 0)
		)
		(min_thickness 0.25)
		(keepout
			(tracks not_allowed)
			(vias allowed)
			(pads allowed)
			(copperpour not_allowed)
			(footprints allowed)
		)
		(placement
			(enabled no)
			(sheetname "")
		)
		(fill
			(thermal_gap 0.5)
			(thermal_bridge_width 0.5)
			(island_removal_mode 0)
		)
		(polygon
			(pts
				(xy 28.50261 -237.875318) (xy 30.00121 -237.875318) (xy 30.00121 -238.395256) (xy 28.50261 -238.395256)
			)
		)
	)
	(zone
		(layer "In2.Cu")
		(hatch none 0.5)
		(connect_pads
			(clearance 0)
		)
		(min_thickness 0.25)
		(keepout
			(tracks not_allowed)
			(vias allowed)
			(pads allowed)
			(copperpour not_allowed)
			(footprints allowed)
		)
		(placement
			(enabled no)
			(sheetname "")
		)
		(fill
			(thermal_gap 0.5)
			(thermal_bridge_width 0.5)
			(island_removal_mode 0)
		)
		(polygon
			(pts
				(xy 171.22267 -278.675338) (xy 172.72127 -278.675338) (xy 172.72127 -279.195276) (xy 171.22267 -279.195276)
			)
		)
	)
	(zone
		(layer "In2.Cu")
		(hatch none 0.5)
		(connect_pads
			(clearance 0)
		)
		(min_thickness 0.25)
		(keepout
			(tracks not_allowed)
			(vias allowed)
			(pads allowed)
			(copperpour not_allowed)
			(footprints allowed)
		)
		(placement
			(enabled no)
			(sheetname "")
		)
		(fill
			(thermal_gap 0.5)
			(thermal_bridge_width 0.5)
			(island_removal_mode 0)
		)
		(polygon
			(pts
				(xy 163.678616 -238.725202) (xy 165.177216 -238.725202) (xy 165.177216 -239.24514) (xy 163.678616 -239.24514)
			)
		)
	)
	(zone
		(layer "In2.Cu")
		(hatch none 0.5)
		(connect_pads
			(clearance 0)
		)
		(min_thickness 0.25)
		(keepout
			(tracks not_allowed)
			(vias allowed)
			(pads allowed)
			(copperpour not_allowed)
			(footprints allowed)
		)
		(placement
			(enabled no)
			(sheetname "")
		)
		(fill
			(thermal_gap 0.5)
			(thermal_bridge_width 0.5)
			(island_removal_mode 0)
		)
		(polygon
			(pts
				(xy 167.778684 -296.525188) (xy 169.277284 -296.525188) (xy 169.277284 -297.045126) (xy 167.778684 -297.045126)
			)
		)
	)
	(zone
		(layer "In2.Cu")
		(hatch none 0.5)
		(connect_pads
			(clearance 0)
		)
		(min_thickness 0.25)
		(keepout
			(tracks not_allowed)
			(vias allowed)
			(pads allowed)
			(copperpour not_allowed)
			(footprints allowed)
		)
		(placement
			(enabled no)
			(sheetname "")
		)
		(fill
			(thermal_gap 0.5)
			(thermal_bridge_width 0.5)
			(island_removal_mode 0)
		)
		(polygon
			(pts
				(xy 163.678616 -288.025332) (xy 165.177216 -288.025332) (xy 165.177216 -288.54527) (xy 163.678616 -288.54527)
			)
		)
	)
	(zone
		(layer "In2.Cu")
		(hatch none 0.5)
		(connect_pads
			(clearance 0)
		)
		(min_thickness 0.25)
		(keepout
			(tracks not_allowed)
			(vias allowed)
			(pads allowed)
			(copperpour not_allowed)
			(footprints allowed)
		)
		(placement
			(enabled no)
			(sheetname "")
		)
		(fill
			(thermal_gap 0.5)
			(thermal_bridge_width 0.5)
			(island_removal_mode 0)
		)
		(polygon
			(pts
				(xy 175.322738 -232.775252) (xy 176.821338 -232.775252) (xy 176.821338 -233.29519) (xy 175.322738 -233.29519)
			)
		)
	)
	(zone
		(layer "In2.Cu")
		(hatch none 0.5)
		(connect_pads
			(clearance 0)
		)
		(min_thickness 0.25)
		(keepout
			(tracks not_allowed)
			(vias allowed)
			(pads allowed)
			(copperpour not_allowed)
			(footprints allowed)
		)
		(placement
			(enabled no)
			(sheetname "")
		)
		(fill
			(thermal_gap 0.5)
			(thermal_bridge_width 0.5)
			(island_removal_mode 0)
		)
		(polygon
			(pts
				(xy 299.07484 -299.925232) (xy 300.57344 -299.925232) (xy 300.57344 -300.44517) (xy 299.07484 -300.44517)
			)
		)
	)
	(zone
		(layer "In2.Cu")
		(hatch none 0.5)
		(connect_pads
			(clearance 0)
		)
		(min_thickness 0.25)
		(keepout
			(tracks not_allowed)
			(vias allowed)
			(pads allowed)
			(copperpour not_allowed)
			(footprints allowed)
		)
		(placement
			(enabled no)
			(sheetname "")
		)
		(fill
			(thermal_gap 0.5)
			(thermal_bridge_width 0.5)
			(island_removal_mode 0)
		)
		(polygon
			(pts
				(xy 423.262806 -245.52529) (xy 424.761406 -245.52529) (xy 424.761406 -246.045228) (xy 423.262806 -246.045228)
			)
		)
	)
	(zone
		(layer "In2.Cu")
		(hatch none 0.5)
		(connect_pads
			(clearance 0)
		)
		(min_thickness 0.25)
		(keepout
			(tracks not_allowed)
			(vias allowed)
			(pads allowed)
			(copperpour not_allowed)
			(footprints allowed)
		)
		(placement
			(enabled no)
			(sheetname "")
		)
		(fill
			(thermal_gap 0.5)
			(thermal_bridge_width 0.5)
			(island_removal_mode 0)
		)
		(polygon
			(pts
				(xy 171.22267 -220.025214) (xy 172.72127 -220.025214) (xy 172.72127 -220.545152) (xy 171.22267 -220.545152)
			)
		)
	)
	(zone
		(layer "In2.Cu")
		(hatch none 0.5)
		(connect_pads
			(clearance 0)
		)
		(min_thickness 0.25)
		(keepout
			(tracks not_allowed)
			(vias allowed)
			(pads allowed)
			(copperpour not_allowed)
			(footprints allowed)
		)
		(placement
			(enabled no)
			(sheetname "")
		)
		(fill
			(thermal_gap 0.5)
			(thermal_bridge_width 0.5)
			(island_removal_mode 0)
		)
		(polygon
			(pts
				(xy 453.438768 -281.225244) (xy 454.937368 -281.225244) (xy 454.937368 -281.745182) (xy 453.438768 -281.745182)
			)
		)
	)
	(zone
		(layer "In2.Cu")
		(hatch none 0.5)
		(connect_pads
			(clearance 0)
		)
		(min_thickness 0.25)
		(keepout
			(tracks not_allowed)
			(vias allowed)
			(pads allowed)
			(copperpour not_allowed)
			(footprints allowed)
		)
		(placement
			(enabled no)
			(sheetname "")
		)
		(fill
			(thermal_gap 0.5)
			(thermal_bridge_width 0.5)
			(island_removal_mode 0)
		)
		(polygon
			(pts
				(xy 426.706792 -291.425122) (xy 428.205392 -291.425122) (xy 428.205392 -291.94506) (xy 426.706792 -291.94506)
			)
		)
	)
	(zone
		(layer "In2.Cu")
		(hatch none 0.5)
		(connect_pads
			(clearance 0)
		)
		(min_thickness 0.25)
		(keepout
			(tracks not_allowed)
			(vias allowed)
			(pads allowed)
			(copperpour not_allowed)
			(footprints allowed)
		)
		(placement
			(enabled no)
			(sheetname "")
		)
		(fill
			(thermal_gap 0.5)
			(thermal_bridge_width 0.5)
			(island_removal_mode 0)
		)
		(polygon
			(pts
				(xy 54.578758 -288.025332) (xy 56.077358 -288.025332) (xy 56.077358 -288.54527) (xy 54.578758 -288.54527)
			)
		)
	)
	(zone
		(layer "In2.Cu")
		(hatch none 0.5)
		(connect_pads
			(clearance 0)
		)
		(min_thickness 0.25)
		(keepout
			(tracks not_allowed)
			(vias allowed)
			(pads allowed)
			(copperpour not_allowed)
			(footprints allowed)
		)
		(placement
			(enabled no)
			(sheetname "")
		)
		(fill
			(thermal_gap 0.5)
			(thermal_bridge_width 0.5)
			(island_removal_mode 0)
		)
		(polygon
			(pts
				(xy 276.442932 -267.625322) (xy 277.941532 -267.625322) (xy 277.941532 -268.14526) (xy 276.442932 -268.14526)
			)
		)
	)
	(zone
		(layer "In2.Cu")
		(hatch none 0.5)
		(connect_pads
			(clearance 0)
		)
		(min_thickness 0.25)
		(keepout
			(tracks allowed)
			(vias allowed)
			(pads allowed)
			(copperpour allowed)
			(footprints allowed)
		)
		(placement
			(enabled no)
			(sheetname "")
		)
		(fill
			(thermal_gap 0.5)
			(thermal_bridge_width 0.5)
			(island_removal_mode 0)
		)
		(polygon
			(pts
				(xy 76.40574 -175.02886) (xy 76.40574 -174.482506) (xy 76.95819 -174.482506) (xy 76.95819 -175.02886)
			)
		)
	)
	(zone
		(layer "In2.Cu")
		(hatch none 0.5)
		(connect_pads
			(clearance 0)
		)
		(min_thickness 0.25)
		(keepout
			(tracks not_allowed)
			(vias allowed)
			(pads allowed)
			(copperpour not_allowed)
			(footprints allowed)
		)
		(placement
			(enabled no)
			(sheetname "")
		)
		(fill
			(thermal_gap 0.5)
			(thermal_bridge_width 0.5)
			(island_removal_mode 0)
		)
		(polygon
			(pts
				(xy 190.410846 -231.07523) (xy 191.909446 -231.07523) (xy 191.909446 -231.595168) (xy 190.410846 -231.595168)
			)
		)
	)
	(zone
		(layer "In2.Cu")
		(hatch none 0.5)
		(connect_pads
			(clearance 0)
		)
		(min_thickness 0.25)
		(keepout
			(tracks not_allowed)
			(vias allowed)
			(pads allowed)
			(copperpour not_allowed)
			(footprints allowed)
		)
		(placement
			(enabled no)
			(sheetname "")
		)
		(fill
			(thermal_gap 0.5)
			(thermal_bridge_width 0.5)
			(island_removal_mode 0)
		)
		(polygon
			(pts
				(xy 201.398632 -233.625136) (xy 202.897232 -233.625136) (xy 202.897232 -234.145074) (xy 201.398632 -234.145074)
			)
		)
	)
	(zone
		(layer "In2.Cu")
		(hatch none 0.5)
		(connect_pads
			(clearance 0)
		)
		(min_thickness 0.25)
		(keepout
			(tracks not_allowed)
			(vias allowed)
			(pads allowed)
			(copperpour not_allowed)
			(footprints allowed)
		)
		(placement
			(enabled no)
			(sheetname "")
		)
		(fill
			(thermal_gap 0.5)
			(thermal_bridge_width 0.5)
			(island_removal_mode 0)
		)
		(polygon
			(pts
				(xy 438.350914 -299.925232) (xy 439.849514 -299.925232) (xy 439.849514 -300.44517) (xy 438.350914 -300.44517)
			)
		)
	)
	(zone
		(layer "In2.Cu")
		(hatch none 0.5)
		(connect_pads
			(clearance 0)
		)
		(min_thickness 0.25)
		(keepout
			(tracks allowed)
			(vias allowed)
			(pads allowed)
			(copperpour allowed)
			(footprints allowed)
		)
		(placement
			(enabled no)
			(sheetname "")
		)
		(fill
			(thermal_gap 0.5)
			(thermal_bridge_width 0.5)
			(island_removal_mode 0)
		)
		(polygon
			(pts
				(xy 377.08713 -180.231034) (xy 377.08713 -179.68468) (xy 377.63958 -179.68468) (xy 377.63958 -180.231034)
			)
		)
	)
	(zone
		(layer "In2.Cu")
		(hatch none 0.5)
		(connect_pads
			(clearance 0)
		)
		(min_thickness 0.25)
		(keepout
			(tracks not_allowed)
			(vias allowed)
			(pads allowed)
			(copperpour not_allowed)
			(footprints allowed)
		)
		(placement
			(enabled no)
			(sheetname "")
		)
		(fill
			(thermal_gap 0.5)
			(thermal_bridge_width 0.5)
			(island_removal_mode 0)
		)
		(polygon
			(pts
				(xy 423.262806 -250.625102) (xy 424.761406 -250.625102) (xy 424.761406 -251.14504) (xy 423.262806 -251.14504)
			)
		)
	)
	(zone
		(layer "In2.Cu")
		(hatch none 0.5)
		(connect_pads
			(clearance 0)
		)
		(min_thickness 0.25)
		(keepout
			(tracks not_allowed)
			(vias allowed)
			(pads allowed)
			(copperpour not_allowed)
			(footprints allowed)
		)
		(placement
			(enabled no)
			(sheetname "")
		)
		(fill
			(thermal_gap 0.5)
			(thermal_bridge_width 0.5)
			(island_removal_mode 0)
		)
		(polygon
			(pts
				(xy 167.778684 -208.125314) (xy 169.277284 -208.125314) (xy 169.277284 -208.645252) (xy 167.778684 -208.645252)
			)
		)
	)
	(zone
		(layer "In2.Cu")
		(hatch none 0.5)
		(connect_pads
			(clearance 0)
		)
		(min_thickness 0.25)
		(keepout
			(tracks not_allowed)
			(vias allowed)
			(pads allowed)
			(copperpour not_allowed)
			(footprints allowed)
		)
		(placement
			(enabled no)
			(sheetname "")
		)
		(fill
			(thermal_gap 0.5)
			(thermal_bridge_width 0.5)
			(island_removal_mode 0)
		)
		(polygon
			(pts
				(xy 175.322738 -248.925334) (xy 176.821338 -248.925334) (xy 176.821338 -249.445272) (xy 175.322738 -249.445272)
			)
		)
	)
	(zone
		(layer "In2.Cu")
		(hatch none 0.5)
		(connect_pads
			(clearance 0)
		)
		(min_thickness 0.25)
		(keepout
			(tracks not_allowed)
			(vias allowed)
			(pads allowed)
			(copperpour not_allowed)
			(footprints allowed)
		)
		(placement
			(enabled no)
			(sheetname "")
		)
		(fill
			(thermal_gap 0.5)
			(thermal_bridge_width 0.5)
			(island_removal_mode 0)
		)
		(polygon
			(pts
				(xy 54.578758 -197.925182) (xy 56.077358 -197.925182) (xy 56.077358 -198.44512) (xy 54.578758 -198.44512)
			)
		)
	)
	(zone
		(layer "In2.Cu")
		(hatch none 0.5)
		(connect_pads
			(clearance 0)
		)
		(min_thickness 0.25)
		(keepout
			(tracks not_allowed)
			(vias allowed)
			(pads allowed)
			(copperpour not_allowed)
			(footprints allowed)
		)
		(placement
			(enabled no)
			(sheetname "")
		)
		(fill
			(thermal_gap 0.5)
			(thermal_bridge_width 0.5)
			(island_removal_mode 0)
		)
		(polygon
			(pts
				(xy 291.530786 -273.575272) (xy 293.029386 -273.575272) (xy 293.029386 -274.09521) (xy 291.530786 -274.09521)
			)
		)
	)
	(zone
		(layer "In2.Cu")
		(hatch none 0.5)
		(connect_pads
			(clearance 0)
		)
		(min_thickness 0.25)
		(keepout
			(tracks not_allowed)
			(vias allowed)
			(pads allowed)
			(copperpour not_allowed)
			(footprints allowed)
		)
		(placement
			(enabled no)
			(sheetname "")
		)
		(fill
			(thermal_gap 0.5)
			(thermal_bridge_width 0.5)
			(island_removal_mode 0)
		)
		(polygon
			(pts
				(xy 306.618894 -254.025146) (xy 308.117494 -254.025146) (xy 308.117494 -254.545084) (xy 306.618894 -254.545084)
			)
		)
	)
	(zone
		(layer "In2.Cu")
		(hatch none 0.5)
		(connect_pads
			(clearance 0)
		)
		(min_thickness 0.25)
		(keepout
			(tracks not_allowed)
			(vias allowed)
			(pads allowed)
			(copperpour not_allowed)
			(footprints allowed)
		)
		(placement
			(enabled no)
			(sheetname "")
		)
		(fill
			(thermal_gap 0.5)
			(thermal_bridge_width 0.5)
			(island_removal_mode 0)
		)
		(polygon
			(pts
				(xy 193.854578 -280.375106) (xy 195.353178 -280.375106) (xy 195.353178 -280.895044) (xy 193.854578 -280.895044)
			)
		)
	)
	(zone
		(layer "In2.Cu")
		(hatch none 0.5)
		(connect_pads
			(clearance 0)
		)
		(min_thickness 0.25)
		(keepout
			(tracks not_allowed)
			(vias allowed)
			(pads allowed)
			(copperpour not_allowed)
			(footprints allowed)
		)
		(placement
			(enabled no)
			(sheetname "")
		)
		(fill
			(thermal_gap 0.5)
			(thermal_bridge_width 0.5)
			(island_removal_mode 0)
		)
		(polygon
			(pts
				(xy 441.7949 -295.675304) (xy 443.2935 -295.675304) (xy 443.2935 -296.195242) (xy 441.7949 -296.195242)
			)
		)
	)
	(zone
		(layer "In2.Cu")
		(hatch none 0.5)
		(connect_pads
			(clearance 0)
		)
		(min_thickness 0.25)
		(keepout
			(tracks not_allowed)
			(vias allowed)
			(pads allowed)
			(copperpour not_allowed)
			(footprints allowed)
		)
		(placement
			(enabled no)
			(sheetname "")
		)
		(fill
			(thermal_gap 0.5)
			(thermal_bridge_width 0.5)
			(island_removal_mode 0)
		)
		(polygon
			(pts
				(xy 31.946596 -261.675118) (xy 33.445196 -261.675118) (xy 33.445196 -262.195056) (xy 31.946596 -262.195056)
			)
		)
	)
	(zone
		(layer "In2.Cu")
		(hatch none 0.5)
		(connect_pads
			(clearance 0)
		)
		(min_thickness 0.25)
		(keepout
			(tracks not_allowed)
			(vias allowed)
			(pads allowed)
			(copperpour not_allowed)
			(footprints allowed)
		)
		(placement
			(enabled no)
			(sheetname "")
		)
		(fill
			(thermal_gap 0.5)
			(thermal_bridge_width 0.5)
			(island_removal_mode 0)
		)
		(polygon
			(pts
				(arc
					(start 43.562524 -16.442436)
					(mid 43.584842 -16.496318)
					(end 43.638724 -16.518636)
				)
				(arc
					(start 43.834304 -16.518636)
					(mid 43.85618 -16.515504)
					(end 43.876214 -16.50619)
				)
				(arc
					(start 44.169838 -16.313658)
					(mid 44.211494 -16.301256)
					(end 44.25315 -16.313658)
				)
				(arc
					(start 44.548044 -16.50619)
					(mid 44.567968 -16.515426)
					(end 44.5897 -16.518636)
				)
				(arc
					(start 44.784264 -16.518636)
					(mid 44.838146 -16.496318)
					(end 44.860464 -16.442436)
				)
				(arc
					(start 44.860464 -15.756636)
					(mid 44.838146 -15.702754)
					(end 44.784264 -15.680436)
				)
				(arc
					(start 44.5897 -15.680436)
					(mid 44.567956 -15.683604)
					(end 44.548044 -15.692882)
				)
				(arc
					(start 44.25188 -15.885668)
					(mid 44.210196 -15.89789)
					(end 44.168568 -15.885414)
				)
				(arc
					(start 43.874944 -15.692882)
					(mid 43.85502 -15.683646)
					(end 43.833288 -15.680436)
				)
				(arc
					(start 43.638724 -15.680436)
					(mid 43.584842 -15.702754)
					(end 43.562524 -15.756636)
				)
			)
		)
	)
	(zone
		(layer "In2.Cu")
		(hatch none 0.5)
		(connect_pads
			(clearance 0)
		)
		(min_thickness 0.25)
		(keepout
			(tracks not_allowed)
			(vias allowed)
			(pads allowed)
			(copperpour not_allowed)
			(footprints allowed)
		)
		(placement
			(enabled no)
			(sheetname "")
		)
		(fill
			(thermal_gap 0.5)
			(thermal_bridge_width 0.5)
			(island_removal_mode 0)
		)
		(polygon
			(pts
				(xy 411.618684 -261.675118) (xy 413.117284 -261.675118) (xy 413.117284 -262.195056) (xy 411.618684 -262.195056)
			)
		)
	)
	(zone
		(layer "In2.Cu")
		(hatch none 0.5)
		(connect_pads
			(clearance 0)
		)
		(min_thickness 0.25)
		(keepout
			(tracks not_allowed)
			(vias allowed)
			(pads allowed)
			(copperpour not_allowed)
			(footprints allowed)
		)
		(placement
			(enabled no)
			(sheetname "")
		)
		(fill
			(thermal_gap 0.5)
			(thermal_bridge_width 0.5)
			(island_removal_mode 0)
		)
		(polygon
			(pts
				(xy 415.718752 -220.025214) (xy 417.217352 -220.025214) (xy 417.217352 -220.545152) (xy 415.718752 -220.545152)
			)
		)
	)
	(zone
		(layer "In2.Cu")
		(hatch none 0.5)
		(connect_pads
			(clearance 0)
		)
		(min_thickness 0.25)
		(keepout
			(tracks not_allowed)
			(vias allowed)
			(pads allowed)
			(copperpour not_allowed)
			(footprints allowed)
		)
		(placement
			(enabled no)
			(sheetname "")
		)
		(fill
			(thermal_gap 0.5)
			(thermal_bridge_width 0.5)
			(island_removal_mode 0)
		)
		(polygon
			(pts
				(xy 47.034704 -210.67522) (xy 48.533304 -210.67522) (xy 48.533304 -211.195158) (xy 47.034704 -211.195158)
			)
		)
	)
	(zone
		(layer "In2.Cu")
		(hatch none 0.5)
		(connect_pads
			(clearance 0)
		)
		(min_thickness 0.25)
		(keepout
			(tracks not_allowed)
			(vias allowed)
			(pads allowed)
			(copperpour not_allowed)
			(footprints allowed)
		)
		(placement
			(enabled no)
			(sheetname "")
		)
		(fill
			(thermal_gap 0.5)
			(thermal_bridge_width 0.5)
			(island_removal_mode 0)
		)
		(polygon
			(pts
				(xy 24.402542 -199.625204) (xy 25.901142 -199.625204) (xy 25.901142 -200.145142) (xy 24.402542 -200.145142)
			)
		)
	)
	(zone
		(layer "In2.Cu")
		(hatch none 0.5)
		(connect_pads
			(clearance 0)
		)
		(min_thickness 0.25)
		(keepout
			(tracks not_allowed)
			(vias allowed)
			(pads allowed)
			(copperpour not_allowed)
			(footprints allowed)
		)
		(placement
			(enabled no)
			(sheetname "")
		)
		(fill
			(thermal_gap 0.5)
			(thermal_bridge_width 0.5)
			(island_removal_mode 0)
		)
		(polygon
			(pts
				(xy 291.530786 -200.475342) (xy 293.029386 -200.475342) (xy 293.029386 -200.99528) (xy 291.530786 -200.99528)
			)
		)
	)
	(zone
		(layer "In2.Cu")
		(hatch none 0.5)
		(connect_pads
			(clearance 0)
		)
		(min_thickness 0.25)
		(keepout
			(tracks not_allowed)
			(vias allowed)
			(pads allowed)
			(copperpour not_allowed)
			(footprints allowed)
		)
		(placement
			(enabled no)
			(sheetname "")
		)
		(fill
			(thermal_gap 0.5)
			(thermal_bridge_width 0.5)
			(island_removal_mode 0)
		)
		(polygon
			(pts
				(xy 51.134772 -304.17516) (xy 52.633372 -304.17516) (xy 52.633372 -304.695098) (xy 51.134772 -304.695098)
			)
		)
	)
	(zone
		(layer "In2.Cu")
		(hatch none 0.5)
		(connect_pads
			(clearance 0)
		)
		(min_thickness 0.25)
		(keepout
			(tracks not_allowed)
			(vias allowed)
			(pads allowed)
			(copperpour not_allowed)
			(footprints allowed)
		)
		(placement
			(enabled no)
			(sheetname "")
		)
		(fill
			(thermal_gap 0.5)
			(thermal_bridge_width 0.5)
			(island_removal_mode 0)
		)
		(polygon
			(pts
				(xy 16.858742 -272.725134) (xy 18.357342 -272.725134) (xy 18.357342 -273.245072) (xy 16.858742 -273.245072)
			)
		)
	)
	(zone
		(layer "In2.Cu")
		(hatch none 0.5)
		(connect_pads
			(clearance 0)
		)
		(min_thickness 0.25)
		(keepout
			(tracks not_allowed)
			(vias allowed)
			(pads allowed)
			(copperpour not_allowed)
			(footprints allowed)
		)
		(placement
			(enabled no)
			(sheetname "")
		)
		(fill
			(thermal_gap 0.5)
			(thermal_bridge_width 0.5)
			(island_removal_mode 0)
		)
		(polygon
			(pts
				(xy 51.134772 -214.075264) (xy 52.633372 -214.075264) (xy 52.633372 -214.595202) (xy 51.134772 -214.595202)
			)
		)
	)
	(zone
		(layer "In2.Cu")
		(hatch none 0.5)
		(connect_pads
			(clearance 0)
		)
		(min_thickness 0.25)
		(keepout
			(tracks not_allowed)
			(vias allowed)
			(pads allowed)
			(copperpour not_allowed)
			(footprints allowed)
		)
		(placement
			(enabled no)
			(sheetname "")
		)
		(fill
			(thermal_gap 0.5)
			(thermal_bridge_width 0.5)
			(island_removal_mode 0)
		)
		(polygon
			(pts
				(xy 287.430718 -254.025146) (xy 288.929318 -254.025146) (xy 288.929318 -254.545084) (xy 287.430718 -254.545084)
			)
		)
	)
	(zone
		(layer "In2.Cu")
		(hatch none 0.5)
		(connect_pads
			(clearance 0)
		)
		(min_thickness 0.25)
		(keepout
			(tracks not_allowed)
			(vias allowed)
			(pads allowed)
			(copperpour not_allowed)
			(footprints allowed)
		)
		(placement
			(enabled no)
			(sheetname "")
		)
		(fill
			(thermal_gap 0.5)
			(thermal_bridge_width 0.5)
			(island_removal_mode 0)
		)
		(polygon
			(pts
				(xy 438.350914 -315.225176) (xy 439.849514 -315.225176) (xy 439.849514 -315.745114) (xy 438.350914 -315.745114)
			)
		)
	)
	(zone
		(layer "In2.Cu")
		(hatch none 0.5)
		(connect_pads
			(clearance 0)
		)
		(min_thickness 0.25)
		(keepout
			(tracks not_allowed)
			(vias allowed)
			(pads allowed)
			(copperpour not_allowed)
			(footprints allowed)
		)
		(placement
			(enabled no)
			(sheetname "")
		)
		(fill
			(thermal_gap 0.5)
			(thermal_bridge_width 0.5)
			(island_removal_mode 0)
		)
		(polygon
			(pts
				(xy 20.95881 -292.27526) (xy 22.45741 -292.27526) (xy 22.45741 -292.795198) (xy 20.95881 -292.795198)
			)
		)
	)
	(zone
		(layer "In2.Cu")
		(hatch none 0.5)
		(connect_pads
			(clearance 0)
		)
		(min_thickness 0.25)
		(keepout
			(tracks not_allowed)
			(vias allowed)
			(pads allowed)
			(copperpour not_allowed)
			(footprints allowed)
		)
		(placement
			(enabled no)
			(sheetname "")
		)
		(fill
			(thermal_gap 0.5)
			(thermal_bridge_width 0.5)
			(island_removal_mode 0)
		)
		(polygon
			(pts
				(xy 438.350914 -240.425224) (xy 439.849514 -240.425224) (xy 439.849514 -240.945162) (xy 438.350914 -240.945162)
			)
		)
	)
	(zone
		(layer "In2.Cu")
		(hatch none 0.5)
		(connect_pads
			(clearance 0)
		)
		(min_thickness 0.25)
		(keepout
			(tracks not_allowed)
			(vias allowed)
			(pads allowed)
			(copperpour not_allowed)
			(footprints allowed)
		)
		(placement
			(enabled no)
			(sheetname "")
		)
		(fill
			(thermal_gap 0.5)
			(thermal_bridge_width 0.5)
			(island_removal_mode 0)
		)
		(polygon
			(pts
				(xy 163.678616 -289.725354) (xy 165.177216 -289.725354) (xy 165.177216 -290.245292) (xy 163.678616 -290.245292)
			)
		)
	)
	(zone
		(layer "In2.Cu")
		(hatch none 0.5)
		(connect_pads
			(clearance 0)
		)
		(min_thickness 0.25)
		(keepout
			(tracks not_allowed)
			(vias allowed)
			(pads allowed)
			(copperpour not_allowed)
			(footprints allowed)
		)
		(placement
			(enabled no)
			(sheetname "")
		)
		(fill
			(thermal_gap 0.5)
			(thermal_bridge_width 0.5)
			(island_removal_mode 0)
		)
		(polygon
			(pts
				(xy 272.342864 -214.925148) (xy 273.841464 -214.925148) (xy 273.841464 -215.445086) (xy 272.342864 -215.445086)
			)
		)
	)
	(zone
		(layer "In2.Cu")
		(hatch none 0.5)
		(connect_pads
			(clearance 0)
		)
		(min_thickness 0.25)
		(keepout
			(tracks not_allowed)
			(vias allowed)
			(pads allowed)
			(copperpour not_allowed)
			(footprints allowed)
		)
		(placement
			(enabled no)
			(sheetname "")
		)
		(fill
			(thermal_gap 0.5)
			(thermal_bridge_width 0.5)
			(island_removal_mode 0)
		)
		(polygon
			(pts
				(xy 287.430718 -220.025214) (xy 288.929318 -220.025214) (xy 288.929318 -220.545152) (xy 287.430718 -220.545152)
			)
		)
	)
	(zone
		(layer "In2.Cu")
		(hatch none 0.5)
		(connect_pads
			(clearance 0)
		)
		(min_thickness 0.25)
		(keepout
			(tracks not_allowed)
			(vias allowed)
			(pads allowed)
			(copperpour not_allowed)
			(footprints allowed)
		)
		(placement
			(enabled no)
			(sheetname "")
		)
		(fill
			(thermal_gap 0.5)
			(thermal_bridge_width 0.5)
			(island_removal_mode 0)
		)
		(polygon
			(pts
				(xy 58.678826 -237.875318) (xy 60.177426 -237.875318) (xy 60.177426 -238.395256) (xy 58.678826 -238.395256)
			)
		)
	)
	(zone
		(layer "In2.Cu")
		(hatch none 0.5)
		(connect_pads
			(clearance 0)
		)
		(min_thickness 0.25)
		(keepout
			(tracks not_allowed)
			(vias allowed)
			(pads allowed)
			(copperpour not_allowed)
			(footprints allowed)
		)
		(placement
			(enabled no)
			(sheetname "")
		)
		(fill
			(thermal_gap 0.5)
			(thermal_bridge_width 0.5)
			(island_removal_mode 0)
		)
		(polygon
			(pts
				(xy 438.350914 -212.375242) (xy 439.849514 -212.375242) (xy 439.849514 -212.89518) (xy 438.350914 -212.89518)
			)
		)
	)
	(zone
		(layer "In2.Cu")
		(hatch none 0.5)
		(connect_pads
			(clearance 0)
		)
		(min_thickness 0.25)
		(keepout
			(tracks not_allowed)
			(vias allowed)
			(pads allowed)
			(copperpour not_allowed)
			(footprints allowed)
		)
		(placement
			(enabled no)
			(sheetname "")
		)
		(fill
			(thermal_gap 0.5)
			(thermal_bridge_width 0.5)
			(island_removal_mode 0)
		)
		(polygon
			(pts
				(xy 430.80686 -226.825302) (xy 432.30546 -226.825302) (xy 432.30546 -227.34524) (xy 430.80686 -227.34524)
			)
		)
	)
	(zone
		(layer "In2.Cu")
		(hatch none 0.5)
		(connect_pads
			(clearance 0)
		)
		(min_thickness 0.25)
		(keepout
			(tracks not_allowed)
			(vias allowed)
			(pads allowed)
			(copperpour not_allowed)
			(footprints allowed)
		)
		(placement
			(enabled no)
			(sheetname "")
		)
		(fill
			(thermal_gap 0.5)
			(thermal_bridge_width 0.5)
			(island_removal_mode 0)
		)
		(polygon
			(pts
				(xy 453.438768 -307.575204) (xy 454.937368 -307.575204) (xy 454.937368 -308.095142) (xy 453.438768 -308.095142)
			)
		)
	)
	(zone
		(layer "In2.Cu")
		(hatch none 0.5)
		(connect_pads
			(clearance 0)
		)
		(min_thickness 0.25)
		(keepout
			(tracks not_allowed)
			(vias allowed)
			(pads allowed)
			(copperpour not_allowed)
			(footprints allowed)
		)
		(placement
			(enabled no)
			(sheetname "")
		)
		(fill
			(thermal_gap 0.5)
			(thermal_bridge_width 0.5)
			(island_removal_mode 0)
		)
		(polygon
			(pts
				(xy 167.778684 -209.825336) (xy 169.277284 -209.825336) (xy 169.277284 -210.345274) (xy 167.778684 -210.345274)
			)
		)
	)
	(zone
		(layer "In2.Cu")
		(hatch none 0.5)
		(connect_pads
			(clearance 0)
		)
		(min_thickness 0.25)
		(keepout
			(tracks not_allowed)
			(vias allowed)
			(pads allowed)
			(copperpour not_allowed)
			(footprints allowed)
		)
		(placement
			(enabled no)
			(sheetname "")
		)
		(fill
			(thermal_gap 0.5)
			(thermal_bridge_width 0.5)
			(island_removal_mode 0)
		)
		(polygon
			(pts
				(arc
					(start 337.416394 -384.288284)
					(mid 337.436318 -384.29752)
					(end 337.45805 -384.30073)
				)
				(arc
					(start 337.652614 -384.30073)
					(mid 337.706496 -384.278412)
					(end 337.728814 -384.22453)
				)
				(arc
					(start 337.728814 -383.53873)
					(mid 337.706496 -383.484848)
					(end 337.652614 -383.46253)
				)
				(arc
					(start 337.45805 -383.46253)
					(mid 337.436306 -383.465698)
					(end 337.416394 -383.474976)
				)
				(arc
					(start 337.12023 -383.667762)
					(mid 337.078546 -383.679984)
					(end 337.036918 -383.667508)
				)
				(arc
					(start 336.743294 -383.474976)
					(mid 336.72337 -383.46574)
					(end 336.701638 -383.46253)
				)
				(arc
					(start 336.507074 -383.46253)
					(mid 336.453192 -383.484848)
					(end 336.430874 -383.53873)
				)
				(arc
					(start 336.430874 -384.22453)
					(mid 336.453192 -384.278412)
					(end 336.507074 -384.30073)
				)
				(arc
					(start 336.702908 -384.30073)
					(mid 336.724652 -384.297562)
					(end 336.744564 -384.288284)
				)
				(arc
					(start 337.038188 -384.095752)
					(mid 337.079844 -384.08335)
					(end 337.1215 -384.095752)
				)
			)
		)
	)
	(zone
		(layer "In2.Cu")
		(hatch none 0.5)
		(connect_pads
			(clearance 0)
		)
		(min_thickness 0.25)
		(keepout
			(tracks not_allowed)
			(vias allowed)
			(pads allowed)
			(copperpour not_allowed)
			(footprints allowed)
		)
		(placement
			(enabled no)
			(sheetname "")
		)
		(fill
			(thermal_gap 0.5)
			(thermal_bridge_width 0.5)
			(island_removal_mode 0)
		)
		(polygon
			(pts
				(xy 197.954646 -209.825336) (xy 199.453246 -209.825336) (xy 199.453246 -210.345274) (xy 197.954646 -210.345274)
			)
		)
	)
	(zone
		(layer "In2.Cu")
		(hatch none 0.5)
		(connect_pads
			(clearance 0)
		)
		(min_thickness 0.25)
		(keepout
			(tracks not_allowed)
			(vias allowed)
			(pads allowed)
			(copperpour not_allowed)
			(footprints allowed)
		)
		(placement
			(enabled no)
			(sheetname "")
		)
		(fill
			(thermal_gap 0.5)
			(thermal_bridge_width 0.5)
			(island_removal_mode 0)
		)
		(polygon
			(pts
				(xy 272.342864 -229.375208) (xy 273.841464 -229.375208) (xy 273.841464 -229.895146) (xy 272.342864 -229.895146)
			)
		)
	)
	(zone
		(layer "In2.Cu")
		(hatch none 0.5)
		(connect_pads
			(clearance 0)
		)
		(min_thickness 0.25)
		(keepout
			(tracks not_allowed)
			(vias allowed)
			(pads allowed)
			(copperpour not_allowed)
			(footprints allowed)
		)
		(placement
			(enabled no)
			(sheetname "")
		)
		(fill
			(thermal_gap 0.5)
			(thermal_bridge_width 0.5)
			(island_removal_mode 0)
		)
		(polygon
			(pts
				(xy 36.046664 -252.325124) (xy 37.545264 -252.325124) (xy 37.545264 -252.845062) (xy 36.046664 -252.845062)
			)
		)
	)
	(zone
		(layer "In2.Cu")
		(hatch none 0.5)
		(connect_pads
			(clearance 0)
		)
		(min_thickness 0.25)
		(keepout
			(tracks not_allowed)
			(vias allowed)
			(pads allowed)
			(copperpour not_allowed)
			(footprints allowed)
		)
		(placement
			(enabled no)
			(sheetname "")
		)
		(fill
			(thermal_gap 0.5)
			(thermal_bridge_width 0.5)
			(island_removal_mode 0)
		)
		(polygon
			(pts
				(xy 16.858742 -201.325226) (xy 18.357342 -201.325226) (xy 18.357342 -201.845164) (xy 16.858742 -201.845164)
			)
		)
	)
	(zone
		(layer "In2.Cu")
		(hatch none 0.5)
		(connect_pads
			(clearance 0)
		)
		(min_thickness 0.25)
		(keepout
			(tracks not_allowed)
			(vias allowed)
			(pads allowed)
			(copperpour not_allowed)
			(footprints allowed)
		)
		(placement
			(enabled no)
			(sheetname "")
		)
		(fill
			(thermal_gap 0.5)
			(thermal_bridge_width 0.5)
			(island_removal_mode 0)
		)
		(polygon
			(pts
				(xy 193.854578 -310.12511) (xy 195.353178 -310.12511) (xy 195.353178 -310.645048) (xy 193.854578 -310.645048)
			)
		)
	)
	(zone
		(layer "In2.Cu")
		(hatch none 0.5)
		(connect_pads
			(clearance 0)
		)
		(min_thickness 0.25)
		(keepout
			(tracks not_allowed)
			(vias allowed)
			(pads allowed)
			(copperpour not_allowed)
			(footprints allowed)
		)
		(placement
			(enabled no)
			(sheetname "")
		)
		(fill
			(thermal_gap 0.5)
			(thermal_bridge_width 0.5)
			(island_removal_mode 0)
		)
		(polygon
			(pts
				(xy 24.402542 -220.025214) (xy 25.901142 -220.025214) (xy 25.901142 -220.545152) (xy 24.402542 -220.545152)
			)
		)
	)
	(zone
		(layer "In2.Cu")
		(hatch none 0.5)
		(connect_pads
			(clearance 0)
		)
		(min_thickness 0.25)
		(keepout
			(tracks not_allowed)
			(vias allowed)
			(pads allowed)
			(copperpour not_allowed)
			(footprints allowed)
		)
		(placement
			(enabled no)
			(sheetname "")
		)
		(fill
			(thermal_gap 0.5)
			(thermal_bridge_width 0.5)
			(island_removal_mode 0)
		)
		(polygon
			(pts
				(xy 167.778684 -203.025248) (xy 169.277284 -203.025248) (xy 169.277284 -203.545186) (xy 167.778684 -203.545186)
			)
		)
	)
	(zone
		(layer "In2.Cu")
		(hatch none 0.5)
		(connect_pads
			(clearance 0)
		)
		(min_thickness 0.25)
		(keepout
			(tracks not_allowed)
			(vias allowed)
			(pads allowed)
			(copperpour not_allowed)
			(footprints allowed)
		)
		(placement
			(enabled no)
			(sheetname "")
		)
		(fill
			(thermal_gap 0.5)
			(thermal_bridge_width 0.5)
			(island_removal_mode 0)
		)
		(polygon
			(pts
				(xy 294.974772 -285.475172) (xy 296.473372 -285.475172) (xy 296.473372 -285.99511) (xy 294.974772 -285.99511)
			)
		)
	)
	(zone
		(layer "In2.Cu")
		(hatch none 0.5)
		(connect_pads
			(clearance 0)
		)
		(min_thickness 0.25)
		(keepout
			(tracks not_allowed)
			(vias allowed)
			(pads allowed)
			(copperpour not_allowed)
			(footprints allowed)
		)
		(placement
			(enabled no)
			(sheetname "")
		)
		(fill
			(thermal_gap 0.5)
			(thermal_bridge_width 0.5)
			(island_removal_mode 0)
		)
		(polygon
			(pts
				(xy 186.310778 -213.225126) (xy 187.809378 -213.225126) (xy 187.809378 -213.745064) (xy 186.310778 -213.745064)
			)
		)
	)
	(zone
		(layer "In2.Cu")
		(hatch none 0.5)
		(connect_pads
			(clearance 0)
		)
		(min_thickness 0.25)
		(keepout
			(tracks not_allowed)
			(vias allowed)
			(pads allowed)
			(copperpour not_allowed)
			(footprints allowed)
		)
		(placement
			(enabled no)
			(sheetname "")
		)
		(fill
			(thermal_gap 0.5)
			(thermal_bridge_width 0.5)
			(island_removal_mode 0)
		)
		(polygon
			(pts
				(xy 163.678616 -237.02518) (xy 165.177216 -237.02518) (xy 165.177216 -237.545118) (xy 163.678616 -237.545118)
			)
		)
	)
	(zone
		(layer "In2.Cu")
		(hatch none 0.5)
		(connect_pads
			(clearance 0)
		)
		(min_thickness 0.25)
		(keepout
			(tracks not_allowed)
			(vias allowed)
			(pads allowed)
			(copperpour not_allowed)
			(footprints allowed)
		)
		(placement
			(enabled no)
			(sheetname "")
		)
		(fill
			(thermal_gap 0.5)
			(thermal_bridge_width 0.5)
			(island_removal_mode 0)
		)
		(polygon
			(pts
				(xy 291.530786 -254.025146) (xy 293.029386 -254.025146) (xy 293.029386 -254.545084) (xy 291.530786 -254.545084)
			)
		)
	)
	(zone
		(layer "In2.Cu")
		(hatch none 0.5)
		(connect_pads
			(clearance 0)
		)
		(min_thickness 0.25)
		(keepout
			(tracks allowed)
			(vias allowed)
			(pads allowed)
			(copperpour allowed)
			(footprints allowed)
		)
		(placement
			(enabled no)
			(sheetname "")
		)
		(fill
			(thermal_gap 0.5)
			(thermal_bridge_width 0.5)
			(island_removal_mode 0)
		)
		(polygon
			(pts
				(xy 286.24657 -349.117666) (xy 286.24657 -348.495366) (xy 286.79775 -348.495366) (xy 286.79775 -349.117666)
			)
		)
	)
	(zone
		(layer "In2.Cu")
		(hatch none 0.5)
		(connect_pads
			(clearance 0)
		)
		(min_thickness 0.25)
		(keepout
			(tracks not_allowed)
			(vias allowed)
			(pads allowed)
			(copperpour not_allowed)
			(footprints allowed)
		)
		(placement
			(enabled no)
			(sheetname "")
		)
		(fill
			(thermal_gap 0.5)
			(thermal_bridge_width 0.5)
			(island_removal_mode 0)
		)
		(polygon
			(pts
				(xy 294.974772 -207.275176) (xy 296.473372 -207.275176) (xy 296.473372 -207.795114) (xy 294.974772 -207.795114)
			)
		)
	)
	(zone
		(layer "In2.Cu")
		(hatch none 0.5)
		(connect_pads
			(clearance 0)
		)
		(min_thickness 0.25)
		(keepout
			(tracks not_allowed)
			(vias allowed)
			(pads allowed)
			(copperpour not_allowed)
			(footprints allowed)
		)
		(placement
			(enabled no)
			(sheetname "")
		)
		(fill
			(thermal_gap 0.5)
			(thermal_bridge_width 0.5)
			(island_removal_mode 0)
		)
		(polygon
			(pts
				(xy 445.894968 -304.17516) (xy 447.393568 -304.17516) (xy 447.393568 -304.695098) (xy 445.894968 -304.695098)
			)
		)
	)
	(zone
		(layer "In2.Cu")
		(hatch none 0.5)
		(connect_pads
			(clearance 0)
		)
		(min_thickness 0.25)
		(keepout
			(tracks not_allowed)
			(vias allowed)
			(pads allowed)
			(copperpour not_allowed)
			(footprints allowed)
		)
		(placement
			(enabled no)
			(sheetname "")
		)
		(fill
			(thermal_gap 0.5)
			(thermal_bridge_width 0.5)
			(island_removal_mode 0)
		)
		(polygon
			(pts
				(xy 438.350914 -260.825234) (xy 439.849514 -260.825234) (xy 439.849514 -261.345172) (xy 438.350914 -261.345172)
			)
		)
	)
	(zone
		(layer "In2.Cu")
		(hatch none 0.5)
		(connect_pads
			(clearance 0)
		)
		(min_thickness 0.25)
		(keepout
			(tracks not_allowed)
			(vias allowed)
			(pads allowed)
			(copperpour not_allowed)
			(footprints allowed)
		)
		(placement
			(enabled no)
			(sheetname "")
		)
		(fill
			(thermal_gap 0.5)
			(thermal_bridge_width 0.5)
			(island_removal_mode 0)
		)
		(polygon
			(pts
				(xy 175.322738 -201.325226) (xy 176.821338 -201.325226) (xy 176.821338 -201.845164) (xy 175.322738 -201.845164)
			)
		)
	)
	(zone
		(layer "In2.Cu")
		(hatch none 0.5)
		(connect_pads
			(clearance 0)
		)
		(min_thickness 0.25)
		(keepout
			(tracks not_allowed)
			(vias allowed)
			(pads allowed)
			(copperpour not_allowed)
			(footprints allowed)
		)
		(placement
			(enabled no)
			(sheetname "")
		)
		(fill
			(thermal_gap 0.5)
			(thermal_bridge_width 0.5)
			(island_removal_mode 0)
		)
		(polygon
			(pts
				(xy 291.530786 -214.075264) (xy 293.029386 -214.075264) (xy 293.029386 -214.595202) (xy 291.530786 -214.595202)
			)
		)
	)
	(zone
		(layer "In2.Cu")
		(hatch none 0.5)
		(connect_pads
			(clearance 0)
		)
		(min_thickness 0.25)
		(keepout
			(tracks not_allowed)
			(vias allowed)
			(pads allowed)
			(copperpour not_allowed)
			(footprints allowed)
		)
		(placement
			(enabled no)
			(sheetname "")
		)
		(fill
			(thermal_gap 0.5)
			(thermal_bridge_width 0.5)
			(island_removal_mode 0)
		)
		(polygon
			(pts
				(xy 36.046664 -250.625102) (xy 37.545264 -250.625102) (xy 37.545264 -251.14504) (xy 36.046664 -251.14504)
			)
		)
	)
	(zone
		(layer "In2.Cu")
		(hatch none 0.5)
		(connect_pads
			(clearance 0)
		)
		(min_thickness 0.25)
		(keepout
			(tracks allowed)
			(vias allowed)
			(pads allowed)
			(copperpour allowed)
			(footprints allowed)
		)
		(placement
			(enabled no)
			(sheetname "")
		)
		(fill
			(thermal_gap 0.5)
			(thermal_bridge_width 0.5)
			(island_removal_mode 0)
		)
		(polygon
			(pts
				(xy 32.03321 -350.595692) (xy 32.03321 -349.973392) (xy 32.58439 -349.973392) (xy 32.58439 -350.595692)
			)
		)
	)
	(zone
		(layer "In2.Cu")
		(hatch none 0.5)
		(connect_pads
			(clearance 0)
		)
		(min_thickness 0.25)
		(keepout
			(tracks not_allowed)
			(vias allowed)
			(pads allowed)
			(copperpour not_allowed)
			(footprints allowed)
		)
		(placement
			(enabled no)
			(sheetname "")
		)
		(fill
			(thermal_gap 0.5)
			(thermal_bridge_width 0.5)
			(island_removal_mode 0)
		)
		(polygon
			(pts
				(xy 16.858742 -254.025146) (xy 18.357342 -254.025146) (xy 18.357342 -254.545084) (xy 16.858742 -254.545084)
			)
		)
	)
	(zone
		(layer "In2.Cu")
		(hatch none 0.5)
		(connect_pads
			(clearance 0)
		)
		(min_thickness 0.25)
		(keepout
			(tracks not_allowed)
			(vias allowed)
			(pads allowed)
			(copperpour not_allowed)
			(footprints allowed)
		)
		(placement
			(enabled no)
			(sheetname "")
		)
		(fill
			(thermal_gap 0.5)
			(thermal_bridge_width 0.5)
			(island_removal_mode 0)
		)
		(polygon
			(pts
				(xy 51.134772 -303.325276) (xy 52.633372 -303.325276) (xy 52.633372 -303.845214) (xy 51.134772 -303.845214)
			)
		)
	)
	(zone
		(layer "In2.Cu")
		(hatch none 0.5)
		(connect_pads
			(clearance 0)
		)
		(min_thickness 0.25)
		(keepout
			(tracks not_allowed)
			(vias allowed)
			(pads allowed)
			(copperpour not_allowed)
			(footprints allowed)
		)
		(placement
			(enabled no)
			(sheetname "")
		)
		(fill
			(thermal_gap 0.5)
			(thermal_bridge_width 0.5)
			(island_removal_mode 0)
		)
		(polygon
			(pts
				(xy 54.578758 -263.37514) (xy 56.077358 -263.37514) (xy 56.077358 -263.895078) (xy 54.578758 -263.895078)
			)
		)
	)
	(zone
		(layer "In2.Cu")
		(hatch none 0.5)
		(connect_pads
			(clearance 0)
		)
		(min_thickness 0.25)
		(keepout
			(tracks not_allowed)
			(vias allowed)
			(pads allowed)
			(copperpour not_allowed)
			(footprints allowed)
		)
		(placement
			(enabled no)
			(sheetname "")
		)
		(fill
			(thermal_gap 0.5)
			(thermal_bridge_width 0.5)
			(island_removal_mode 0)
		)
		(polygon
			(pts
				(xy 445.894968 -307.575204) (xy 447.393568 -307.575204) (xy 447.393568 -308.095142) (xy 445.894968 -308.095142)
			)
		)
	)
	(zone
		(layer "In2.Cu")
		(hatch none 0.5)
		(connect_pads
			(clearance 0)
		)
		(min_thickness 0.25)
		(keepout
			(tracks allowed)
			(vias allowed)
			(pads allowed)
			(copperpour allowed)
			(footprints allowed)
		)
		(placement
			(enabled no)
			(sheetname "")
		)
		(fill
			(thermal_gap 0.5)
			(thermal_bridge_width 0.5)
			(island_removal_mode 0)
		)
		(polygon
			(pts
				(xy 58.38063 -347.529912) (xy 58.38063 -348.479872) (xy 58.01233 -348.479872) (xy 58.01233 -347.529912)
			)
		)
	)
	(zone
		(layer "In2.Cu")
		(hatch none 0.5)
		(connect_pads
			(clearance 0)
		)
		(min_thickness 0.25)
		(keepout
			(tracks not_allowed)
			(vias allowed)
			(pads allowed)
			(copperpour not_allowed)
			(footprints allowed)
		)
		(placement
			(enabled no)
			(sheetname "")
		)
		(fill
			(thermal_gap 0.5)
			(thermal_bridge_width 0.5)
			(island_removal_mode 0)
		)
		(polygon
			(pts
				(xy 175.322738 -316.925198) (xy 176.821338 -316.925198) (xy 176.821338 -317.445136) (xy 175.322738 -317.445136)
			)
		)
	)
	(zone
		(layer "In2.Cu")
		(hatch none 0.5)
		(connect_pads
			(clearance 0)
		)
		(min_thickness 0.25)
		(keepout
			(tracks not_allowed)
			(vias allowed)
			(pads allowed)
			(copperpour not_allowed)
			(footprints allowed)
		)
		(placement
			(enabled no)
			(sheetname "")
		)
		(fill
			(thermal_gap 0.5)
			(thermal_bridge_width 0.5)
			(island_removal_mode 0)
		)
		(polygon
			(pts
				(xy 268.898878 -265.9253) (xy 270.397478 -265.9253) (xy 270.397478 -266.445238) (xy 268.898878 -266.445238)
			)
		)
	)
	(zone
		(layer "In2.Cu")
		(hatch none 0.5)
		(connect_pads
			(clearance 0)
		)
		(min_thickness 0.25)
		(keepout
			(tracks not_allowed)
			(vias allowed)
			(pads allowed)
			(copperpour not_allowed)
			(footprints allowed)
		)
		(placement
			(enabled no)
			(sheetname "")
		)
		(fill
			(thermal_gap 0.5)
			(thermal_bridge_width 0.5)
			(island_removal_mode 0)
		)
		(polygon
			(pts
				(xy 268.898878 -260.825234) (xy 270.397478 -260.825234) (xy 270.397478 -261.345172) (xy 268.898878 -261.345172)
			)
		)
	)
	(zone
		(layer "In2.Cu")
		(hatch none 0.5)
		(connect_pads
			(clearance 0)
		)
		(min_thickness 0.25)
		(keepout
			(tracks not_allowed)
			(vias allowed)
			(pads allowed)
			(copperpour not_allowed)
			(footprints allowed)
		)
		(placement
			(enabled no)
			(sheetname "")
		)
		(fill
			(thermal_gap 0.5)
			(thermal_bridge_width 0.5)
			(island_removal_mode 0)
		)
		(polygon
			(pts
				(xy 193.854578 -268.475206) (xy 195.353178 -268.475206) (xy 195.353178 -268.995144) (xy 193.854578 -268.995144)
			)
		)
	)
	(zone
		(layer "In2.Cu")
		(hatch none 0.5)
		(connect_pads
			(clearance 0)
		)
		(min_thickness 0.25)
		(keepout
			(tracks not_allowed)
			(vias allowed)
			(pads allowed)
			(copperpour not_allowed)
			(footprints allowed)
		)
		(placement
			(enabled no)
			(sheetname "")
		)
		(fill
			(thermal_gap 0.5)
			(thermal_bridge_width 0.5)
			(island_removal_mode 0)
		)
		(polygon
			(pts
				(xy 430.80686 -197.075298) (xy 432.30546 -197.075298) (xy 432.30546 -197.595236) (xy 430.80686 -197.595236)
			)
		)
	)
	(zone
		(layer "In2.Cu")
		(hatch none 0.5)
		(connect_pads
			(clearance 0)
		)
		(min_thickness 0.25)
		(keepout
			(tracks not_allowed)
			(vias allowed)
			(pads allowed)
			(copperpour not_allowed)
			(footprints allowed)
		)
		(placement
			(enabled no)
			(sheetname "")
		)
		(fill
			(thermal_gap 0.5)
			(thermal_bridge_width 0.5)
			(island_removal_mode 0)
		)
		(polygon
			(pts
				(xy 283.986732 -223.425258) (xy 285.485332 -223.425258) (xy 285.485332 -223.945196) (xy 283.986732 -223.945196)
			)
		)
	)
	(zone
		(layer "In2.Cu")
		(hatch none 0.5)
		(connect_pads
			(clearance 0)
		)
		(min_thickness 0.25)
		(keepout
			(tracks not_allowed)
			(vias allowed)
			(pads allowed)
			(copperpour not_allowed)
			(footprints allowed)
		)
		(placement
			(enabled no)
			(sheetname "")
		)
		(fill
			(thermal_gap 0.5)
			(thermal_bridge_width 0.5)
			(island_removal_mode 0)
		)
		(polygon
			(pts
				(xy 453.438768 -309.275226) (xy 454.937368 -309.275226) (xy 454.937368 -309.795164) (xy 453.438768 -309.795164)
			)
		)
	)
	(zone
		(layer "In2.Cu")
		(hatch none 0.5)
		(connect_pads
			(clearance 0)
		)
		(min_thickness 0.25)
		(keepout
			(tracks not_allowed)
			(vias allowed)
			(pads allowed)
			(copperpour not_allowed)
			(footprints allowed)
		)
		(placement
			(enabled no)
			(sheetname "")
		)
		(fill
			(thermal_gap 0.5)
			(thermal_bridge_width 0.5)
			(island_removal_mode 0)
		)
		(polygon
			(pts
				(xy 16.858742 -300.775116) (xy 18.357342 -300.775116) (xy 18.357342 -301.295054) (xy 16.858742 -301.295054)
			)
		)
	)
	(zone
		(layer "In2.Cu")
		(hatch none 0.5)
		(connect_pads
			(clearance 0)
		)
		(min_thickness 0.25)
		(keepout
			(tracks not_allowed)
			(vias allowed)
			(pads allowed)
			(copperpour not_allowed)
			(footprints allowed)
		)
		(placement
			(enabled no)
			(sheetname "")
		)
		(fill
			(thermal_gap 0.5)
			(thermal_bridge_width 0.5)
			(island_removal_mode 0)
		)
		(polygon
			(pts
				(xy 47.034704 -202.17511) (xy 48.533304 -202.17511) (xy 48.533304 -202.695048) (xy 47.034704 -202.695048)
			)
		)
	)
	(zone
		(layer "In2.Cu")
		(hatch none 0.5)
		(connect_pads
			(clearance 0)
		)
		(min_thickness 0.25)
		(keepout
			(tracks not_allowed)
			(vias allowed)
			(pads allowed)
			(copperpour not_allowed)
			(footprints allowed)
		)
		(placement
			(enabled no)
			(sheetname "")
		)
		(fill
			(thermal_gap 0.5)
			(thermal_bridge_width 0.5)
			(island_removal_mode 0)
		)
		(polygon
			(pts
				(xy 28.50261 -215.775286) (xy 30.00121 -215.775286) (xy 30.00121 -216.295224) (xy 28.50261 -216.295224)
			)
		)
	)
	(zone
		(layer "In2.Cu")
		(hatch none 0.5)
		(connect_pads
			(clearance 0)
		)
		(min_thickness 0.25)
		(keepout
			(tracks not_allowed)
			(vias allowed)
			(pads allowed)
			(copperpour not_allowed)
			(footprints allowed)
		)
		(placement
			(enabled no)
			(sheetname "")
		)
		(fill
			(thermal_gap 0.5)
			(thermal_bridge_width 0.5)
			(island_removal_mode 0)
		)
		(polygon
			(pts
				(xy 268.898878 -267.625322) (xy 270.397478 -267.625322) (xy 270.397478 -268.14526) (xy 268.898878 -268.14526)
			)
		)
	)
	(zone
		(layer "In2.Cu")
		(hatch none 0.5)
		(connect_pads
			(clearance 0)
		)
		(min_thickness 0.25)
		(keepout
			(tracks not_allowed)
			(vias allowed)
			(pads allowed)
			(copperpour not_allowed)
			(footprints allowed)
		)
		(placement
			(enabled no)
			(sheetname "")
		)
		(fill
			(thermal_gap 0.5)
			(thermal_bridge_width 0.5)
			(island_removal_mode 0)
		)
		(polygon
			(pts
				(xy 419.162738 -213.225126) (xy 420.661338 -213.225126) (xy 420.661338 -213.745064) (xy 419.162738 -213.745064)
			)
		)
	)
	(zone
		(layer "In2.Cu")
		(hatch none 0.5)
		(connect_pads
			(clearance 0)
		)
		(min_thickness 0.25)
		(keepout
			(tracks not_allowed)
			(vias allowed)
			(pads allowed)
			(copperpour not_allowed)
			(footprints allowed)
		)
		(placement
			(enabled no)
			(sheetname "")
		)
		(fill
			(thermal_gap 0.5)
			(thermal_bridge_width 0.5)
			(island_removal_mode 0)
		)
		(polygon
			(pts
				(xy 201.398632 -311.825132) (xy 202.897232 -311.825132) (xy 202.897232 -312.34507) (xy 201.398632 -312.34507)
			)
		)
	)
	(zone
		(layer "In2.Cu")
		(hatch none 0.5)
		(connect_pads
			(clearance 0)
		)
		(min_thickness 0.25)
		(keepout
			(tracks not_allowed)
			(vias allowed)
			(pads allowed)
			(copperpour not_allowed)
			(footprints allowed)
		)
		(placement
			(enabled no)
			(sheetname "")
		)
		(fill
			(thermal_gap 0.5)
			(thermal_bridge_width 0.5)
			(island_removal_mode 0)
		)
		(polygon
			(pts
				(xy 272.342864 -314.375292) (xy 273.841464 -314.375292) (xy 273.841464 -314.89523) (xy 272.342864 -314.89523)
			)
		)
	)
	(zone
		(layer "In2.Cu")
		(hatch none 0.5)
		(connect_pads
			(clearance 0)
		)
		(min_thickness 0.25)
		(keepout
			(tracks not_allowed)
			(vias allowed)
			(pads allowed)
			(copperpour not_allowed)
			(footprints allowed)
		)
		(placement
			(enabled no)
			(sheetname "")
		)
		(fill
			(thermal_gap 0.5)
			(thermal_bridge_width 0.5)
			(island_removal_mode 0)
		)
		(polygon
			(pts
				(xy 24.402542 -283.77515) (xy 25.901142 -283.77515) (xy 25.901142 -284.295088) (xy 24.402542 -284.295088)
			)
		)
	)
	(zone
		(layer "In2.Cu")
		(hatch none 0.5)
		(connect_pads
			(clearance 0)
		)
		(min_thickness 0.25)
		(keepout
			(tracks not_allowed)
			(vias allowed)
			(pads allowed)
			(copperpour not_allowed)
			(footprints allowed)
		)
		(placement
			(enabled no)
			(sheetname "")
		)
		(fill
			(thermal_gap 0.5)
			(thermal_bridge_width 0.5)
			(island_removal_mode 0)
		)
		(polygon
			(pts
				(arc
					(start 26.492708 -16.442436)
					(mid 26.515026 -16.496318)
					(end 26.568908 -16.518636)
				)
				(arc
					(start 26.764488 -16.518636)
					(mid 26.786364 -16.515504)
					(end 26.806398 -16.50619)
				)
				(arc
					(start 27.100022 -16.313658)
					(mid 27.141678 -16.301256)
					(end 27.183334 -16.313658)
				)
				(arc
					(start 27.478228 -16.50619)
					(mid 27.498152 -16.515426)
					(end 27.519884 -16.518636)
				)
				(arc
					(start 27.714448 -16.518636)
					(mid 27.76833 -16.496318)
					(end 27.790648 -16.442436)
				)
				(arc
					(start 27.790648 -15.756636)
					(mid 27.76833 -15.702754)
					(end 27.714448 -15.680436)
				)
				(arc
					(start 27.519884 -15.680436)
					(mid 27.49814 -15.683604)
					(end 27.478228 -15.692882)
				)
				(arc
					(start 27.182064 -15.885668)
					(mid 27.14038 -15.89789)
					(end 27.098752 -15.885414)
				)
				(arc
					(start 26.805128 -15.692882)
					(mid 26.785204 -15.683646)
					(end 26.763472 -15.680436)
				)
				(arc
					(start 26.568908 -15.680436)
					(mid 26.515026 -15.702754)
					(end 26.492708 -15.756636)
				)
			)
		)
	)
	(zone
		(layer "In2.Cu")
		(hatch none 0.5)
		(connect_pads
			(clearance 0)
		)
		(min_thickness 0.25)
		(keepout
			(tracks not_allowed)
			(vias allowed)
			(pads allowed)
			(copperpour not_allowed)
			(footprints allowed)
		)
		(placement
			(enabled no)
			(sheetname "")
		)
		(fill
			(thermal_gap 0.5)
			(thermal_bridge_width 0.5)
			(island_removal_mode 0)
		)
		(polygon
			(pts
				(xy 31.946596 -233.625136) (xy 33.445196 -233.625136) (xy 33.445196 -234.145074) (xy 31.946596 -234.145074)
			)
		)
	)
	(zone
		(layer "In2.Cu")
		(hatch none 0.5)
		(connect_pads
			(clearance 0)
		)
		(min_thickness 0.25)
		(keepout
			(tracks not_allowed)
			(vias allowed)
			(pads allowed)
			(copperpour not_allowed)
			(footprints allowed)
		)
		(placement
			(enabled no)
			(sheetname "")
		)
		(fill
			(thermal_gap 0.5)
			(thermal_bridge_width 0.5)
			(island_removal_mode 0)
		)
		(polygon
			(pts
				(xy 24.402542 -261.675118) (xy 25.901142 -261.675118) (xy 25.901142 -262.195056) (xy 24.402542 -262.195056)
			)
		)
	)
	(zone
		(layer "In2.Cu")
		(hatch none 0.5)
		(connect_pads
			(clearance 0)
		)
		(min_thickness 0.25)
		(keepout
			(tracks not_allowed)
			(vias allowed)
			(pads allowed)
			(copperpour not_allowed)
			(footprints allowed)
		)
		(placement
			(enabled no)
			(sheetname "")
		)
		(fill
			(thermal_gap 0.5)
			(thermal_bridge_width 0.5)
			(island_removal_mode 0)
		)
		(polygon
			(pts
				(xy 137.355326 -15.82674) (xy 138.336274 -15.82674) (xy 138.336274 -17.27454) (xy 137.355326 -17.27454)
			)
		)
	)
	(zone
		(layer "In2.Cu")
		(hatch none 0.5)
		(connect_pads
			(clearance 0)
		)
		(min_thickness 0.25)
		(keepout
			(tracks not_allowed)
			(vias allowed)
			(pads allowed)
			(copperpour not_allowed)
			(footprints allowed)
		)
		(placement
			(enabled no)
			(sheetname "")
		)
		(fill
			(thermal_gap 0.5)
			(thermal_bridge_width 0.5)
			(island_removal_mode 0)
		)
		(polygon
			(pts
				(xy 430.80686 -264.225278) (xy 432.30546 -264.225278) (xy 432.30546 -264.745216) (xy 430.80686 -264.745216)
			)
		)
	)
	(zone
		(layer "In2.Cu")
		(hatch none 0.5)
		(connect_pads
			(clearance 0)
		)
		(min_thickness 0.25)
		(keepout
			(tracks not_allowed)
			(vias allowed)
			(pads allowed)
			(copperpour not_allowed)
			(footprints allowed)
		)
		(placement
			(enabled no)
			(sheetname "")
		)
		(fill
			(thermal_gap 0.5)
			(thermal_bridge_width 0.5)
			(island_removal_mode 0)
		)
		(polygon
			(pts
				(xy 268.898878 -229.375208) (xy 270.397478 -229.375208) (xy 270.397478 -229.895146) (xy 268.898878 -229.895146)
			)
		)
	)
	(zone
		(layer "In2.Cu")
		(hatch none 0.5)
		(connect_pads
			(clearance 0)
		)
		(min_thickness 0.25)
		(keepout
			(tracks not_allowed)
			(vias allowed)
			(pads allowed)
			(copperpour not_allowed)
			(footprints allowed)
		)
		(placement
			(enabled no)
			(sheetname "")
		)
		(fill
			(thermal_gap 0.5)
			(thermal_bridge_width 0.5)
			(island_removal_mode 0)
		)
		(polygon
			(pts
				(xy 302.518826 -276.975316) (xy 304.017426 -276.975316) (xy 304.017426 -277.495254) (xy 302.518826 -277.495254)
			)
		)
	)
	(zone
		(layer "In2.Cu")
		(hatch none 0.5)
		(connect_pads
			(clearance 0)
		)
		(min_thickness 0.25)
		(keepout
			(tracks not_allowed)
			(vias allowed)
			(pads allowed)
			(copperpour not_allowed)
			(footprints allowed)
		)
		(placement
			(enabled no)
			(sheetname "")
		)
		(fill
			(thermal_gap 0.5)
			(thermal_bridge_width 0.5)
			(island_removal_mode 0)
		)
		(polygon
			(pts
				(xy 294.974772 -304.17516) (xy 296.473372 -304.17516) (xy 296.473372 -304.695098) (xy 294.974772 -304.695098)
			)
		)
	)
	(zone
		(layer "In2.Cu")
		(hatch none 0.5)
		(connect_pads
			(clearance 0)
		)
		(min_thickness 0.25)
		(keepout
			(tracks not_allowed)
			(vias allowed)
			(pads allowed)
			(copperpour not_allowed)
			(footprints allowed)
		)
		(placement
			(enabled no)
			(sheetname "")
		)
		(fill
			(thermal_gap 0.5)
			(thermal_bridge_width 0.5)
			(island_removal_mode 0)
		)
		(polygon
			(pts
				(xy 306.618894 -231.07523) (xy 308.117494 -231.07523) (xy 308.117494 -231.595168) (xy 306.618894 -231.595168)
			)
		)
	)
	(zone
		(layer "In2.Cu")
		(hatch none 0.5)
		(connect_pads
			(clearance 0)
		)
		(min_thickness 0.25)
		(keepout
			(tracks not_allowed)
			(vias allowed)
			(pads allowed)
			(copperpour not_allowed)
			(footprints allowed)
		)
		(placement
			(enabled no)
			(sheetname "")
		)
		(fill
			(thermal_gap 0.5)
			(thermal_bridge_width 0.5)
			(island_removal_mode 0)
		)
		(polygon
			(pts
				(xy 36.046664 -214.075264) (xy 37.545264 -214.075264) (xy 37.545264 -214.595202) (xy 36.046664 -214.595202)
			)
		)
	)
	(zone
		(layer "In2.Cu")
		(hatch none 0.5)
		(connect_pads
			(clearance 0)
		)
		(min_thickness 0.25)
		(keepout
			(tracks not_allowed)
			(vias allowed)
			(pads allowed)
			(copperpour not_allowed)
			(footprints allowed)
		)
		(placement
			(enabled no)
			(sheetname "")
		)
		(fill
			(thermal_gap 0.5)
			(thermal_bridge_width 0.5)
			(island_removal_mode 0)
		)
		(polygon
			(pts
				(xy 438.350914 -203.025248) (xy 439.849514 -203.025248) (xy 439.849514 -203.545186) (xy 438.350914 -203.545186)
			)
		)
	)
	(zone
		(layer "In2.Cu")
		(hatch none 0.5)
		(connect_pads
			(clearance 0)
		)
		(min_thickness 0.25)
		(keepout
			(tracks allowed)
			(vias allowed)
			(pads allowed)
			(copperpour allowed)
			(footprints allowed)
		)
		(placement
			(enabled no)
			(sheetname "")
		)
		(fill
			(thermal_gap 0.5)
			(thermal_bridge_width 0.5)
			(island_removal_mode 0)
		)
		(polygon
			(pts
				(xy 427.076616 -354.989384) (xy 427.076616 -354.367084) (xy 427.627796 -354.367084) (xy 427.627796 -354.989384)
			)
		)
	)
	(zone
		(layer "In2.Cu")
		(hatch none 0.5)
		(connect_pads
			(clearance 0)
		)
		(min_thickness 0.25)
		(keepout
			(tracks not_allowed)
			(vias allowed)
			(pads allowed)
			(copperpour not_allowed)
			(footprints allowed)
		)
		(placement
			(enabled no)
			(sheetname "")
		)
		(fill
			(thermal_gap 0.5)
			(thermal_bridge_width 0.5)
			(island_removal_mode 0)
		)
		(polygon
			(pts
				(xy 291.530786 -309.275226) (xy 293.029386 -309.275226) (xy 293.029386 -309.795164) (xy 291.530786 -309.795164)
			)
		)
	)
	(zone
		(layer "In2.Cu")
		(hatch none 0.5)
		(connect_pads
			(clearance 0)
		)
		(min_thickness 0.25)
		(keepout
			(tracks not_allowed)
			(vias allowed)
			(pads allowed)
			(copperpour not_allowed)
			(footprints allowed)
		)
		(placement
			(enabled no)
			(sheetname "")
		)
		(fill
			(thermal_gap 0.5)
			(thermal_bridge_width 0.5)
			(island_removal_mode 0)
		)
		(polygon
			(pts
				(xy 54.578758 -286.32531) (xy 56.077358 -286.32531) (xy 56.077358 -286.845248) (xy 54.578758 -286.845248)
			)
		)
	)
	(zone
		(layer "In2.Cu")
		(hatch none 0.5)
		(connect_pads
			(clearance 0)
		)
		(min_thickness 0.25)
		(keepout
			(tracks not_allowed)
			(vias allowed)
			(pads allowed)
			(copperpour not_allowed)
			(footprints allowed)
		)
		(placement
			(enabled no)
			(sheetname "")
		)
		(fill
			(thermal_gap 0.5)
			(thermal_bridge_width 0.5)
			(island_removal_mode 0)
		)
		(polygon
			(pts
				(xy 186.310778 -306.72532) (xy 187.809378 -306.72532) (xy 187.809378 -307.245258) (xy 186.310778 -307.245258)
			)
		)
	)
	(zone
		(layer "In2.Cu")
		(hatch none 0.5)
		(connect_pads
			(clearance 0)
		)
		(min_thickness 0.25)
		(keepout
			(tracks not_allowed)
			(vias allowed)
			(pads allowed)
			(copperpour not_allowed)
			(footprints allowed)
		)
		(placement
			(enabled no)
			(sheetname "")
		)
		(fill
			(thermal_gap 0.5)
			(thermal_bridge_width 0.5)
			(island_removal_mode 0)
		)
		(polygon
			(pts
				(xy 302.518826 -313.525154) (xy 304.017426 -313.525154) (xy 304.017426 -314.045092) (xy 302.518826 -314.045092)
			)
		)
	)
	(zone
		(layer "In2.Cu")
		(hatch none 0.5)
		(connect_pads
			(clearance 0)
		)
		(min_thickness 0.25)
		(keepout
			(tracks not_allowed)
			(vias allowed)
			(pads allowed)
			(copperpour not_allowed)
			(footprints allowed)
		)
		(placement
			(enabled no)
			(sheetname "")
		)
		(fill
			(thermal_gap 0.5)
			(thermal_bridge_width 0.5)
			(island_removal_mode 0)
		)
		(polygon
			(pts
				(xy 20.95881 -288.875216) (xy 22.45741 -288.875216) (xy 22.45741 -289.395154) (xy 20.95881 -289.395154)
			)
		)
	)
	(zone
		(layer "In2.Cu")
		(hatch none 0.5)
		(connect_pads
			(clearance 0)
		)
		(min_thickness 0.25)
		(keepout
			(tracks not_allowed)
			(vias allowed)
			(pads allowed)
			(copperpour not_allowed)
			(footprints allowed)
		)
		(placement
			(enabled no)
			(sheetname "")
		)
		(fill
			(thermal_gap 0.5)
			(thermal_bridge_width 0.5)
			(island_removal_mode 0)
		)
		(polygon
			(pts
				(xy 28.50261 -250.625102) (xy 30.00121 -250.625102) (xy 30.00121 -251.14504) (xy 28.50261 -251.14504)
			)
		)
	)
	(zone
		(layer "In2.Cu")
		(hatch none 0.5)
		(connect_pads
			(clearance 0)
		)
		(min_thickness 0.25)
		(keepout
			(tracks not_allowed)
			(vias allowed)
			(pads allowed)
			(copperpour not_allowed)
			(footprints allowed)
		)
		(placement
			(enabled no)
			(sheetname "")
		)
		(fill
			(thermal_gap 0.5)
			(thermal_bridge_width 0.5)
			(island_removal_mode 0)
		)
		(polygon
			(pts
				(xy 186.310778 -285.475172) (xy 187.809378 -285.475172) (xy 187.809378 -285.99511) (xy 186.310778 -285.99511)
			)
		)
	)
	(zone
		(layer "In2.Cu")
		(hatch none 0.5)
		(connect_pads
			(clearance 0)
		)
		(min_thickness 0.25)
		(keepout
			(tracks not_allowed)
			(vias allowed)
			(pads allowed)
			(copperpour not_allowed)
			(footprints allowed)
		)
		(placement
			(enabled no)
			(sheetname "")
		)
		(fill
			(thermal_gap 0.5)
			(thermal_bridge_width 0.5)
			(island_removal_mode 0)
		)
		(polygon
			(pts
				(xy 268.898878 -221.725236) (xy 270.397478 -221.725236) (xy 270.397478 -222.245174) (xy 268.898878 -222.245174)
			)
		)
	)
	(zone
		(layer "In2.Cu")
		(hatch none 0.5)
		(connect_pads
			(clearance 0)
		)
		(min_thickness 0.25)
		(keepout
			(tracks not_allowed)
			(vias allowed)
			(pads allowed)
			(copperpour not_allowed)
			(footprints allowed)
		)
		(placement
			(enabled no)
			(sheetname "")
		)
		(fill
			(thermal_gap 0.5)
			(thermal_bridge_width 0.5)
			(island_removal_mode 0)
		)
		(polygon
			(pts
				(xy 411.618684 -300.775116) (xy 413.117284 -300.775116) (xy 413.117284 -301.295054) (xy 411.618684 -301.295054)
			)
		)
	)
	(zone
		(layer "In2.Cu")
		(hatch none 0.5)
		(connect_pads
			(clearance 0)
		)
		(min_thickness 0.25)
		(keepout
			(tracks not_allowed)
			(vias allowed)
			(pads allowed)
			(copperpour not_allowed)
			(footprints allowed)
		)
		(placement
			(enabled no)
			(sheetname "")
		)
		(fill
			(thermal_gap 0.5)
			(thermal_bridge_width 0.5)
			(island_removal_mode 0)
		)
		(polygon
			(pts
				(xy 453.438768 -299.925232) (xy 454.937368 -299.925232) (xy 454.937368 -300.44517) (xy 453.438768 -300.44517)
			)
		)
	)
	(zone
		(layer "In2.Cu")
		(hatch none 0.5)
		(connect_pads
			(clearance 0)
		)
		(min_thickness 0.25)
		(keepout
			(tracks not_allowed)
			(vias allowed)
			(pads allowed)
			(copperpour not_allowed)
			(footprints allowed)
		)
		(placement
			(enabled no)
			(sheetname "")
		)
		(fill
			(thermal_gap 0.5)
			(thermal_bridge_width 0.5)
			(island_removal_mode 0)
		)
		(polygon
			(pts
				(xy 276.442932 -226.825302) (xy 277.941532 -226.825302) (xy 277.941532 -227.34524) (xy 276.442932 -227.34524)
			)
		)
	)
	(zone
		(layer "In2.Cu")
		(hatch none 0.5)
		(connect_pads
			(clearance 0)
		)
		(min_thickness 0.25)
		(keepout
			(tracks not_allowed)
			(vias allowed)
			(pads allowed)
			(copperpour not_allowed)
			(footprints allowed)
		)
		(placement
			(enabled no)
			(sheetname "")
		)
		(fill
			(thermal_gap 0.5)
			(thermal_bridge_width 0.5)
			(island_removal_mode 0)
		)
		(polygon
			(pts
				(xy 449.3387 -224.275142) (xy 450.8373 -224.275142) (xy 450.8373 -224.79508) (xy 449.3387 -224.79508)
			)
		)
	)
	(zone
		(layer "In2.Cu")
		(hatch none 0.5)
		(connect_pads
			(clearance 0)
		)
		(min_thickness 0.25)
		(keepout
			(tracks not_allowed)
			(vias allowed)
			(pads allowed)
			(copperpour not_allowed)
			(footprints allowed)
		)
		(placement
			(enabled no)
			(sheetname "")
		)
		(fill
			(thermal_gap 0.5)
			(thermal_bridge_width 0.5)
			(island_removal_mode 0)
		)
		(polygon
			(pts
				(xy 20.95881 -204.72527) (xy 22.45741 -204.72527) (xy 22.45741 -205.245208) (xy 20.95881 -205.245208)
			)
		)
	)
	(zone
		(layer "In2.Cu")
		(hatch none 0.5)
		(connect_pads
			(clearance 0)
		)
		(min_thickness 0.25)
		(keepout
			(tracks not_allowed)
			(vias allowed)
			(pads allowed)
			(copperpour not_allowed)
			(footprints allowed)
		)
		(placement
			(enabled no)
			(sheetname "")
		)
		(fill
			(thermal_gap 0.5)
			(thermal_bridge_width 0.5)
			(island_removal_mode 0)
		)
		(polygon
			(pts
				(xy 430.80686 -234.475274) (xy 432.30546 -234.475274) (xy 432.30546 -234.995212) (xy 430.80686 -234.995212)
			)
		)
	)
	(zone
		(layer "In2.Cu")
		(hatch none 0.5)
		(connect_pads
			(clearance 0)
		)
		(min_thickness 0.25)
		(keepout
			(tracks not_allowed)
			(vias allowed)
			(pads allowed)
			(copperpour not_allowed)
			(footprints allowed)
		)
		(placement
			(enabled no)
			(sheetname "")
		)
		(fill
			(thermal_gap 0.5)
			(thermal_bridge_width 0.5)
			(island_removal_mode 0)
		)
		(polygon
			(pts
				(xy 201.398632 -201.325226) (xy 202.897232 -201.325226) (xy 202.897232 -201.845164) (xy 201.398632 -201.845164)
			)
		)
	)
	(zone
		(layer "In2.Cu")
		(hatch none 0.5)
		(connect_pads
			(clearance 0)
		)
		(min_thickness 0.25)
		(keepout
			(tracks not_allowed)
			(vias allowed)
			(pads allowed)
			(copperpour not_allowed)
			(footprints allowed)
		)
		(placement
			(enabled no)
			(sheetname "")
		)
		(fill
			(thermal_gap 0.5)
			(thermal_bridge_width 0.5)
			(island_removal_mode 0)
		)
		(polygon
			(pts
				(xy 426.706792 -302.475138) (xy 428.205392 -302.475138) (xy 428.205392 -302.995076) (xy 426.706792 -302.995076)
			)
		)
	)
	(zone
		(layer "In2.Cu")
		(hatch none 0.5)
		(connect_pads
			(clearance 0)
		)
		(min_thickness 0.25)
		(keepout
			(tracks not_allowed)
			(vias allowed)
			(pads allowed)
			(copperpour not_allowed)
			(footprints allowed)
		)
		(placement
			(enabled no)
			(sheetname "")
		)
		(fill
			(thermal_gap 0.5)
			(thermal_bridge_width 0.5)
			(island_removal_mode 0)
		)
		(polygon
			(pts
				(xy 430.80686 -204.72527) (xy 432.30546 -204.72527) (xy 432.30546 -205.245208) (xy 430.80686 -205.245208)
			)
		)
	)
	(zone
		(layer "In2.Cu")
		(hatch none 0.5)
		(connect_pads
			(clearance 0)
		)
		(min_thickness 0.25)
		(keepout
			(tracks not_allowed)
			(vias allowed)
			(pads allowed)
			(copperpour not_allowed)
			(footprints allowed)
		)
		(placement
			(enabled no)
			(sheetname "")
		)
		(fill
			(thermal_gap 0.5)
			(thermal_bridge_width 0.5)
			(island_removal_mode 0)
		)
		(polygon
			(pts
				(xy 24.402542 -305.025298) (xy 25.901142 -305.025298) (xy 25.901142 -305.545236) (xy 24.402542 -305.545236)
			)
		)
	)
	(zone
		(layer "In2.Cu")
		(hatch none 0.5)
		(connect_pads
			(clearance 0)
		)
		(min_thickness 0.25)
		(keepout
			(tracks not_allowed)
			(vias allowed)
			(pads allowed)
			(copperpour not_allowed)
			(footprints allowed)
		)
		(placement
			(enabled no)
			(sheetname "")
		)
		(fill
			(thermal_gap 0.5)
			(thermal_bridge_width 0.5)
			(island_removal_mode 0)
		)
		(polygon
			(pts
				(xy 279.886664 -249.775218) (xy 281.385264 -249.775218) (xy 281.385264 -250.295156) (xy 279.886664 -250.295156)
			)
		)
	)
	(zone
		(layer "In2.Cu")
		(hatch none 0.5)
		(connect_pads
			(clearance 0)
		)
		(min_thickness 0.25)
		(keepout
			(tracks not_allowed)
			(vias allowed)
			(pads allowed)
			(copperpour not_allowed)
			(footprints allowed)
		)
		(placement
			(enabled no)
			(sheetname "")
		)
		(fill
			(thermal_gap 0.5)
			(thermal_bridge_width 0.5)
			(island_removal_mode 0)
		)
		(polygon
			(pts
				(xy 36.046664 -292.27526) (xy 37.545264 -292.27526) (xy 37.545264 -292.795198) (xy 36.046664 -292.795198)
			)
		)
	)
	(zone
		(layer "In2.Cu")
		(hatch none 0.5)
		(connect_pads
			(clearance 0)
		)
		(min_thickness 0.25)
		(keepout
			(tracks not_allowed)
			(vias allowed)
			(pads allowed)
			(copperpour not_allowed)
			(footprints allowed)
		)
		(placement
			(enabled no)
			(sheetname "")
		)
		(fill
			(thermal_gap 0.5)
			(thermal_bridge_width 0.5)
			(island_removal_mode 0)
		)
		(polygon
			(pts
				(xy 426.706792 -201.325226) (xy 428.205392 -201.325226) (xy 428.205392 -201.845164) (xy 426.706792 -201.845164)
			)
		)
	)
	(zone
		(layer "In2.Cu")
		(hatch none 0.5)
		(connect_pads
			(clearance 0)
		)
		(min_thickness 0.25)
		(keepout
			(tracks not_allowed)
			(vias allowed)
			(pads allowed)
			(copperpour not_allowed)
			(footprints allowed)
		)
		(placement
			(enabled no)
			(sheetname "")
		)
		(fill
			(thermal_gap 0.5)
			(thermal_bridge_width 0.5)
			(island_removal_mode 0)
		)
		(polygon
			(pts
				(xy 287.430718 -203.875132) (xy 288.929318 -203.875132) (xy 288.929318 -204.39507) (xy 287.430718 -204.39507)
			)
		)
	)
	(zone
		(layer "In2.Cu")
		(hatch none 0.5)
		(connect_pads
			(clearance 0)
		)
		(min_thickness 0.25)
		(keepout
			(tracks not_allowed)
			(vias allowed)
			(pads allowed)
			(copperpour not_allowed)
			(footprints allowed)
		)
		(placement
			(enabled no)
			(sheetname "")
		)
		(fill
			(thermal_gap 0.5)
			(thermal_bridge_width 0.5)
			(island_removal_mode 0)
		)
		(polygon
			(pts
				(xy 423.262806 -271.87525) (xy 424.761406 -271.87525) (xy 424.761406 -272.395188) (xy 423.262806 -272.395188)
			)
		)
	)
	(zone
		(layer "In2.Cu")
		(hatch none 0.5)
		(connect_pads
			(clearance 0)
		)
		(min_thickness 0.25)
		(keepout
			(tracks not_allowed)
			(vias allowed)
			(pads allowed)
			(copperpour not_allowed)
			(footprints allowed)
		)
		(placement
			(enabled no)
			(sheetname "")
		)
		(fill
			(thermal_gap 0.5)
			(thermal_bridge_width 0.5)
			(island_removal_mode 0)
		)
		(polygon
			(pts
				(xy 272.342864 -263.37514) (xy 273.841464 -263.37514) (xy 273.841464 -263.895078) (xy 272.342864 -263.895078)
			)
		)
	)
	(zone
		(layer "In2.Cu")
		(hatch none 0.5)
		(connect_pads
			(clearance 0)
		)
		(min_thickness 0.25)
		(keepout
			(tracks not_allowed)
			(vias allowed)
			(pads allowed)
			(copperpour not_allowed)
			(footprints allowed)
		)
		(placement
			(enabled no)
			(sheetname "")
		)
		(fill
			(thermal_gap 0.5)
			(thermal_bridge_width 0.5)
			(island_removal_mode 0)
		)
		(polygon
			(pts
				(xy 186.310778 -230.225346) (xy 187.809378 -230.225346) (xy 187.809378 -230.745284) (xy 186.310778 -230.745284)
			)
		)
	)
	(zone
		(layer "In2.Cu")
		(hatch none 0.5)
		(connect_pads
			(clearance 0)
		)
		(min_thickness 0.25)
		(keepout
			(tracks not_allowed)
			(vias allowed)
			(pads allowed)
			(copperpour not_allowed)
			(footprints allowed)
		)
		(placement
			(enabled no)
			(sheetname "")
		)
		(fill
			(thermal_gap 0.5)
			(thermal_bridge_width 0.5)
			(island_removal_mode 0)
		)
		(polygon
			(pts
				(xy 51.134772 -265.9253) (xy 52.633372 -265.9253) (xy 52.633372 -266.445238) (xy 51.134772 -266.445238)
			)
		)
	)
	(zone
		(layer "In2.Cu")
		(hatch none 0.5)
		(connect_pads
			(clearance 0)
		)
		(min_thickness 0.25)
		(keepout
			(tracks not_allowed)
			(vias allowed)
			(pads allowed)
			(copperpour not_allowed)
			(footprints allowed)
		)
		(placement
			(enabled no)
			(sheetname "")
		)
		(fill
			(thermal_gap 0.5)
			(thermal_bridge_width 0.5)
			(island_removal_mode 0)
		)
		(polygon
			(pts
				(xy 419.162738 -207.275176) (xy 420.661338 -207.275176) (xy 420.661338 -207.795114) (xy 419.162738 -207.795114)
			)
		)
	)
	(zone
		(layer "In2.Cu")
		(hatch none 0.5)
		(connect_pads
			(clearance 0)
		)
		(min_thickness 0.25)
		(keepout
			(tracks not_allowed)
			(vias allowed)
			(pads allowed)
			(copperpour not_allowed)
			(footprints allowed)
		)
		(placement
			(enabled no)
			(sheetname "")
		)
		(fill
			(thermal_gap 0.5)
			(thermal_bridge_width 0.5)
			(island_removal_mode 0)
		)
		(polygon
			(pts
				(xy 419.162738 -261.675118) (xy 420.661338 -261.675118) (xy 420.661338 -262.195056) (xy 419.162738 -262.195056)
			)
		)
	)
	(zone
		(layer "In2.Cu")
		(hatch none 0.5)
		(connect_pads
			(clearance 0)
		)
		(min_thickness 0.25)
		(keepout
			(tracks not_allowed)
			(vias allowed)
			(pads allowed)
			(copperpour not_allowed)
			(footprints allowed)
		)
		(placement
			(enabled no)
			(sheetname "")
		)
		(fill
			(thermal_gap 0.5)
			(thermal_bridge_width 0.5)
			(island_removal_mode 0)
		)
		(polygon
			(pts
				(arc
					(start 56.561482 -11.91768)
					(mid 56.539164 -11.971562)
					(end 56.485282 -11.99388)
				)
				(arc
					(start 55.448708 -11.99388)
					(mid 55.394826 -11.971562)
					(end 55.372508 -11.91768)
				)
				(arc
					(start 55.372508 -10.51814)
					(mid 55.394826 -10.464258)
					(end 55.448708 -10.44194)
				)
				(arc
					(start 56.485282 -10.44194)
					(mid 56.539164 -10.464258)
					(end 56.561482 -10.51814)
				)
			)
		)
	)
	(zone
		(layer "In2.Cu")
		(hatch none 0.5)
		(connect_pads
			(clearance 0)
		)
		(min_thickness 0.25)
		(keepout
			(tracks not_allowed)
			(vias allowed)
			(pads allowed)
			(copperpour not_allowed)
			(footprints allowed)
		)
		(placement
			(enabled no)
			(sheetname "")
		)
		(fill
			(thermal_gap 0.5)
			(thermal_bridge_width 0.5)
			(island_removal_mode 0)
		)
		(polygon
			(pts
				(xy 441.7949 -224.275142) (xy 443.2935 -224.275142) (xy 443.2935 -224.79508) (xy 441.7949 -224.79508)
			)
		)
	)
	(zone
		(layer "In2.Cu")
		(hatch none 0.5)
		(connect_pads
			(clearance 0)
		)
		(min_thickness 0.25)
		(keepout
			(tracks not_allowed)
			(vias allowed)
			(pads allowed)
			(copperpour not_allowed)
			(footprints allowed)
		)
		(placement
			(enabled no)
			(sheetname "")
		)
		(fill
			(thermal_gap 0.5)
			(thermal_bridge_width 0.5)
			(island_removal_mode 0)
		)
		(polygon
			(pts
				(xy 411.618684 -313.525154) (xy 413.117284 -313.525154) (xy 413.117284 -314.045092) (xy 411.618684 -314.045092)
			)
		)
	)
	(zone
		(layer "In2.Cu")
		(hatch none 0.5)
		(connect_pads
			(clearance 0)
		)
		(min_thickness 0.25)
		(keepout
			(tracks not_allowed)
			(vias allowed)
			(pads allowed)
			(copperpour not_allowed)
			(footprints allowed)
		)
		(placement
			(enabled no)
			(sheetname "")
		)
		(fill
			(thermal_gap 0.5)
			(thermal_bridge_width 0.5)
			(island_removal_mode 0)
		)
		(polygon
			(pts
				(xy 167.778684 -288.875216) (xy 169.277284 -288.875216) (xy 169.277284 -289.395154) (xy 167.778684 -289.395154)
			)
		)
	)
	(zone
		(layer "In2.Cu")
		(hatch none 0.5)
		(connect_pads
			(clearance 0)
		)
		(min_thickness 0.25)
		(keepout
			(tracks not_allowed)
			(vias allowed)
			(pads allowed)
			(copperpour not_allowed)
			(footprints allowed)
		)
		(placement
			(enabled no)
			(sheetname "")
		)
		(fill
			(thermal_gap 0.5)
			(thermal_bridge_width 0.5)
			(island_removal_mode 0)
		)
		(polygon
			(pts
				(xy 167.778684 -248.925334) (xy 169.277284 -248.925334) (xy 169.277284 -249.445272) (xy 167.778684 -249.445272)
			)
		)
	)
	(zone
		(layer "In2.Cu")
		(hatch none 0.5)
		(connect_pads
			(clearance 0)
		)
		(min_thickness 0.25)
		(keepout
			(tracks not_allowed)
			(vias allowed)
			(pads allowed)
			(copperpour not_allowed)
			(footprints allowed)
		)
		(placement
			(enabled no)
			(sheetname "")
		)
		(fill
			(thermal_gap 0.5)
			(thermal_bridge_width 0.5)
			(island_removal_mode 0)
		)
		(polygon
			(pts
				(xy 287.430718 -308.425342) (xy 288.929318 -308.425342) (xy 288.929318 -308.94528) (xy 287.430718 -308.94528)
			)
		)
	)
	(zone
		(layer "In2.Cu")
		(hatch none 0.5)
		(connect_pads
			(clearance 0)
		)
		(min_thickness 0.25)
		(keepout
			(tracks not_allowed)
			(vias allowed)
			(pads allowed)
			(copperpour not_allowed)
			(footprints allowed)
		)
		(placement
			(enabled no)
			(sheetname "")
		)
		(fill
			(thermal_gap 0.5)
			(thermal_bridge_width 0.5)
			(island_removal_mode 0)
		)
		(polygon
			(pts
				(xy 24.402542 -235.325158) (xy 25.901142 -235.325158) (xy 25.901142 -235.845096) (xy 24.402542 -235.845096)
			)
		)
	)
	(zone
		(layer "In2.Cu")
		(hatch none 0.5)
		(connect_pads
			(clearance 0)
		)
		(min_thickness 0.25)
		(keepout
			(tracks not_allowed)
			(vias allowed)
			(pads allowed)
			(copperpour not_allowed)
			(footprints allowed)
		)
		(placement
			(enabled no)
			(sheetname "")
		)
		(fill
			(thermal_gap 0.5)
			(thermal_bridge_width 0.5)
			(island_removal_mode 0)
		)
		(polygon
			(pts
				(xy 272.342864 -207.275176) (xy 273.841464 -207.275176) (xy 273.841464 -207.795114) (xy 272.342864 -207.795114)
			)
		)
	)
	(zone
		(layer "In2.Cu")
		(hatch none 0.5)
		(connect_pads
			(clearance 0)
		)
		(min_thickness 0.25)
		(keepout
			(tracks not_allowed)
			(vias allowed)
			(pads allowed)
			(copperpour not_allowed)
			(footprints allowed)
		)
		(placement
			(enabled no)
			(sheetname "")
		)
		(fill
			(thermal_gap 0.5)
			(thermal_bridge_width 0.5)
			(island_removal_mode 0)
		)
		(polygon
			(pts
				(xy 47.034704 -263.37514) (xy 48.533304 -263.37514) (xy 48.533304 -263.895078) (xy 47.034704 -263.895078)
			)
		)
	)
	(zone
		(layer "In2.Cu")
		(hatch none 0.5)
		(connect_pads
			(clearance 0)
		)
		(min_thickness 0.25)
		(keepout
			(tracks not_allowed)
			(vias allowed)
			(pads allowed)
			(copperpour not_allowed)
			(footprints allowed)
		)
		(placement
			(enabled no)
			(sheetname "")
		)
		(fill
			(thermal_gap 0.5)
			(thermal_bridge_width 0.5)
			(island_removal_mode 0)
		)
		(polygon
			(pts
				(xy 129.504694 -33.584388) (xy 129.504694 -34.162238) (xy 128.183894 -34.162238) (xy 128.183894 -33.584388)
			)
		)
	)
	(zone
		(layer "In2.Cu")
		(hatch none 0.5)
		(connect_pads
			(clearance 0)
		)
		(min_thickness 0.25)
		(keepout
			(tracks not_allowed)
			(vias allowed)
			(pads allowed)
			(copperpour not_allowed)
			(footprints allowed)
		)
		(placement
			(enabled no)
			(sheetname "")
		)
		(fill
			(thermal_gap 0.5)
			(thermal_bridge_width 0.5)
			(island_removal_mode 0)
		)
		(polygon
			(pts
				(xy 163.678616 -230.225346) (xy 165.177216 -230.225346) (xy 165.177216 -230.745284) (xy 163.678616 -230.745284)
			)
		)
	)
	(zone
		(layer "In2.Cu")
		(hatch none 0.5)
		(connect_pads
			(clearance 0)
		)
		(min_thickness 0.25)
		(keepout
			(tracks not_allowed)
			(vias allowed)
			(pads allowed)
			(copperpour not_allowed)
			(footprints allowed)
		)
		(placement
			(enabled no)
			(sheetname "")
		)
		(fill
			(thermal_gap 0.5)
			(thermal_bridge_width 0.5)
			(island_removal_mode 0)
		)
		(polygon
			(pts
				(xy 197.954646 -271.87525) (xy 199.453246 -271.87525) (xy 199.453246 -272.395188) (xy 197.954646 -272.395188)
			)
		)
	)
	(zone
		(layer "In2.Cu")
		(hatch none 0.5)
		(connect_pads
			(clearance 0)
		)
		(min_thickness 0.25)
		(keepout
			(tracks not_allowed)
			(vias allowed)
			(pads allowed)
			(copperpour not_allowed)
			(footprints allowed)
		)
		(placement
			(enabled no)
			(sheetname "")
		)
		(fill
			(thermal_gap 0.5)
			(thermal_bridge_width 0.5)
			(island_removal_mode 0)
		)
		(polygon
			(pts
				(xy 135.555228 -12.876784) (xy 136.536176 -12.876784) (xy 136.536176 -14.324584) (xy 135.555228 -14.324584)
			)
		)
	)
	(zone
		(layer "In2.Cu")
		(hatch none 0.5)
		(connect_pads
			(clearance 0)
		)
		(min_thickness 0.25)
		(keepout
			(tracks not_allowed)
			(vias allowed)
			(pads allowed)
			(copperpour not_allowed)
			(footprints allowed)
		)
		(placement
			(enabled no)
			(sheetname "")
		)
		(fill
			(thermal_gap 0.5)
			(thermal_bridge_width 0.5)
			(island_removal_mode 0)
		)
		(polygon
			(pts
				(xy 24.402542 -299.075348) (xy 25.901142 -299.075348) (xy 25.901142 -299.595286) (xy 24.402542 -299.595286)
			)
		)
	)
	(zone
		(layer "In2.Cu")
		(hatch none 0.5)
		(connect_pads
			(clearance 0)
		)
		(min_thickness 0.25)
		(keepout
			(tracks not_allowed)
			(vias allowed)
			(pads allowed)
			(copperpour not_allowed)
			(footprints allowed)
		)
		(placement
			(enabled no)
			(sheetname "")
		)
		(fill
			(thermal_gap 0.5)
			(thermal_bridge_width 0.5)
			(island_removal_mode 0)
		)
		(polygon
			(pts
				(xy 24.402542 -233.625136) (xy 25.901142 -233.625136) (xy 25.901142 -234.145074) (xy 24.402542 -234.145074)
			)
		)
	)
	(zone
		(layer "In2.Cu")
		(hatch none 0.5)
		(connect_pads
			(clearance 0)
		)
		(min_thickness 0.25)
		(keepout
			(tracks not_allowed)
			(vias allowed)
			(pads allowed)
			(copperpour not_allowed)
			(footprints allowed)
		)
		(placement
			(enabled no)
			(sheetname "")
		)
		(fill
			(thermal_gap 0.5)
			(thermal_bridge_width 0.5)
			(island_removal_mode 0)
		)
		(polygon
			(pts
				(xy 163.678616 -227.675186) (xy 165.177216 -227.675186) (xy 165.177216 -228.195124) (xy 163.678616 -228.195124)
			)
		)
	)
	(zone
		(layer "In2.Cu")
		(hatch none 0.5)
		(connect_pads
			(clearance 0)
		)
		(min_thickness 0.25)
		(keepout
			(tracks not_allowed)
			(vias allowed)
			(pads allowed)
			(copperpour not_allowed)
			(footprints allowed)
		)
		(placement
			(enabled no)
			(sheetname "")
		)
		(fill
			(thermal_gap 0.5)
			(thermal_bridge_width 0.5)
			(island_removal_mode 0)
		)
		(polygon
			(pts
				(xy 283.986732 -279.525222) (xy 285.485332 -279.525222) (xy 285.485332 -280.04516) (xy 283.986732 -280.04516)
			)
		)
	)
	(zone
		(layer "In2.Cu")
		(hatch none 0.5)
		(connect_pads
			(clearance 0)
		)
		(min_thickness 0.25)
		(keepout
			(tracks not_allowed)
			(vias allowed)
			(pads allowed)
			(copperpour not_allowed)
			(footprints allowed)
		)
		(placement
			(enabled no)
			(sheetname "")
		)
		(fill
			(thermal_gap 0.5)
			(thermal_bridge_width 0.5)
			(island_removal_mode 0)
		)
		(polygon
			(pts
				(arc
					(start 46.356524 -17.966436)
					(mid 46.378842 -18.020318)
					(end 46.432724 -18.042636)
				)
				(arc
					(start 46.628304 -18.042636)
					(mid 46.65018 -18.039504)
					(end 46.670214 -18.03019)
				)
				(arc
					(start 46.963838 -17.837658)
					(mid 47.005494 -17.825256)
					(end 47.04715 -17.837658)
				)
				(arc
					(start 47.342044 -18.03019)
					(mid 47.361968 -18.039426)
					(end 47.3837 -18.042636)
				)
				(arc
					(start 47.578264 -18.042636)
					(mid 47.632146 -18.020318)
					(end 47.654464 -17.966436)
				)
				(arc
					(start 47.654464 -17.280636)
					(mid 47.632146 -17.226754)
					(end 47.578264 -17.204436)
				)
				(arc
					(start 47.3837 -17.204436)
					(mid 47.361956 -17.207604)
					(end 47.342044 -17.216882)
				)
				(arc
					(start 47.04588 -17.409668)
					(mid 47.004196 -17.42189)
					(end 46.962568 -17.409414)
				)
				(arc
					(start 46.668944 -17.216882)
					(mid 46.64902 -17.207646)
					(end 46.627288 -17.204436)
				)
				(arc
					(start 46.432724 -17.204436)
					(mid 46.378842 -17.226754)
					(end 46.356524 -17.280636)
				)
			)
		)
	)
	(zone
		(layer "In2.Cu")
		(hatch none 0.5)
		(connect_pads
			(clearance 0)
		)
		(min_thickness 0.25)
		(keepout
			(tracks not_allowed)
			(vias allowed)
			(pads allowed)
			(copperpour not_allowed)
			(footprints allowed)
		)
		(placement
			(enabled no)
			(sheetname "")
		)
		(fill
			(thermal_gap 0.5)
			(thermal_bridge_width 0.5)
			(island_removal_mode 0)
		)
		(polygon
			(pts
				(xy 47.034704 -265.075162) (xy 48.533304 -265.075162) (xy 48.533304 -265.5951) (xy 47.034704 -265.5951)
			)
		)
	)
	(zone
		(layer "In2.Cu")
		(hatch none 0.5)
		(connect_pads
			(clearance 0)
		)
		(min_thickness 0.25)
		(keepout
			(tracks not_allowed)
			(vias allowed)
			(pads allowed)
			(copperpour not_allowed)
			(footprints allowed)
		)
		(placement
			(enabled no)
			(sheetname "")
		)
		(fill
			(thermal_gap 0.5)
			(thermal_bridge_width 0.5)
			(island_removal_mode 0)
		)
		(polygon
			(pts
				(xy 175.322738 -315.225176) (xy 176.821338 -315.225176) (xy 176.821338 -315.745114) (xy 175.322738 -315.745114)
			)
		)
	)
	(zone
		(layer "In2.Cu")
		(hatch none 0.5)
		(connect_pads
			(clearance 0)
		)
		(min_thickness 0.25)
		(keepout
			(tracks not_allowed)
			(vias allowed)
			(pads allowed)
			(copperpour not_allowed)
			(footprints allowed)
		)
		(placement
			(enabled no)
			(sheetname "")
		)
		(fill
			(thermal_gap 0.5)
			(thermal_bridge_width 0.5)
			(island_removal_mode 0)
		)
		(polygon
			(pts
				(xy 419.162738 -229.375208) (xy 420.661338 -229.375208) (xy 420.661338 -229.895146) (xy 419.162738 -229.895146)
			)
		)
	)
	(zone
		(layer "In2.Cu")
		(hatch none 0.5)
		(connect_pads
			(clearance 0)
		)
		(min_thickness 0.25)
		(keepout
			(tracks not_allowed)
			(vias allowed)
			(pads allowed)
			(copperpour not_allowed)
			(footprints allowed)
		)
		(placement
			(enabled no)
			(sheetname "")
		)
		(fill
			(thermal_gap 0.5)
			(thermal_bridge_width 0.5)
			(island_removal_mode 0)
		)
		(polygon
			(pts
				(xy 419.162738 -251.47524) (xy 420.661338 -251.47524) (xy 420.661338 -251.995178) (xy 419.162738 -251.995178)
			)
		)
	)
	(zone
		(layer "In2.Cu")
		(hatch none 0.5)
		(connect_pads
			(clearance 0)
		)
		(min_thickness 0.25)
		(keepout
			(tracks not_allowed)
			(vias allowed)
			(pads allowed)
			(copperpour not_allowed)
			(footprints allowed)
		)
		(placement
			(enabled no)
			(sheetname "")
		)
		(fill
			(thermal_gap 0.5)
			(thermal_bridge_width 0.5)
			(island_removal_mode 0)
		)
		(polygon
			(pts
				(xy 279.886664 -283.77515) (xy 281.385264 -283.77515) (xy 281.385264 -284.295088) (xy 279.886664 -284.295088)
			)
		)
	)
	(zone
		(layer "In2.Cu")
		(hatch none 0.5)
		(connect_pads
			(clearance 0)
		)
		(min_thickness 0.25)
		(keepout
			(tracks not_allowed)
			(vias allowed)
			(pads allowed)
			(copperpour not_allowed)
			(footprints allowed)
		)
		(placement
			(enabled no)
			(sheetname "")
		)
		(fill
			(thermal_gap 0.5)
			(thermal_bridge_width 0.5)
			(island_removal_mode 0)
		)
		(polygon
			(pts
				(xy 186.310778 -225.975164) (xy 187.809378 -225.975164) (xy 187.809378 -226.495102) (xy 186.310778 -226.495102)
			)
		)
	)
	(zone
		(layer "In2.Cu")
		(hatch none 0.5)
		(connect_pads
			(clearance 0)
		)
		(min_thickness 0.25)
		(keepout
			(tracks not_allowed)
			(vias allowed)
			(pads allowed)
			(copperpour not_allowed)
			(footprints allowed)
		)
		(placement
			(enabled no)
			(sheetname "")
		)
		(fill
			(thermal_gap 0.5)
			(thermal_bridge_width 0.5)
			(island_removal_mode 0)
		)
		(polygon
			(pts
				(xy 276.442932 -303.325276) (xy 277.941532 -303.325276) (xy 277.941532 -303.845214) (xy 276.442932 -303.845214)
			)
		)
	)
	(zone
		(layer "In2.Cu")
		(hatch none 0.5)
		(connect_pads
			(clearance 0)
		)
		(min_thickness 0.25)
		(keepout
			(tracks not_allowed)
			(vias allowed)
			(pads allowed)
			(copperpour not_allowed)
			(footprints allowed)
		)
		(placement
			(enabled no)
			(sheetname "")
		)
		(fill
			(thermal_gap 0.5)
			(thermal_bridge_width 0.5)
			(island_removal_mode 0)
		)
		(polygon
			(pts
				(xy 58.678826 -282.925266) (xy 60.177426 -282.925266) (xy 60.177426 -283.445204) (xy 58.678826 -283.445204)
			)
		)
	)
	(zone
		(layer "In2.Cu")
		(hatch none 0.5)
		(connect_pads
			(clearance 0)
		)
		(min_thickness 0.25)
		(keepout
			(tracks not_allowed)
			(vias allowed)
			(pads allowed)
			(copperpour not_allowed)
			(footprints allowed)
		)
		(placement
			(enabled no)
			(sheetname "")
		)
		(fill
			(thermal_gap 0.5)
			(thermal_bridge_width 0.5)
			(island_removal_mode 0)
		)
		(polygon
			(pts
				(xy 419.162738 -314.375292) (xy 420.661338 -314.375292) (xy 420.661338 -314.89523) (xy 419.162738 -314.89523)
			)
		)
	)
	(zone
		(layer "In2.Cu")
		(hatch none 0.5)
		(connect_pads
			(clearance 0)
		)
		(min_thickness 0.25)
		(keepout
			(tracks not_allowed)
			(vias allowed)
			(pads allowed)
			(copperpour not_allowed)
			(footprints allowed)
		)
		(placement
			(enabled no)
			(sheetname "")
		)
		(fill
			(thermal_gap 0.5)
			(thermal_bridge_width 0.5)
			(island_removal_mode 0)
		)
		(polygon
			(pts
				(xy 306.618894 -223.425258) (xy 308.117494 -223.425258) (xy 308.117494 -223.945196) (xy 306.618894 -223.945196)
			)
		)
	)
	(zone
		(layer "In2.Cu")
		(hatch none 0.5)
		(connect_pads
			(clearance 0)
		)
		(min_thickness 0.25)
		(keepout
			(tracks not_allowed)
			(vias allowed)
			(pads allowed)
			(copperpour not_allowed)
			(footprints allowed)
		)
		(placement
			(enabled no)
			(sheetname "")
		)
		(fill
			(thermal_gap 0.5)
			(thermal_bridge_width 0.5)
			(island_removal_mode 0)
		)
		(polygon
			(pts
				(xy 434.250846 -285.475172) (xy 435.749446 -285.475172) (xy 435.749446 -285.99511) (xy 434.250846 -285.99511)
			)
		)
	)
	(zone
		(layer "In2.Cu")
		(hatch none 0.5)
		(connect_pads
			(clearance 0)
		)
		(min_thickness 0.25)
		(keepout
			(tracks not_allowed)
			(vias allowed)
			(pads allowed)
			(copperpour not_allowed)
			(footprints allowed)
		)
		(placement
			(enabled no)
			(sheetname "")
		)
		(fill
			(thermal_gap 0.5)
			(thermal_bridge_width 0.5)
			(island_removal_mode 0)
		)
		(polygon
			(pts
				(xy 201.398632 -261.675118) (xy 202.897232 -261.675118) (xy 202.897232 -262.195056) (xy 201.398632 -262.195056)
			)
		)
	)
	(zone
		(layer "In2.Cu")
		(hatch none 0.5)
		(connect_pads
			(clearance 0)
		)
		(min_thickness 0.25)
		(keepout
			(tracks not_allowed)
			(vias allowed)
			(pads allowed)
			(copperpour not_allowed)
			(footprints allowed)
		)
		(placement
			(enabled no)
			(sheetname "")
		)
		(fill
			(thermal_gap 0.5)
			(thermal_bridge_width 0.5)
			(island_removal_mode 0)
		)
		(polygon
			(pts
				(xy 16.858742 -231.925114) (xy 18.357342 -231.925114) (xy 18.357342 -232.445052) (xy 16.858742 -232.445052)
			)
		)
	)
	(zone
		(layer "In2.Cu")
		(hatch none 0.5)
		(connect_pads
			(clearance 0)
		)
		(min_thickness 0.25)
		(keepout
			(tracks not_allowed)
			(vias allowed)
			(pads allowed)
			(copperpour not_allowed)
			(footprints allowed)
		)
		(placement
			(enabled no)
			(sheetname "")
		)
		(fill
			(thermal_gap 0.5)
			(thermal_bridge_width 0.5)
			(island_removal_mode 0)
		)
		(polygon
			(pts
				(xy 268.898878 -197.075298) (xy 270.397478 -197.075298) (xy 270.397478 -197.595236) (xy 268.898878 -197.595236)
			)
		)
	)
	(zone
		(layer "In2.Cu")
		(hatch none 0.5)
		(connect_pads
			(clearance 0)
		)
		(min_thickness 0.25)
		(keepout
			(tracks not_allowed)
			(vias allowed)
			(pads allowed)
			(copperpour not_allowed)
			(footprints allowed)
		)
		(placement
			(enabled no)
			(sheetname "")
		)
		(fill
			(thermal_gap 0.5)
			(thermal_bridge_width 0.5)
			(island_removal_mode 0)
		)
		(polygon
			(pts
				(xy 167.778684 -282.925266) (xy 169.277284 -282.925266) (xy 169.277284 -283.445204) (xy 167.778684 -283.445204)
			)
		)
	)
	(zone
		(layer "In2.Cu")
		(hatch none 0.5)
		(connect_pads
			(clearance 0)
		)
		(min_thickness 0.25)
		(keepout
			(tracks not_allowed)
			(vias allowed)
			(pads allowed)
			(copperpour not_allowed)
			(footprints allowed)
		)
		(placement
			(enabled no)
			(sheetname "")
		)
		(fill
			(thermal_gap 0.5)
			(thermal_bridge_width 0.5)
			(island_removal_mode 0)
		)
		(polygon
			(pts
				(xy 453.438768 -265.9253) (xy 454.937368 -265.9253) (xy 454.937368 -266.445238) (xy 453.438768 -266.445238)
			)
		)
	)
	(zone
		(layer "In2.Cu")
		(hatch none 0.5)
		(connect_pads
			(clearance 0)
		)
		(min_thickness 0.25)
		(keepout
			(tracks not_allowed)
			(vias allowed)
			(pads allowed)
			(copperpour not_allowed)
			(footprints allowed)
		)
		(placement
			(enabled no)
			(sheetname "")
		)
		(fill
			(thermal_gap 0.5)
			(thermal_bridge_width 0.5)
			(island_removal_mode 0)
		)
		(polygon
			(pts
				(xy 302.518826 -249.775218) (xy 304.017426 -249.775218) (xy 304.017426 -250.295156) (xy 302.518826 -250.295156)
			)
		)
	)
	(zone
		(layer "In2.Cu")
		(hatch none 0.5)
		(connect_pads
			(clearance 0)
		)
		(min_thickness 0.25)
		(keepout
			(tracks not_allowed)
			(vias allowed)
			(pads allowed)
			(copperpour not_allowed)
			(footprints allowed)
		)
		(placement
			(enabled no)
			(sheetname "")
		)
		(fill
			(thermal_gap 0.5)
			(thermal_bridge_width 0.5)
			(island_removal_mode 0)
		)
		(polygon
			(pts
				(xy 272.342864 -291.425122) (xy 273.841464 -291.425122) (xy 273.841464 -291.94506) (xy 272.342864 -291.94506)
			)
		)
	)
	(zone
		(layer "In2.Cu")
		(hatch none 0.5)
		(connect_pads
			(clearance 0)
		)
		(min_thickness 0.25)
		(keepout
			(tracks not_allowed)
			(vias allowed)
			(pads allowed)
			(copperpour not_allowed)
			(footprints allowed)
		)
		(placement
			(enabled no)
			(sheetname "")
		)
		(fill
			(thermal_gap 0.5)
			(thermal_bridge_width 0.5)
			(island_removal_mode 0)
		)
		(polygon
			(pts
				(xy 24.402542 -222.57512) (xy 25.901142 -222.57512) (xy 25.901142 -223.095058) (xy 24.402542 -223.095058)
			)
		)
	)
	(zone
		(layer "In2.Cu")
		(hatch none 0.5)
		(connect_pads
			(clearance 0)
		)
		(min_thickness 0.25)
		(keepout
			(tracks not_allowed)
			(vias allowed)
			(pads allowed)
			(copperpour not_allowed)
			(footprints allowed)
		)
		(placement
			(enabled no)
			(sheetname "")
		)
		(fill
			(thermal_gap 0.5)
			(thermal_bridge_width 0.5)
			(island_removal_mode 0)
		)
		(polygon
			(pts
				(xy 190.410846 -208.125314) (xy 191.909446 -208.125314) (xy 191.909446 -208.645252) (xy 190.410846 -208.645252)
			)
		)
	)
	(zone
		(layer "In2.Cu")
		(hatch none 0.5)
		(connect_pads
			(clearance 0)
		)
		(min_thickness 0.25)
		(keepout
			(tracks not_allowed)
			(vias allowed)
			(pads allowed)
			(copperpour not_allowed)
			(footprints allowed)
		)
		(placement
			(enabled no)
			(sheetname "")
		)
		(fill
			(thermal_gap 0.5)
			(thermal_bridge_width 0.5)
			(island_removal_mode 0)
		)
		(polygon
			(pts
				(xy 299.07484 -307.575204) (xy 300.57344 -307.575204) (xy 300.57344 -308.095142) (xy 299.07484 -308.095142)
			)
		)
	)
	(zone
		(layer "In2.Cu")
		(hatch none 0.5)
		(connect_pads
			(clearance 0)
		)
		(min_thickness 0.25)
		(keepout
			(tracks not_allowed)
			(vias allowed)
			(pads allowed)
			(copperpour not_allowed)
			(footprints allowed)
		)
		(placement
			(enabled no)
			(sheetname "")
		)
		(fill
			(thermal_gap 0.5)
			(thermal_bridge_width 0.5)
			(island_removal_mode 0)
		)
		(polygon
			(pts
				(xy 31.946596 -278.675338) (xy 33.445196 -278.675338) (xy 33.445196 -279.195276) (xy 31.946596 -279.195276)
			)
		)
	)
	(zone
		(layer "In2.Cu")
		(hatch none 0.5)
		(connect_pads
			(clearance 0)
		)
		(min_thickness 0.25)
		(keepout
			(tracks not_allowed)
			(vias allowed)
			(pads allowed)
			(copperpour not_allowed)
			(footprints allowed)
		)
		(placement
			(enabled no)
			(sheetname "")
		)
		(fill
			(thermal_gap 0.5)
			(thermal_bridge_width 0.5)
			(island_removal_mode 0)
		)
		(polygon
			(pts
				(xy 306.618894 -237.875318) (xy 308.117494 -237.875318) (xy 308.117494 -238.395256) (xy 306.618894 -238.395256)
			)
		)
	)
	(zone
		(layer "In2.Cu")
		(hatch none 0.5)
		(connect_pads
			(clearance 0)
		)
		(min_thickness 0.25)
		(keepout
			(tracks not_allowed)
			(vias allowed)
			(pads allowed)
			(copperpour not_allowed)
			(footprints allowed)
		)
		(placement
			(enabled no)
			(sheetname "")
		)
		(fill
			(thermal_gap 0.5)
			(thermal_bridge_width 0.5)
			(island_removal_mode 0)
		)
		(polygon
			(pts
				(xy 31.946596 -286.32531) (xy 33.445196 -286.32531) (xy 33.445196 -286.845248) (xy 31.946596 -286.845248)
			)
		)
	)
	(zone
		(layer "In2.Cu")
		(hatch none 0.5)
		(connect_pads
			(clearance 0)
		)
		(min_thickness 0.25)
		(keepout
			(tracks not_allowed)
			(vias allowed)
			(pads allowed)
			(copperpour not_allowed)
			(footprints allowed)
		)
		(placement
			(enabled no)
			(sheetname "")
		)
		(fill
			(thermal_gap 0.5)
			(thermal_bridge_width 0.5)
			(island_removal_mode 0)
		)
		(polygon
			(pts
				(xy 163.678616 -239.57534) (xy 165.177216 -239.57534) (xy 165.177216 -240.095278) (xy 163.678616 -240.095278)
			)
		)
	)
	(zone
		(layer "In2.Cu")
		(hatch none 0.5)
		(connect_pads
			(clearance 0)
		)
		(min_thickness 0.25)
		(keepout
			(tracks not_allowed)
			(vias allowed)
			(pads allowed)
			(copperpour not_allowed)
			(footprints allowed)
		)
		(placement
			(enabled no)
			(sheetname "")
		)
		(fill
			(thermal_gap 0.5)
			(thermal_bridge_width 0.5)
			(island_removal_mode 0)
		)
		(polygon
			(pts
				(xy 163.678616 -263.37514) (xy 165.177216 -263.37514) (xy 165.177216 -263.895078) (xy 163.678616 -263.895078)
			)
		)
	)
	(zone
		(layer "In2.Cu")
		(hatch none 0.5)
		(connect_pads
			(clearance 0)
		)
		(min_thickness 0.25)
		(keepout
			(tracks not_allowed)
			(vias allowed)
			(pads allowed)
			(copperpour not_allowed)
			(footprints allowed)
		)
		(placement
			(enabled no)
			(sheetname "")
		)
		(fill
			(thermal_gap 0.5)
			(thermal_bridge_width 0.5)
			(island_removal_mode 0)
		)
		(polygon
			(pts
				(xy 415.718752 -304.17516) (xy 417.217352 -304.17516) (xy 417.217352 -304.695098) (xy 415.718752 -304.695098)
			)
		)
	)
	(zone
		(layer "In2.Cu")
		(hatch none 0.5)
		(connect_pads
			(clearance 0)
		)
		(min_thickness 0.25)
		(keepout
			(tracks not_allowed)
			(vias allowed)
			(pads allowed)
			(copperpour not_allowed)
			(footprints allowed)
		)
		(placement
			(enabled no)
			(sheetname "")
		)
		(fill
			(thermal_gap 0.5)
			(thermal_bridge_width 0.5)
			(island_removal_mode 0)
		)
		(polygon
			(pts
				(xy 438.350914 -285.475172) (xy 439.849514 -285.475172) (xy 439.849514 -285.99511) (xy 438.350914 -285.99511)
			)
		)
	)
	(zone
		(layer "In2.Cu")
		(hatch none 0.5)
		(connect_pads
			(clearance 0)
		)
		(min_thickness 0.25)
		(keepout
			(tracks not_allowed)
			(vias allowed)
			(pads allowed)
			(copperpour not_allowed)
			(footprints allowed)
		)
		(placement
			(enabled no)
			(sheetname "")
		)
		(fill
			(thermal_gap 0.5)
			(thermal_bridge_width 0.5)
			(island_removal_mode 0)
		)
		(polygon
			(pts
				(xy 287.430718 -305.025298) (xy 288.929318 -305.025298) (xy 288.929318 -305.545236) (xy 287.430718 -305.545236)
			)
		)
	)
	(zone
		(layer "In2.Cu")
		(hatch none 0.5)
		(connect_pads
			(clearance 0)
		)
		(min_thickness 0.25)
		(keepout
			(tracks not_allowed)
			(vias allowed)
			(pads allowed)
			(copperpour not_allowed)
			(footprints allowed)
		)
		(placement
			(enabled no)
			(sheetname "")
		)
		(fill
			(thermal_gap 0.5)
			(thermal_bridge_width 0.5)
			(island_removal_mode 0)
		)
		(polygon
			(pts
				(xy 20.95881 -273.575272) (xy 22.45741 -273.575272) (xy 22.45741 -274.09521) (xy 20.95881 -274.09521)
			)
		)
	)
	(zone
		(layer "In2.Cu")
		(hatch none 0.5)
		(connect_pads
			(clearance 0)
		)
		(min_thickness 0.25)
		(keepout
			(tracks not_allowed)
			(vias allowed)
			(pads allowed)
			(copperpour not_allowed)
			(footprints allowed)
		)
		(placement
			(enabled no)
			(sheetname "")
		)
		(fill
			(thermal_gap 0.5)
			(thermal_bridge_width 0.5)
			(island_removal_mode 0)
		)
		(polygon
			(pts
				(xy 302.518826 -304.17516) (xy 304.017426 -304.17516) (xy 304.017426 -304.695098) (xy 302.518826 -304.695098)
			)
		)
	)
	(zone
		(layer "In2.Cu")
		(hatch none 0.5)
		(connect_pads
			(clearance 0)
		)
		(min_thickness 0.25)
		(keepout
			(tracks not_allowed)
			(vias allowed)
			(pads allowed)
			(copperpour not_allowed)
			(footprints allowed)
		)
		(placement
			(enabled no)
			(sheetname "")
		)
		(fill
			(thermal_gap 0.5)
			(thermal_bridge_width 0.5)
			(island_removal_mode 0)
		)
		(polygon
			(pts
				(xy 197.954646 -217.475308) (xy 199.453246 -217.475308) (xy 199.453246 -217.995246) (xy 197.954646 -217.995246)
			)
		)
	)
	(zone
		(layer "In2.Cu")
		(hatch none 0.5)
		(connect_pads
			(clearance 0)
		)
		(min_thickness 0.25)
		(keepout
			(tracks not_allowed)
			(vias allowed)
			(pads allowed)
			(copperpour not_allowed)
			(footprints allowed)
		)
		(placement
			(enabled no)
			(sheetname "")
		)
		(fill
			(thermal_gap 0.5)
			(thermal_bridge_width 0.5)
			(island_removal_mode 0)
		)
		(polygon
			(pts
				(xy 272.342864 -197.925182) (xy 273.841464 -197.925182) (xy 273.841464 -198.44512) (xy 272.342864 -198.44512)
			)
		)
	)
	(zone
		(layer "In2.Cu")
		(hatch none 0.5)
		(connect_pads
			(clearance 0)
		)
		(min_thickness 0.25)
		(keepout
			(tracks not_allowed)
			(vias allowed)
			(pads allowed)
			(copperpour not_allowed)
			(footprints allowed)
		)
		(placement
			(enabled no)
			(sheetname "")
		)
		(fill
			(thermal_gap 0.5)
			(thermal_bridge_width 0.5)
			(island_removal_mode 0)
		)
		(polygon
			(pts
				(xy 430.80686 -237.875318) (xy 432.30546 -237.875318) (xy 432.30546 -238.395256) (xy 430.80686 -238.395256)
			)
		)
	)
	(zone
		(layer "In2.Cu")
		(hatch none 0.5)
		(connect_pads
			(clearance 0)
		)
		(min_thickness 0.25)
		(keepout
			(tracks not_allowed)
			(vias allowed)
			(pads allowed)
			(copperpour not_allowed)
			(footprints allowed)
		)
		(placement
			(enabled no)
			(sheetname "")
		)
		(fill
			(thermal_gap 0.5)
			(thermal_bridge_width 0.5)
			(island_removal_mode 0)
		)
		(polygon
			(pts
				(xy 58.678826 -299.925232) (xy 60.177426 -299.925232) (xy 60.177426 -300.44517) (xy 58.678826 -300.44517)
			)
		)
	)
	(zone
		(layer "In2.Cu")
		(hatch none 0.5)
		(connect_pads
			(clearance 0)
		)
		(min_thickness 0.25)
		(keepout
			(tracks not_allowed)
			(vias allowed)
			(pads allowed)
			(copperpour not_allowed)
			(footprints allowed)
		)
		(placement
			(enabled no)
			(sheetname "")
		)
		(fill
			(thermal_gap 0.5)
			(thermal_bridge_width 0.5)
			(island_removal_mode 0)
		)
		(polygon
			(pts
				(xy 453.438768 -210.67522) (xy 454.937368 -210.67522) (xy 454.937368 -211.195158) (xy 453.438768 -211.195158)
			)
		)
	)
	(zone
		(layer "In2.Cu")
		(hatch none 0.5)
		(connect_pads
			(clearance 0)
		)
		(min_thickness 0.25)
		(keepout
			(tracks not_allowed)
			(vias allowed)
			(pads allowed)
			(copperpour not_allowed)
			(footprints allowed)
		)
		(placement
			(enabled no)
			(sheetname "")
		)
		(fill
			(thermal_gap 0.5)
			(thermal_bridge_width 0.5)
			(island_removal_mode 0)
		)
		(polygon
			(pts
				(xy 302.518826 -248.075196) (xy 304.017426 -248.075196) (xy 304.017426 -248.595134) (xy 302.518826 -248.595134)
			)
		)
	)
	(zone
		(layer "In2.Cu")
		(hatch none 0.5)
		(connect_pads
			(clearance 0)
		)
		(min_thickness 0.25)
		(keepout
			(tracks not_allowed)
			(vias allowed)
			(pads allowed)
			(copperpour not_allowed)
			(footprints allowed)
		)
		(placement
			(enabled no)
			(sheetname "")
		)
		(fill
			(thermal_gap 0.5)
			(thermal_bridge_width 0.5)
			(island_removal_mode 0)
		)
		(polygon
			(pts
				(xy 268.898878 -231.07523) (xy 270.397478 -231.07523) (xy 270.397478 -231.595168) (xy 268.898878 -231.595168)
			)
		)
	)
	(zone
		(layer "In2.Cu")
		(hatch none 0.5)
		(connect_pads
			(clearance 0)
		)
		(min_thickness 0.25)
		(keepout
			(tracks not_allowed)
			(vias allowed)
			(pads allowed)
			(copperpour not_allowed)
			(footprints allowed)
		)
		(placement
			(enabled no)
			(sheetname "")
		)
		(fill
			(thermal_gap 0.5)
			(thermal_bridge_width 0.5)
			(island_removal_mode 0)
		)
		(polygon
			(pts
				(xy 430.80686 -315.225176) (xy 432.30546 -315.225176) (xy 432.30546 -315.745114) (xy 430.80686 -315.745114)
			)
		)
	)
	(zone
		(layer "In2.Cu")
		(hatch none 0.5)
		(connect_pads
			(clearance 0)
		)
		(min_thickness 0.25)
		(keepout
			(tracks allowed)
			(vias allowed)
			(pads allowed)
			(copperpour allowed)
			(footprints allowed)
		)
		(placement
			(enabled no)
			(sheetname "")
		)
		(fill
			(thermal_gap 0.5)
			(thermal_bridge_width 0.5)
			(island_removal_mode 0)
		)
		(polygon
			(pts
				(xy 19.920966 -417.944808) (xy 19.394678 -417.944808) (xy 19.394678 -417.410392) (xy 19.920966 -417.410392)
			)
		)
	)
	(zone
		(layer "In2.Cu")
		(hatch none 0.5)
		(connect_pads
			(clearance 0)
		)
		(min_thickness 0.25)
		(keepout
			(tracks not_allowed)
			(vias allowed)
			(pads allowed)
			(copperpour not_allowed)
			(footprints allowed)
		)
		(placement
			(enabled no)
			(sheetname "")
		)
		(fill
			(thermal_gap 0.5)
			(thermal_bridge_width 0.5)
			(island_removal_mode 0)
		)
		(polygon
			(pts
				(xy 54.578758 -297.375326) (xy 56.077358 -297.375326) (xy 56.077358 -297.895264) (xy 54.578758 -297.895264)
			)
		)
	)
	(zone
		(layer "In2.Cu")
		(hatch none 0.5)
		(connect_pads
			(clearance 0)
		)
		(min_thickness 0.25)
		(keepout
			(tracks not_allowed)
			(vias allowed)
			(pads allowed)
			(copperpour not_allowed)
			(footprints allowed)
		)
		(placement
			(enabled no)
			(sheetname "")
		)
		(fill
			(thermal_gap 0.5)
			(thermal_bridge_width 0.5)
			(island_removal_mode 0)
		)
		(polygon
			(pts
				(xy 434.250846 -265.075162) (xy 435.749446 -265.075162) (xy 435.749446 -265.5951) (xy 434.250846 -265.5951)
			)
		)
	)
	(zone
		(layer "In2.Cu")
		(hatch none 0.5)
		(connect_pads
			(clearance 0)
		)
		(min_thickness 0.25)
		(keepout
			(tracks not_allowed)
			(vias allowed)
			(pads allowed)
			(copperpour not_allowed)
			(footprints allowed)
		)
		(placement
			(enabled no)
			(sheetname "")
		)
		(fill
			(thermal_gap 0.5)
			(thermal_bridge_width 0.5)
			(island_removal_mode 0)
		)
		(polygon
			(pts
				(xy 20.95881 -262.525256) (xy 22.45741 -262.525256) (xy 22.45741 -263.045194) (xy 20.95881 -263.045194)
			)
		)
	)
	(zone
		(layer "In2.Cu")
		(hatch none 0.5)
		(connect_pads
			(clearance 0)
		)
		(min_thickness 0.25)
		(keepout
			(tracks allowed)
			(vias allowed)
			(pads allowed)
			(copperpour allowed)
			(footprints allowed)
		)
		(placement
			(enabled no)
			(sheetname "")
		)
		(fill
			(thermal_gap 0.5)
			(thermal_bridge_width 0.5)
			(island_removal_mode 0)
		)
		(polygon
			(pts
				(xy 420.641018 -354.336858) (xy 420.641018 -353.714558) (xy 421.192198 -353.714558) (xy 421.192198 -354.336858)
			)
		)
	)
	(zone
		(layer "In2.Cu")
		(hatch none 0.5)
		(connect_pads
			(clearance 0)
		)
		(min_thickness 0.25)
		(keepout
			(tracks not_allowed)
			(vias allowed)
			(pads allowed)
			(copperpour not_allowed)
			(footprints allowed)
		)
		(placement
			(enabled no)
			(sheetname "")
		)
		(fill
			(thermal_gap 0.5)
			(thermal_bridge_width 0.5)
			(island_removal_mode 0)
		)
		(polygon
			(pts
				(xy 276.442932 -309.275226) (xy 277.941532 -309.275226) (xy 277.941532 -309.795164) (xy 276.442932 -309.795164)
			)
		)
	)
	(zone
		(layer "In2.Cu")
		(hatch none 0.5)
		(connect_pads
			(clearance 0)
		)
		(min_thickness 0.25)
		(keepout
			(tracks not_allowed)
			(vias allowed)
			(pads allowed)
			(copperpour not_allowed)
			(footprints allowed)
		)
		(placement
			(enabled no)
			(sheetname "")
		)
		(fill
			(thermal_gap 0.5)
			(thermal_bridge_width 0.5)
			(island_removal_mode 0)
		)
		(polygon
			(pts
				(xy 190.410846 -287.175194) (xy 191.909446 -287.175194) (xy 191.909446 -287.695132) (xy 190.410846 -287.695132)
			)
		)
	)
	(zone
		(layer "In2.Cu")
		(hatch none 0.5)
		(connect_pads
			(clearance 0)
		)
		(min_thickness 0.25)
		(keepout
			(tracks not_allowed)
			(vias allowed)
			(pads allowed)
			(copperpour not_allowed)
			(footprints allowed)
		)
		(placement
			(enabled no)
			(sheetname "")
		)
		(fill
			(thermal_gap 0.5)
			(thermal_bridge_width 0.5)
			(island_removal_mode 0)
		)
		(polygon
			(pts
				(xy 276.442932 -197.075298) (xy 277.941532 -197.075298) (xy 277.941532 -197.595236) (xy 276.442932 -197.595236)
			)
		)
	)
	(zone
		(layer "In2.Cu")
		(hatch none 0.5)
		(connect_pads
			(clearance 0)
		)
		(min_thickness 0.25)
		(keepout
			(tracks not_allowed)
			(vias allowed)
			(pads allowed)
			(copperpour not_allowed)
			(footprints allowed)
		)
		(placement
			(enabled no)
			(sheetname "")
		)
		(fill
			(thermal_gap 0.5)
			(thermal_bridge_width 0.5)
			(island_removal_mode 0)
		)
		(polygon
			(pts
				(xy 299.07484 -282.925266) (xy 300.57344 -282.925266) (xy 300.57344 -283.445204) (xy 299.07484 -283.445204)
			)
		)
	)
	(zone
		(layer "In2.Cu")
		(hatch none 0.5)
		(connect_pads
			(clearance 0)
		)
		(min_thickness 0.25)
		(keepout
			(tracks not_allowed)
			(vias allowed)
			(pads allowed)
			(copperpour not_allowed)
			(footprints allowed)
		)
		(placement
			(enabled no)
			(sheetname "")
		)
		(fill
			(thermal_gap 0.5)
			(thermal_bridge_width 0.5)
			(island_removal_mode 0)
		)
		(polygon
			(pts
				(xy 24.402542 -224.275142) (xy 25.901142 -224.275142) (xy 25.901142 -224.79508) (xy 24.402542 -224.79508)
			)
		)
	)
	(zone
		(layer "In2.Cu")
		(hatch none 0.5)
		(connect_pads
			(clearance 0)
		)
		(min_thickness 0.25)
		(keepout
			(tracks not_allowed)
			(vias allowed)
			(pads allowed)
			(copperpour not_allowed)
			(footprints allowed)
		)
		(placement
			(enabled no)
			(sheetname "")
		)
		(fill
			(thermal_gap 0.5)
			(thermal_bridge_width 0.5)
			(island_removal_mode 0)
		)
		(polygon
			(pts
				(xy 299.07484 -270.175228) (xy 300.57344 -270.175228) (xy 300.57344 -270.695166) (xy 299.07484 -270.695166)
			)
		)
	)
	(zone
		(layer "In2.Cu")
		(hatch none 0.5)
		(connect_pads
			(clearance 0)
		)
		(min_thickness 0.25)
		(keepout
			(tracks not_allowed)
			(vias allowed)
			(pads allowed)
			(copperpour not_allowed)
			(footprints allowed)
		)
		(placement
			(enabled no)
			(sheetname "")
		)
		(fill
			(thermal_gap 0.5)
			(thermal_bridge_width 0.5)
			(island_removal_mode 0)
		)
		(polygon
			(pts
				(xy 268.898878 -215.775286) (xy 270.397478 -215.775286) (xy 270.397478 -216.295224) (xy 268.898878 -216.295224)
			)
		)
	)
	(zone
		(layer "In2.Cu")
		(hatch none 0.5)
		(connect_pads
			(clearance 0)
		)
		(min_thickness 0.25)
		(keepout
			(tracks not_allowed)
			(vias allowed)
			(pads allowed)
			(copperpour not_allowed)
			(footprints allowed)
		)
		(placement
			(enabled no)
			(sheetname "")
		)
		(fill
			(thermal_gap 0.5)
			(thermal_bridge_width 0.5)
			(island_removal_mode 0)
		)
		(polygon
			(pts
				(xy 31.946596 -246.375174) (xy 33.445196 -246.375174) (xy 33.445196 -246.895112) (xy 31.946596 -246.895112)
			)
		)
	)
	(zone
		(layer "In2.Cu")
		(hatch none 0.5)
		(connect_pads
			(clearance 0)
		)
		(min_thickness 0.25)
		(keepout
			(tracks not_allowed)
			(vias allowed)
			(pads allowed)
			(copperpour not_allowed)
			(footprints allowed)
		)
		(placement
			(enabled no)
			(sheetname "")
		)
		(fill
			(thermal_gap 0.5)
			(thermal_bridge_width 0.5)
			(island_removal_mode 0)
		)
		(polygon
			(pts
				(xy 186.310778 -294.825166) (xy 187.809378 -294.825166) (xy 187.809378 -295.345104) (xy 186.310778 -295.345104)
			)
		)
	)
	(zone
		(layer "In2.Cu")
		(hatch none 0.5)
		(connect_pads
			(clearance 0)
		)
		(min_thickness 0.25)
		(keepout
			(tracks not_allowed)
			(vias allowed)
			(pads allowed)
			(copperpour not_allowed)
			(footprints allowed)
		)
		(placement
			(enabled no)
			(sheetname "")
		)
		(fill
			(thermal_gap 0.5)
			(thermal_bridge_width 0.5)
			(island_removal_mode 0)
		)
		(polygon
			(pts
				(xy 197.954646 -301.625254) (xy 199.453246 -301.625254) (xy 199.453246 -302.145192) (xy 197.954646 -302.145192)
			)
		)
	)
	(zone
		(layer "In2.Cu")
		(hatch none 0.5)
		(connect_pads
			(clearance 0)
		)
		(min_thickness 0.25)
		(keepout
			(tracks not_allowed)
			(vias allowed)
			(pads allowed)
			(copperpour not_allowed)
			(footprints allowed)
		)
		(placement
			(enabled no)
			(sheetname "")
		)
		(fill
			(thermal_gap 0.5)
			(thermal_bridge_width 0.5)
			(island_removal_mode 0)
		)
		(polygon
			(pts
				(xy 163.678616 -218.325192) (xy 165.177216 -218.325192) (xy 165.177216 -218.84513) (xy 163.678616 -218.84513)
			)
		)
	)
	(zone
		(layer "In2.Cu")
		(hatch none 0.5)
		(connect_pads
			(clearance 0)
		)
		(min_thickness 0.25)
		(keepout
			(tracks not_allowed)
			(vias allowed)
			(pads allowed)
			(copperpour not_allowed)
			(footprints allowed)
		)
		(placement
			(enabled no)
			(sheetname "")
		)
		(fill
			(thermal_gap 0.5)
			(thermal_bridge_width 0.5)
			(island_removal_mode 0)
		)
		(polygon
			(pts
				(xy 54.578758 -305.025298) (xy 56.077358 -305.025298) (xy 56.077358 -305.545236) (xy 54.578758 -305.545236)
			)
		)
	)
	(zone
		(layer "In2.Cu")
		(hatch none 0.5)
		(connect_pads
			(clearance 0)
		)
		(min_thickness 0.25)
		(keepout
			(tracks not_allowed)
			(vias allowed)
			(pads allowed)
			(copperpour not_allowed)
			(footprints allowed)
		)
		(placement
			(enabled no)
			(sheetname "")
		)
		(fill
			(thermal_gap 0.5)
			(thermal_bridge_width 0.5)
			(island_removal_mode 0)
		)
		(polygon
			(pts
				(xy 268.898878 -304.17516) (xy 270.397478 -304.17516) (xy 270.397478 -304.695098) (xy 268.898878 -304.695098)
			)
		)
	)
	(zone
		(layer "In2.Cu")
		(hatch none 0.5)
		(connect_pads
			(clearance 0)
		)
		(min_thickness 0.25)
		(keepout
			(tracks not_allowed)
			(vias allowed)
			(pads allowed)
			(copperpour not_allowed)
			(footprints allowed)
		)
		(placement
			(enabled no)
			(sheetname "")
		)
		(fill
			(thermal_gap 0.5)
			(thermal_bridge_width 0.5)
			(island_removal_mode 0)
		)
		(polygon
			(pts
				(xy 193.854578 -266.775184) (xy 195.353178 -266.775184) (xy 195.353178 -267.295122) (xy 193.854578 -267.295122)
			)
		)
	)
	(zone
		(layer "In2.Cu")
		(hatch none 0.5)
		(connect_pads
			(clearance 0)
		)
		(min_thickness 0.25)
		(keepout
			(tracks not_allowed)
			(vias allowed)
			(pads allowed)
			(copperpour not_allowed)
			(footprints allowed)
		)
		(placement
			(enabled no)
			(sheetname "")
		)
		(fill
			(thermal_gap 0.5)
			(thermal_bridge_width 0.5)
			(island_removal_mode 0)
		)
		(polygon
			(pts
				(xy 123.74626 -35.680904)
				(arc
					(start 123.886468 -35.680904)
					(mid 123.95635 -35.651695)
					(end 123.98502 -35.58159)
				)
				(arc
					(start 123.98502 -35.280346)
					(mid 123.95635 -35.210241)
					(end 123.886468 -35.181032)
				)
				(xy 123.74626 -35.181032) (xy 123.74626 -35.240976)
				(arc
					(start 123.177046 -35.240976)
					(mid 123.140677 -35.197477)
					(end 123.086368 -35.181032)
				)
				(arc
					(start 122.826272 -35.181032)
					(mid 122.77188 -35.197351)
					(end 122.735594 -35.240976)
				)
				(xy 122.16638 -35.240976) (xy 122.16638 -35.181032)
				(arc
					(start 122.026172 -35.181032)
					(mid 121.95629 -35.210241)
					(end 121.92762 -35.280346)
				)
				(arc
					(start 121.92762 -35.58159)
					(mid 121.95629 -35.651695)
					(end 122.026172 -35.680904)
				)
				(xy 122.16638 -35.680904) (xy 122.16638 -35.62096)
				(arc
					(start 122.735594 -35.62096)
					(mid 122.771963 -35.664459)
					(end 122.826272 -35.680904)
				)
				(arc
					(start 123.086368 -35.680904)
					(mid 123.14076 -35.664585)
					(end 123.177046 -35.62096)
				)
				(xy 123.74626 -35.62096)
			)
		)
	)
	(zone
		(layer "In2.Cu")
		(hatch none 0.5)
		(connect_pads
			(clearance 0)
		)
		(min_thickness 0.25)
		(keepout
			(tracks not_allowed)
			(vias allowed)
			(pads allowed)
			(copperpour not_allowed)
			(footprints allowed)
		)
		(placement
			(enabled no)
			(sheetname "")
		)
		(fill
			(thermal_gap 0.5)
			(thermal_bridge_width 0.5)
			(island_removal_mode 0)
		)
		(polygon
			(pts
				(arc
					(start 30.841442 -11.91768)
					(mid 30.819124 -11.971562)
					(end 30.765242 -11.99388)
				)
				(arc
					(start 29.728668 -11.99388)
					(mid 29.674786 -11.971562)
					(end 29.652468 -11.91768)
				)
				(arc
					(start 29.652468 -10.51814)
					(mid 29.674786 -10.464258)
					(end 29.728668 -10.44194)
				)
				(arc
					(start 30.765242 -10.44194)
					(mid 30.819124 -10.464258)
					(end 30.841442 -10.51814)
				)
			)
		)
	)
	(zone
		(layer "In2.Cu")
		(hatch none 0.5)
		(connect_pads
			(clearance 0)
		)
		(min_thickness 0.25)
		(keepout
			(tracks not_allowed)
			(vias allowed)
			(pads allowed)
			(copperpour not_allowed)
			(footprints allowed)
		)
		(placement
			(enabled no)
			(sheetname "")
		)
		(fill
			(thermal_gap 0.5)
			(thermal_bridge_width 0.5)
			(island_removal_mode 0)
		)
		(polygon
			(pts
				(xy 197.954646 -287.175194) (xy 199.453246 -287.175194) (xy 199.453246 -287.695132) (xy 197.954646 -287.695132)
			)
		)
	)
	(zone
		(layer "In2.Cu")
		(hatch none 0.5)
		(connect_pads
			(clearance 0)
		)
		(min_thickness 0.25)
		(keepout
			(tracks not_allowed)
			(vias allowed)
			(pads allowed)
			(copperpour not_allowed)
			(footprints allowed)
		)
		(placement
			(enabled no)
			(sheetname "")
		)
		(fill
			(thermal_gap 0.5)
			(thermal_bridge_width 0.5)
			(island_removal_mode 0)
		)
		(polygon
			(pts
				(xy 163.678616 -274.425156) (xy 165.177216 -274.425156) (xy 165.177216 -274.945094) (xy 163.678616 -274.945094)
			)
		)
	)
	(zone
		(layer "In2.Cu")
		(hatch none 0.5)
		(connect_pads
			(clearance 0)
		)
		(min_thickness 0.25)
		(keepout
			(tracks not_allowed)
			(vias allowed)
			(pads allowed)
			(copperpour not_allowed)
			(footprints allowed)
		)
		(placement
			(enabled no)
			(sheetname "")
		)
		(fill
			(thermal_gap 0.5)
			(thermal_bridge_width 0.5)
			(island_removal_mode 0)
		)
		(polygon
			(pts
				(xy 299.07484 -198.77532) (xy 300.57344 -198.77532) (xy 300.57344 -199.295258) (xy 299.07484 -199.295258)
			)
		)
	)
	(zone
		(layer "In2.Cu")
		(hatch none 0.5)
		(connect_pads
			(clearance 0)
		)
		(min_thickness 0.25)
		(keepout
			(tracks not_allowed)
			(vias allowed)
			(pads allowed)
			(copperpour not_allowed)
			(footprints allowed)
		)
		(placement
			(enabled no)
			(sheetname "")
		)
		(fill
			(thermal_gap 0.5)
			(thermal_bridge_width 0.5)
			(island_removal_mode 0)
		)
		(polygon
			(pts
				(xy 54.578758 -261.675118) (xy 56.077358 -261.675118) (xy 56.077358 -262.195056) (xy 54.578758 -262.195056)
			)
		)
	)
	(zone
		(layer "In2.Cu")
		(hatch none 0.5)
		(connect_pads
			(clearance 0)
		)
		(min_thickness 0.25)
		(keepout
			(tracks not_allowed)
			(vias allowed)
			(pads allowed)
			(copperpour not_allowed)
			(footprints allowed)
		)
		(placement
			(enabled no)
			(sheetname "")
		)
		(fill
			(thermal_gap 0.5)
			(thermal_bridge_width 0.5)
			(island_removal_mode 0)
		)
		(polygon
			(pts
				(xy 423.262806 -309.275226) (xy 424.761406 -309.275226) (xy 424.761406 -309.795164) (xy 423.262806 -309.795164)
			)
		)
	)
	(zone
		(layer "In2.Cu")
		(hatch none 0.5)
		(connect_pads
			(clearance 0)
		)
		(min_thickness 0.25)
		(keepout
			(tracks not_allowed)
			(vias allowed)
			(pads allowed)
			(copperpour not_allowed)
			(footprints allowed)
		)
		(placement
			(enabled no)
			(sheetname "")
		)
		(fill
			(thermal_gap 0.5)
			(thermal_bridge_width 0.5)
			(island_removal_mode 0)
		)
		(polygon
			(pts
				(xy 415.718752 -312.67527) (xy 417.217352 -312.67527) (xy 417.217352 -313.195208) (xy 415.718752 -313.195208)
			)
		)
	)
	(zone
		(layers "In2.Cu" "In4.Cu" "In6.Cu" "In8.Cu" "In9.Cu" "In11.Cu" "In13.Cu"
			"In15.Cu"
		)
		(hatch none 0.5)
		(connect_pads
			(clearance 0)
		)
		(min_thickness 0.25)
		(keepout
			(tracks not_allowed)
			(vias allowed)
			(pads allowed)
			(copperpour not_allowed)
			(footprints allowed)
		)
		(placement
			(enabled no)
			(sheetname "")
		)
		(fill yes
			(thermal_gap 0.5)
			(thermal_bridge_width 0.5)
			(island_removal_mode 0)
		)
		(polygon
			(pts
				(arc
					(start 298.82084 -435.600348)
					(mid 288.27984 -435.600348)
					(end 298.82084 -435.600348)
				)
			)
		)
	)
	(zone
		(layers "In2.Cu" "In4.Cu" "In6.Cu" "In8.Cu" "In9.Cu" "In11.Cu" "In13.Cu"
			"In15.Cu"
		)
		(hatch none 0.5)
		(connect_pads
			(clearance 0)
		)
		(min_thickness 0.25)
		(keepout
			(tracks not_allowed)
			(vias allowed)
			(pads allowed)
			(copperpour not_allowed)
			(footprints allowed)
		)
		(placement
			(enabled no)
			(sheetname "")
		)
		(fill yes
			(thermal_gap 0.5)
			(thermal_bridge_width 0.5)
			(island_removal_mode 0)
		)
		(polygon
			(pts
				(arc
					(start 105.771188 -435.600094)
					(mid 95.230188 -435.600094)
					(end 105.771188 -435.600094)
				)
			)
		)
	)
	(zone
		(layers "In2.Cu" "In4.Cu" "In6.Cu" "In8.Cu" "In9.Cu" "In11.Cu" "In13.Cu"
			"In15.Cu"
		)
		(hatch none 0.5)
		(connect_pads
			(clearance 0)
		)
		(min_thickness 0.25)
		(keepout
			(tracks not_allowed)
			(vias allowed)
			(pads allowed)
			(copperpour not_allowed)
			(footprints allowed)
		)
		(placement
			(enabled no)
			(sheetname "")
		)
		(fill yes
			(thermal_gap 0.5)
			(thermal_bridge_width 0.5)
			(island_removal_mode 0)
		)
		(polygon
			(pts
				(arc
					(start 376.569478 -435.600348)
					(mid 366.028478 -435.600348)
					(end 376.569478 -435.600348)
				)
			)
		)
	)
	(zone
		(layers "In2.Cu" "In4.Cu" "In6.Cu" "In8.Cu" "In9.Cu" "In11.Cu" "In13.Cu"
			"In15.Cu"
		)
		(hatch none 0.5)
		(connect_pads
			(clearance 0)
		)
		(min_thickness 0.25)
		(keepout
			(tracks not_allowed)
			(vias allowed)
			(pads allowed)
			(copperpour not_allowed)
			(footprints allowed)
		)
		(placement
			(enabled no)
			(sheetname "")
		)
		(fill yes
			(thermal_gap 0.5)
			(thermal_bridge_width 0.5)
			(island_removal_mode 0)
		)
		(polygon
			(pts
				(arc
					(start 241.170714 -81.70037)
					(mid 230.629714 -81.70037)
					(end 241.170714 -81.70037)
				)
			)
		)
	)
	(zone
		(layers "In2.Cu" "In4.Cu" "In6.Cu" "In8.Cu" "In9.Cu" "In11.Cu" "In13.Cu"
			"In15.Cu"
		)
		(hatch none 0.5)
		(connect_pads
			(clearance 0)
		)
		(min_thickness 0.25)
		(keepout
			(tracks not_allowed)
			(vias allowed)
			(pads allowed)
			(copperpour not_allowed)
			(footprints allowed)
		)
		(placement
			(enabled no)
			(sheetname "")
		)
		(fill yes
			(thermal_gap 0.5)
			(thermal_bridge_width 0.5)
			(island_removal_mode 0)
		)
		(polygon
			(pts
				(arc
					(start 185.020712 -435.600094)
					(mid 174.479712 -435.600094)
					(end 185.020712 -435.600094)
				)
			)
		)
	)
	(zone
		(layers "In2.Cu" "In4.Cu" "In6.Cu" "In8.Cu" "In9.Cu" "In11.Cu" "In13.Cu"
			"In15.Cu"
		)
		(hatch none 0.5)
		(connect_pads
			(clearance 0)
		)
		(min_thickness 0.25)
		(keepout
			(tracks not_allowed)
			(vias allowed)
			(pads allowed)
			(copperpour not_allowed)
			(footprints allowed)
		)
		(placement
			(enabled no)
			(sheetname "")
		)
		(fill yes
			(thermal_gap 0.5)
			(thermal_bridge_width 0.5)
			(island_removal_mode 0)
		)
		(polygon
			(pts
				(arc
					(start 451.79996 -435.59984)
					(mid 445.799972 -435.59984)
					(end 451.79996 -435.59984)
				)
			)
		)
	)
	(zone
		(layers "In2.Cu" "In4.Cu" "In6.Cu" "In11.Cu")
		(hatch none 0.5)
		(connect_pads
			(clearance 0)
		)
		(min_thickness 0.25)
		(keepout
			(tracks not_allowed)
			(vias allowed)
			(pads allowed)
			(copperpour not_allowed)
			(footprints allowed)
		)
		(placement
			(enabled no)
			(sheetname "")
		)
		(fill yes
			(thermal_gap 0.5)
			(thermal_bridge_width 0.5)
			(island_removal_mode 0)
		)
		(polygon
			(pts
				(xy 290.91763 -12.914122) (xy 297.813222 -12.914122) (xy 297.813222 -17.914366) (xy 290.91763 -17.914366)
			)
		)
	)
	(zone
		(layers "In2.Cu" "In4.Cu" "In6.Cu" "In11.Cu" "In13.Cu" "In15.Cu")
		(hatch none 0.5)
		(connect_pads
			(clearance 0)
		)
		(min_thickness 0.25)
		(keepout
			(tracks not_allowed)
			(vias allowed)
			(pads allowed)
			(copperpour not_allowed)
			(footprints allowed)
		)
		(placement
			(enabled no)
			(sheetname "")
		)
		(fill yes
			(thermal_gap 0.5)
			(thermal_bridge_width 0.5)
			(island_removal_mode 0)
		)
		(polygon
			(pts
				(arc
					(start 113.402618 -150.941786)
					(mid 111.878618 -150.941786)
					(end 113.402618 -150.941786)
				)
			)
		)
	)
	(zone
		(layers "In2.Cu" "In4.Cu" "In6.Cu" "In11.Cu" "In13.Cu" "In15.Cu")
		(hatch none 0.5)
		(connect_pads
			(clearance 0)
		)
		(min_thickness 0.25)
		(keepout
			(tracks not_allowed)
			(vias allowed)
			(pads allowed)
			(copperpour not_allowed)
			(footprints allowed)
		)
		(placement
			(enabled no)
			(sheetname "")
		)
		(fill yes
			(thermal_gap 0.5)
			(thermal_bridge_width 0.5)
			(island_removal_mode 0)
		)
		(polygon
			(pts
				(xy 381.857504 -153.463752) (xy 381.857504 -156.079952) (xy 380.206504 -156.079952) (xy 380.206504 -153.463752)
			)
		)
	)
	(zone
		(layers "In2.Cu" "In4.Cu" "In6.Cu" "In11.Cu" "In13.Cu" "In15.Cu")
		(hatch none 0.5)
		(connect_pads
			(clearance 0)
		)
		(min_thickness 0.25)
		(keepout
			(tracks not_allowed)
			(vias allowed)
			(pads allowed)
			(copperpour not_allowed)
			(footprints allowed)
		)
		(placement
			(enabled no)
			(sheetname "")
		)
		(fill yes
			(thermal_gap 0.5)
			(thermal_bridge_width 0.5)
			(island_removal_mode 0)
		)
		(polygon
			(pts
				(arc
					(start 15.610586 -160.50006)
					(mid 5.069586 -160.50006)
					(end 15.610586 -160.50006)
				)
			)
		)
	)
	(zone
		(layers "In2.Cu" "In4.Cu" "In6.Cu" "In11.Cu" "In13.Cu" "In15.Cu")
		(hatch none 0.5)
		(connect_pads
			(clearance 0)
		)
		(min_thickness 0.25)
		(keepout
			(tracks not_allowed)
			(vias allowed)
			(pads allowed)
			(copperpour not_allowed)
			(footprints allowed)
		)
		(placement
			(enabled no)
			(sheetname "")
		)
		(fill yes
			(thermal_gap 0.5)
			(thermal_bridge_width 0.5)
			(island_removal_mode 0)
		)
		(polygon
			(pts
				(arc
					(start 378.631958 -165.096952)
					(mid 377.107958 -165.096952)
					(end 378.631958 -165.096952)
				)
			)
		)
	)
	(zone
		(layers "In2.Cu" "In4.Cu" "In6.Cu" "In11.Cu" "In13.Cu" "In15.Cu")
		(hatch none 0.5)
		(connect_pads
			(clearance 0)
		)
		(min_thickness 0.25)
		(keepout
			(tracks not_allowed)
			(vias allowed)
			(pads allowed)
			(copperpour not_allowed)
			(footprints allowed)
		)
		(placement
			(enabled no)
			(sheetname "")
		)
		(fill yes
			(thermal_gap 0.5)
			(thermal_bridge_width 0.5)
			(island_removal_mode 0)
		)
		(polygon
			(pts
				(arc
					(start 15.610586 -347.699838)
					(mid 5.069586 -347.699838)
					(end 15.610586 -347.699838)
				)
			)
		)
	)
	(zone
		(layers "In2.Cu" "In4.Cu" "In6.Cu" "In11.Cu" "In13.Cu" "In15.Cu")
		(hatch none 0.5)
		(connect_pads
			(clearance 0)
		)
		(min_thickness 0.25)
		(keepout
			(tracks not_allowed)
			(vias allowed)
			(pads allowed)
			(copperpour not_allowed)
			(footprints allowed)
		)
		(placement
			(enabled no)
			(sheetname "")
		)
		(fill yes
			(thermal_gap 0.5)
			(thermal_bridge_width 0.5)
			(island_removal_mode 0)
		)
		(polygon
			(pts
				(arc
					(start 241.920522 -272.499836)
					(mid 231.379522 -272.499836)
					(end 241.920522 -272.499836)
				)
			)
		)
	)
	(zone
		(layers "In2.Cu" "In4.Cu" "In6.Cu" "In11.Cu" "In13.Cu" "In15.Cu")
		(hatch none 0.5)
		(connect_pads
			(clearance 0)
		)
		(min_thickness 0.25)
		(keepout
			(tracks not_allowed)
			(vias allowed)
			(pads allowed)
			(copperpour not_allowed)
			(footprints allowed)
		)
		(placement
			(enabled no)
			(sheetname "")
		)
		(fill yes
			(thermal_gap 0.5)
			(thermal_bridge_width 0.5)
			(island_removal_mode 0)
		)
		(polygon
			(pts
				(arc
					(start 18.270474 -435.600348)
					(mid 7.729474 -435.600348)
					(end 18.270474 -435.600348)
				)
			)
		)
	)
	(zone
		(layers "In2.Cu" "In4.Cu" "In6.Cu" "In11.Cu" "In13.Cu" "In15.Cu")
		(hatch none 0.5)
		(connect_pads
			(clearance 0)
		)
		(min_thickness 0.25)
		(keepout
			(tracks not_allowed)
			(vias allowed)
			(pads allowed)
			(copperpour not_allowed)
			(footprints allowed)
		)
		(placement
			(enabled no)
			(sheetname "")
		)
		(fill yes
			(thermal_gap 0.5)
			(thermal_bridge_width 0.5)
			(island_removal_mode 0)
		)
		(polygon
			(pts
				(arc
					(start 208.670398 -22.29993)
					(mid 198.129398 -22.29993)
					(end 208.670398 -22.29993)
				)
			)
		)
	)
	(zone
		(layers "In2.Cu" "In4.Cu" "In6.Cu" "In11.Cu" "In13.Cu" "In15.Cu")
		(hatch none 0.5)
		(connect_pads
			(clearance 0)
		)
		(min_thickness 0.25)
		(keepout
			(tracks not_allowed)
			(vias allowed)
			(pads allowed)
			(copperpour not_allowed)
			(footprints allowed)
		)
		(placement
			(enabled no)
			(sheetname "")
		)
		(fill yes
			(thermal_gap 0.5)
			(thermal_bridge_width 0.5)
			(island_removal_mode 0)
		)
		(polygon
			(pts
				(arc
					(start 241.920522 -352.49993)
					(mid 231.379522 -352.49993)
					(end 241.920522 -352.49993)
				)
			)
		)
	)
	(zone
		(layers "In2.Cu" "In4.Cu" "In6.Cu" "In11.Cu" "In13.Cu" "In15.Cu")
		(hatch none 0.5)
		(connect_pads
			(clearance 0)
		)
		(min_thickness 0.25)
		(keepout
			(tracks not_allowed)
			(vias allowed)
			(pads allowed)
			(copperpour not_allowed)
			(footprints allowed)
		)
		(placement
			(enabled no)
			(sheetname "")
		)
		(fill yes
			(thermal_gap 0.5)
			(thermal_bridge_width 0.5)
			(island_removal_mode 0)
		)
		(polygon
			(pts
				(arc
					(start 466.730588 -160.50006)
					(mid 456.189588 -160.50006)
					(end 466.730588 -160.50006)
				)
			)
		)
	)
	(zone
		(layers "In2.Cu" "In4.Cu" "In6.Cu" "In11.Cu" "In13.Cu" "In15.Cu")
		(hatch none 0.5)
		(connect_pads
			(clearance 0)
		)
		(min_thickness 0.25)
		(keepout
			(tracks not_allowed)
			(vias allowed)
			(pads allowed)
			(copperpour not_allowed)
			(footprints allowed)
		)
		(placement
			(enabled no)
			(sheetname "")
		)
		(fill yes
			(thermal_gap 0.5)
			(thermal_bridge_width 0.5)
			(island_removal_mode 0)
		)
		(polygon
			(pts
				(arc
					(start 386.170424 -22.29993)
					(mid 375.629424 -22.29993)
					(end 386.170424 -22.29993)
				)
			)
		)
	)
	(zone
		(layers "In2.Cu" "In4.Cu" "In6.Cu" "In11.Cu" "In13.Cu" "In15.Cu")
		(hatch none 0.5)
		(connect_pads
			(clearance 0)
		)
		(min_thickness 0.25)
		(keepout
			(tracks not_allowed)
			(vias allowed)
			(pads allowed)
			(copperpour not_allowed)
			(footprints allowed)
		)
		(placement
			(enabled no)
			(sheetname "")
		)
		(fill yes
			(thermal_gap 0.5)
			(thermal_bridge_width 0.5)
			(island_removal_mode 0)
		)
		(polygon
			(pts
				(arc
					(start 387.968998 -165.152832)
					(mid 386.444998 -165.152832)
					(end 387.968998 -165.152832)
				)
			)
		)
	)
	(zone
		(layers "In2.Cu" "In4.Cu" "In6.Cu" "In11.Cu" "In13.Cu" "In15.Cu")
		(hatch none 0.5)
		(connect_pads
			(clearance 0)
		)
		(min_thickness 0.25)
		(keepout
			(tracks not_allowed)
			(vias allowed)
			(pads allowed)
			(copperpour not_allowed)
			(footprints allowed)
		)
		(placement
			(enabled no)
			(sheetname "")
		)
		(fill yes
			(thermal_gap 0.5)
			(thermal_bridge_width 0.5)
			(island_removal_mode 0)
		)
		(polygon
			(pts
				(arc
					(start 100.170488 -22.29993)
					(mid 89.629488 -22.29993)
					(end 100.170488 -22.29993)
				)
			)
		)
	)
	(zone
		(layers "In2.Cu" "In4.Cu" "In6.Cu" "In11.Cu" "In13.Cu" "In15.Cu")
		(hatch none 0.5)
		(connect_pads
			(clearance 0)
		)
		(min_thickness 0.25)
		(keepout
			(tracks not_allowed)
			(vias allowed)
			(pads allowed)
			(copperpour not_allowed)
			(footprints allowed)
		)
		(placement
			(enabled no)
			(sheetname "")
		)
		(fill yes
			(thermal_gap 0.5)
			(thermal_bridge_width 0.5)
			(island_removal_mode 0)
		)
		(polygon
			(pts
				(arc
					(start 464.070446 -435.600348)
					(mid 453.529446 -435.600348)
					(end 464.070446 -435.600348)
				)
			)
		)
	)
	(zone
		(layers "In2.Cu" "In4.Cu" "In6.Cu" "In11.Cu" "In13.Cu" "In15.Cu")
		(hatch none 0.5)
		(connect_pads
			(clearance 0)
		)
		(min_thickness 0.25)
		(keepout
			(tracks not_allowed)
			(vias allowed)
			(pads allowed)
			(copperpour not_allowed)
			(footprints allowed)
		)
		(placement
			(enabled no)
			(sheetname "")
		)
		(fill yes
			(thermal_gap 0.5)
			(thermal_bridge_width 0.5)
			(island_removal_mode 0)
		)
		(polygon
			(pts
				(arc
					(start 73.68286 -47.049944)
					(mid 67.082924 -47.049944)
					(end 73.68286 -47.049944)
				)
			)
		)
	)
	(zone
		(layers "In2.Cu" "In4.Cu" "In6.Cu" "In11.Cu" "In13.Cu" "In15.Cu")
		(hatch none 0.5)
		(connect_pads
			(clearance 0)
		)
		(min_thickness 0.25)
		(keepout
			(tracks not_allowed)
			(vias allowed)
			(pads allowed)
			(copperpour not_allowed)
			(footprints allowed)
		)
		(placement
			(enabled no)
			(sheetname "")
		)
		(fill yes
			(thermal_gap 0.5)
			(thermal_bridge_width 0.5)
			(island_removal_mode 0)
		)
		(polygon
			(pts
				(arc
					(start 328.170794 -160.50006)
					(mid 317.629794 -160.50006)
					(end 328.170794 -160.50006)
				)
			)
		)
	)
	(zone
		(layers "In2.Cu" "In4.Cu" "In6.Cu" "In11.Cu" "In13.Cu" "In15.Cu")
		(hatch none 0.5)
		(connect_pads
			(clearance 0)
		)
		(min_thickness 0.25)
		(keepout
			(tracks not_allowed)
			(vias allowed)
			(pads allowed)
			(copperpour not_allowed)
			(footprints allowed)
		)
		(placement
			(enabled no)
			(sheetname "")
		)
		(fill yes
			(thermal_gap 0.5)
			(thermal_bridge_width 0.5)
			(island_removal_mode 0)
		)
		(polygon
			(pts
				(arc
					(start 322.90004 -165.52926)
					(mid 327.92924 -160.50006)
					(end 322.90004 -155.47086)
				)
				(arc
					(start 322.90004 -155.47086)
					(mid 322.78574 -155.35656)
					(end 322.90004 -155.24226)
				)
				(arc
					(start 322.90004 -155.24226)
					(mid 328.15784 -160.50006)
					(end 322.90004 -165.75786)
				)
				(arc
					(start 322.90004 -165.75786)
					(mid 322.78574 -165.64356)
					(end 322.90004 -165.52926)
				)
			)
		)
	)
	(zone
		(layers "In2.Cu" "In4.Cu" "In6.Cu" "In11.Cu" "In13.Cu" "In15.Cu")
		(hatch none 0.5)
		(connect_pads
			(clearance 0)
		)
		(min_thickness 0.25)
		(keepout
			(tracks not_allowed)
			(vias allowed)
			(pads allowed)
			(copperpour not_allowed)
			(footprints allowed)
		)
		(placement
			(enabled no)
			(sheetname "")
		)
		(fill yes
			(thermal_gap 0.5)
			(thermal_bridge_width 0.5)
			(island_removal_mode 0)
		)
		(polygon
			(pts
				(arc
					(start 241.920522 -192.499996)
					(mid 231.379522 -192.499996)
					(end 241.920522 -192.499996)
				)
			)
		)
	)
	(zone
		(layers "In2.Cu" "In4.Cu" "In6.Cu" "In11.Cu" "In13.Cu" "In15.Cu")
		(hatch none 0.5)
		(connect_pads
			(clearance 0)
		)
		(min_thickness 0.25)
		(keepout
			(tracks not_allowed)
			(vias allowed)
			(pads allowed)
			(copperpour not_allowed)
			(footprints allowed)
		)
		(placement
			(enabled no)
			(sheetname "")
		)
		(fill yes
			(thermal_gap 0.5)
			(thermal_bridge_width 0.5)
			(island_removal_mode 0)
		)
		(polygon
			(pts
				(arc
					(start 200.354946 -153.774902)
					(mid 187.55487 -153.774902)
					(end 200.354946 -153.774902)
				)
			)
		)
	)
	(zone
		(layers "In2.Cu" "In4.Cu" "In6.Cu" "In11.Cu" "In13.Cu" "In15.Cu")
		(hatch none 0.5)
		(connect_pads
			(clearance 0)
		)
		(min_thickness 0.25)
		(keepout
			(tracks not_allowed)
			(vias allowed)
			(pads allowed)
			(copperpour not_allowed)
			(footprints allowed)
		)
		(placement
			(enabled no)
			(sheetname "")
		)
		(fill yes
			(thermal_gap 0.5)
			(thermal_bridge_width 0.5)
			(island_removal_mode 0)
		)
		(polygon
			(pts
				(arc
					(start 362.847382 -152.71242)
					(mid 361.323382 -152.71242)
					(end 362.847382 -152.71242)
				)
			)
		)
	)
	(zone
		(layers "In2.Cu" "In4.Cu" "In6.Cu" "In11.Cu" "In13.Cu" "In15.Cu")
		(hatch none 0.5)
		(connect_pads
			(clearance 0)
		)
		(min_thickness 0.25)
		(keepout
			(tracks not_allowed)
			(vias allowed)
			(pads allowed)
			(copperpour not_allowed)
			(footprints allowed)
		)
		(placement
			(enabled no)
			(sheetname "")
		)
		(fill yes
			(thermal_gap 0.5)
			(thermal_bridge_width 0.5)
			(island_removal_mode 0)
		)
		(polygon
			(pts
				(arc
					(start 173.170596 -160.50006)
					(mid 162.629596 -160.50006)
					(end 173.170596 -160.50006)
				)
			)
		)
	)
	(zone
		(layers "In2.Cu" "In4.Cu" "In6.Cu" "In11.Cu" "In13.Cu" "In15.Cu")
		(hatch none 0.5)
		(connect_pads
			(clearance 0)
		)
		(min_thickness 0.25)
		(keepout
			(tracks not_allowed)
			(vias allowed)
			(pads allowed)
			(copperpour not_allowed)
			(footprints allowed)
		)
		(placement
			(enabled no)
			(sheetname "")
		)
		(fill yes
			(thermal_gap 0.5)
			(thermal_bridge_width 0.5)
			(island_removal_mode 0)
		)
		(polygon
			(pts
				(xy 367.488978 -158.308548) (xy 367.488978 -156.063442) (xy 371.200172 -156.063442) (xy 371.200172 -158.308548)
			)
		)
	)
	(zone
		(layers "In2.Cu" "In4.Cu" "In6.Cu" "In11.Cu" "In13.Cu" "In15.Cu")
		(hatch none 0.5)
		(connect_pads
			(clearance 0)
		)
		(min_thickness 0.25)
		(keepout
			(tracks not_allowed)
			(vias allowed)
			(pads allowed)
			(copperpour not_allowed)
			(footprints allowed)
		)
		(placement
			(enabled no)
			(sheetname "")
		)
		(fill yes
			(thermal_gap 0.5)
			(thermal_bridge_width 0.5)
			(island_removal_mode 0)
		)
		(polygon
			(pts
				(xy 86.44001 -157.470094) (xy 86.44001 -155.14574) (xy 90.144346 -155.14574) (xy 90.144346 -157.470094)
			)
		)
	)
	(zone
		(layers "In2.Cu" "In4.Cu" "In6.Cu" "In11.Cu" "In13.Cu" "In15.Cu")
		(hatch none 0.5)
		(connect_pads
			(clearance 0)
		)
		(min_thickness 0.25)
		(keepout
			(tracks not_allowed)
			(vias allowed)
			(pads allowed)
			(copperpour not_allowed)
			(footprints allowed)
		)
		(placement
			(enabled no)
			(sheetname "")
		)
		(fill yes
			(thermal_gap 0.5)
			(thermal_bridge_width 0.5)
			(island_removal_mode 0)
		)
		(polygon
			(pts
				(xy 88.462612 -354.37572) (xy 88.462612 -352.02622) (xy 92.347796 -352.02622) (xy 92.347796 -354.37572)
			)
		)
	)
	(zone
		(layers "In2.Cu" "In4.Cu" "In6.Cu" "In11.Cu" "In13.Cu" "In15.Cu")
		(hatch none 0.5)
		(connect_pads
			(clearance 0)
		)
		(min_thickness 0.25)
		(keepout
			(tracks not_allowed)
			(vias allowed)
			(pads allowed)
			(copperpour not_allowed)
			(footprints allowed)
		)
		(placement
			(enabled no)
			(sheetname "")
		)
		(fill yes
			(thermal_gap 0.5)
			(thermal_bridge_width 0.5)
			(island_removal_mode 0)
		)
		(polygon
			(pts
				(arc
					(start 284.295088 -153.76652)
					(mid 271.495012 -153.76652)
					(end 284.295088 -153.76652)
				)
			)
		)
	)
	(zone
		(layers "In2.Cu" "In4.Cu" "In6.Cu" "In11.Cu" "In13.Cu" "In15.Cu")
		(hatch none 0.5)
		(connect_pads
			(clearance 0)
		)
		(min_thickness 0.25)
		(keepout
			(tracks not_allowed)
			(vias allowed)
			(pads allowed)
			(copperpour not_allowed)
			(footprints allowed)
		)
		(placement
			(enabled no)
			(sheetname "")
		)
		(fill yes
			(thermal_gap 0.5)
			(thermal_bridge_width 0.5)
			(island_removal_mode 0)
		)
		(polygon
			(pts
				(arc
					(start 322.90004 -155.47086)
					(mid 317.87084 -160.50006)
					(end 322.90004 -165.52926)
				)
				(arc
					(start 322.90004 -165.52926)
					(mid 323.01434 -165.64356)
					(end 322.90004 -165.75786)
				)
				(arc
					(start 322.90004 -165.75786)
					(mid 317.64224 -160.50006)
					(end 322.90004 -155.24226)
				)
				(arc
					(start 322.90004 -155.24226)
					(mid 323.01434 -155.35656)
					(end 322.90004 -155.47086)
				)
			)
		)
	)
	(zone
		(layers "In2.Cu" "In4.Cu" "In6.Cu" "In11.Cu" "In13.Cu" "In15.Cu")
		(hatch none 0.5)
		(connect_pads
			(clearance 0)
		)
		(min_thickness 0.25)
		(keepout
			(tracks allowed)
			(vias allowed)
			(pads allowed)
			(copperpour allowed)
			(footprints allowed)
		)
		(placement
			(enabled no)
			(sheetname "")
		)
		(fill yes
			(thermal_gap 0.5)
			(thermal_bridge_width 0.5)
			(island_removal_mode 0)
		)
		(polygon
			(pts
				(xy 323.895974 -296.61231) (xy 323.895974 -226.66579) (xy 324.434454 -226.12731) (xy 324.434454 -223.33331)
				(xy 326.593454 -221.17431) (xy 395.859254 -221.17431) (xy 395.859254 -296.61231)
			)
		)
	)
	(zone
		(layers "In2.Cu" "In4.Cu" "In6.Cu" "In11.Cu" "In13.Cu" "In15.Cu")
		(hatch none 0.5)
		(connect_pads
			(clearance 0)
		)
		(min_thickness 0.25)
		(keepout
			(tracks not_allowed)
			(vias allowed)
			(pads allowed)
			(copperpour not_allowed)
			(footprints allowed)
		)
		(placement
			(enabled no)
			(sheetname "")
		)
		(fill yes
			(thermal_gap 0.5)
			(thermal_bridge_width 0.5)
			(island_removal_mode 0)
		)
		(polygon
			(pts
				(arc
					(start 83.751674 -168.462198)
					(mid 82.227674 -168.462198)
					(end 83.751674 -168.462198)
				)
			)
		)
	)
	(zone
		(layers "In2.Cu" "In4.Cu" "In6.Cu" "In11.Cu" "In13.Cu" "In15.Cu")
		(hatch none 0.5)
		(connect_pads
			(clearance 0)
		)
		(min_thickness 0.25)
		(keepout
			(tracks not_allowed)
			(vias allowed)
			(pads allowed)
			(copperpour not_allowed)
			(footprints allowed)
		)
		(placement
			(enabled no)
			(sheetname "")
		)
		(fill yes
			(thermal_gap 0.5)
			(thermal_bridge_width 0.5)
			(island_removal_mode 0)
		)
		(polygon
			(pts
				(arc
					(start 12.270486 -22.29993)
					(mid 1.729486 -22.29993)
					(end 12.270486 -22.29993)
				)
			)
		)
	)
	(zone
		(layers "In2.Cu" "In4.Cu" "In6.Cu" "In11.Cu" "In13.Cu" "In15.Cu")
		(hatch none 0.5)
		(connect_pads
			(clearance 0)
		)
		(min_thickness 0.25)
		(keepout
			(tracks not_allowed)
			(vias allowed)
			(pads allowed)
			(copperpour not_allowed)
			(footprints allowed)
		)
		(placement
			(enabled no)
			(sheetname "")
		)
		(fill yes
			(thermal_gap 0.5)
			(thermal_bridge_width 0.5)
			(island_removal_mode 0)
		)
		(polygon
			(pts
				(arc
					(start 209.91576 -51.999896)
					(mid 199.37476 -51.999896)
					(end 209.91576 -51.999896)
				)
			)
		)
	)
	(zone
		(layers "In2.Cu" "In4.Cu" "In6.Cu" "In11.Cu" "In13.Cu" "In15.Cu")
		(hatch none 0.5)
		(connect_pads
			(clearance 0)
		)
		(min_thickness 0.25)
		(keepout
			(tracks not_allowed)
			(vias allowed)
			(pads allowed)
			(copperpour not_allowed)
			(footprints allowed)
		)
		(placement
			(enabled no)
			(sheetname "")
		)
		(fill yes
			(thermal_gap 0.5)
			(thermal_bridge_width 0.5)
			(island_removal_mode 0)
		)
		(polygon
			(pts
				(arc
					(start 351.317052 -147.904962)
					(mid 344.78722 -147.904962)
					(end 351.317052 -147.904962)
				)
			)
		)
	)
	(zone
		(layers "In2.Cu" "In4.Cu" "In6.Cu" "In11.Cu" "In13.Cu" "In15.Cu")
		(hatch none 0.5)
		(connect_pads
			(clearance 0)
		)
		(min_thickness 0.25)
		(keepout
			(tracks not_allowed)
			(vias allowed)
			(pads allowed)
			(copperpour not_allowed)
			(footprints allowed)
		)
		(placement
			(enabled no)
			(sheetname "")
		)
		(fill yes
			(thermal_gap 0.5)
			(thermal_bridge_width 0.5)
			(island_removal_mode 0)
		)
		(polygon
			(pts
				(arc
					(start 93.149674 -168.462198)
					(mid 91.625674 -168.462198)
					(end 93.149674 -168.462198)
				)
			)
		)
	)
	(zone
		(layers "In2.Cu" "In4.Cu" "In6.Cu" "In11.Cu" "In13.Cu" "In15.Cu")
		(hatch none 0.5)
		(connect_pads
			(clearance 0)
		)
		(min_thickness 0.25)
		(keepout
			(tracks not_allowed)
			(vias allowed)
			(pads allowed)
			(copperpour not_allowed)
			(footprints allowed)
		)
		(placement
			(enabled no)
			(sheetname "")
		)
		(fill yes
			(thermal_gap 0.5)
			(thermal_bridge_width 0.5)
			(island_removal_mode 0)
		)
		(polygon
			(pts
				(arc
					(start 466.730588 -347.699838)
					(mid 456.189588 -347.699838)
					(end 466.730588 -347.699838)
				)
			)
		)
	)
	(zone
		(layers "In2.Cu" "In4.Cu" "In6.Cu" "In11.Cu" "In13.Cu" "In15.Cu")
		(hatch none 0.5)
		(connect_pads
			(clearance 0)
		)
		(min_thickness 0.25)
		(keepout
			(tracks not_allowed)
			(vias allowed)
			(pads allowed)
			(copperpour not_allowed)
			(footprints allowed)
		)
		(placement
			(enabled no)
			(sheetname "")
		)
		(fill yes
			(thermal_gap 0.5)
			(thermal_bridge_width 0.5)
			(island_removal_mode 0)
		)
		(polygon
			(pts
				(arc
					(start 470.070434 -22.29993)
					(mid 459.529434 -22.29993)
					(end 470.070434 -22.29993)
				)
			)
		)
	)
	(zone
		(layers "In2.Cu" "In4.Cu" "In6.Cu" "In11.Cu" "In13.Cu" "In15.Cu")
		(hatch none 0.5)
		(connect_pads
			(clearance 0)
		)
		(min_thickness 0.25)
		(keepout
			(tracks not_allowed)
			(vias allowed)
			(pads allowed)
			(copperpour not_allowed)
			(footprints allowed)
		)
		(placement
			(enabled no)
			(sheetname "")
		)
		(fill yes
			(thermal_gap 0.5)
			(thermal_bridge_width 0.5)
			(island_removal_mode 0)
		)
		(polygon
			(pts
				(arc
					(start 103.6828 -47.049944)
					(mid 97.082864 -47.049944)
					(end 103.6828 -47.049944)
				)
			)
		)
	)
	(zone
		(layers "In2.Cu" "In4.Cu" "In6.Cu" "In11.Cu" "In13.Cu" "In15.Cu")
		(hatch none 0.5)
		(connect_pads
			(clearance 0)
		)
		(min_thickness 0.25)
		(keepout
			(tracks not_allowed)
			(vias allowed)
			(pads allowed)
			(copperpour not_allowed)
			(footprints allowed)
		)
		(placement
			(enabled no)
			(sheetname "")
		)
		(fill yes
			(thermal_gap 0.5)
			(thermal_bridge_width 0.5)
			(island_removal_mode 0)
		)
		(polygon
			(pts
				(arc
					(start 273.91614 -52.00015)
					(mid 263.37514 -52.00015)
					(end 273.91614 -52.00015)
				)
			)
		)
	)
	(zone
		(layers "In2.Cu" "In4.Cu" "In6.Cu" "In11.Cu" "In13.Cu" "In15.Cu")
		(hatch none 0.5)
		(connect_pads
			(clearance 0)
		)
		(min_thickness 0.25)
		(keepout
			(tracks not_allowed)
			(vias allowed)
			(pads allowed)
			(copperpour not_allowed)
			(footprints allowed)
		)
		(placement
			(enabled no)
			(sheetname "")
		)
		(fill yes
			(thermal_gap 0.5)
			(thermal_bridge_width 0.5)
			(island_removal_mode 0)
		)
		(polygon
			(pts
				(xy 117.203474 -144.940528) (xy 119.819674 -144.940528) (xy 119.819674 -146.591528) (xy 117.203474 -146.591528)
			)
		)
	)
	(zone
		(layers "In2.Cu" "In4.Cu" "In6.Cu" "In11.Cu" "In15.Cu")
		(hatch none 0.5)
		(connect_pads
			(clearance 0)
		)
		(min_thickness 0.25)
		(keepout
			(tracks not_allowed)
			(vias allowed)
			(pads allowed)
			(copperpour not_allowed)
			(footprints allowed)
		)
		(placement
			(enabled no)
			(sheetname "")
		)
		(fill yes
			(thermal_gap 0.5)
			(thermal_bridge_width 0.5)
			(island_removal_mode 0)
		)
		(polygon
			(pts
				(arc
					(start 450.454268 -74.873358)
					(mid 448.930268 -74.873358)
					(end 450.454268 -74.873358)
				)
			)
		)
	)
	(zone
		(layers "In2.Cu" "In4.Cu" "In6.Cu" "In11.Cu" "In15.Cu")
		(hatch none 0.5)
		(connect_pads
			(clearance 0)
		)
		(min_thickness 0.25)
		(keepout
			(tracks not_allowed)
			(vias allowed)
			(pads allowed)
			(copperpour not_allowed)
			(footprints allowed)
		)
		(placement
			(enabled no)
			(sheetname "")
		)
		(fill yes
			(thermal_gap 0.5)
			(thermal_bridge_width 0.5)
			(island_removal_mode 0)
		)
		(polygon
			(pts
				(arc
					(start 457.962508 -74.873358)
					(mid 456.438508 -74.873358)
					(end 457.962508 -74.873358)
				)
			)
		)
	)
	(zone
		(layers "In2.Cu" "In4.Cu" "In6.Cu" "In12.Cu" "In14.Cu" "In16.Cu")
		(hatch none 0.5)
		(connect_pads
			(clearance 0.5)
		)
		(min_thickness 0.25)
		(fill yes
			(thermal_gap 0.5)
			(thermal_bridge_width 0.5)
			(island_removal_mode 0)
		)
		(polygon
			(pts
				(arc
					(start 474.307916 -461.028288)
					(mid 474.744912 -462.083288)
					(end 475.799912 -462.520284)
				)
				(arc
					(start 531.7998 -462.520284)
					(mid 532.8548 -462.083288)
					(end 533.291796 -461.028288)
				)
				(arc
					(start 533.291796 -455.0283)
					(mid 532.8548 -453.9733)
					(end 531.7998 -453.536304)
				)
				(arc
					(start 516.019796 -453.536304)
					(mid 514.246375 -452.801729)
					(end 513.5118 -451.028308)
				)
				(arc
					(start 513.5118 -312.408316)
					(mid 514.246375 -310.634895)
					(end 516.019796 -309.90032)
				)
				(arc
					(start 531.7998 -309.90032)
					(mid 532.8548 -309.463324)
					(end 533.291796 -308.408324)
				)
				(arc
					(start 533.291796 10.40003)
					(mid 532.8548 11.45503)
					(end 531.7998 11.892026)
				)
				(arc
					(start 475.799912 11.892026)
					(mid 474.744912 11.45503)
					(end 474.307916 10.40003)
				)
				(arc
					(start 474.307916 -77.67193)
					(mid 473.964721 -79.396816)
					(end 472.987624 -80.859122)
				)
				(arc
					(start 471.245184 -82.601562)
					(mid 470.921671 -83.085639)
					(end 470.80805 -83.656678)
				)
				(arc
					(start 470.80805 -404.871936)
					(mid 470.464855 -406.596822)
					(end 469.487758 -408.059128)
				)
				(arc
					(start 468.244936 -409.30195)
					(mid 467.921608 -409.785939)
					(end 467.808056 -410.356812)
				)
				(xy 467.808056 -418.45738) (xy 464.79206 -418.45738)
				(arc
					(start 464.79206 -409.528264)
					(mid 464.983018 -408.568632)
					(end 465.526628 -407.75509)
				)
				(arc
					(start 467.355174 -405.926544)
					(mid 467.678507 -405.442687)
					(end 467.792054 -404.871936)
				)
				(arc
					(start 467.792054 -82.82813)
					(mid 467.983012 -81.868498)
					(end 468.526622 -81.054956)
				)
				(arc
					(start 470.85504 -78.726538)
					(mid 471.178373 -78.242681)
					(end 471.29192 -77.67193)
				)
				(arc
					(start 471.29192 -13.780008)
					(mid 470.854924 -12.725008)
					(end 469.799924 -12.288012)
				)
				(xy 464.447636 -12.288012) (xy 464.447636 -9.272016)
				(arc
					(start 469.799924 -9.272016)
					(mid 470.854924 -8.83502)
					(end 471.29192 -7.78002)
				)
				(arc
					(start 471.29192 10.40003)
					(mid 470.854924 11.45503)
					(end 469.799924 11.892026)
				)
				(arc
					(start 1.999996 11.892026)
					(mid 0.944996 11.45503)
					(end 0.508 10.40003)
				)
				(arc
					(start 0.508 -7.78002)
					(mid 0.944996 -8.83502)
					(end 1.999996 -9.272016)
				)
				(arc
					(start 9.10209 -9.272016)
					(mid 10.15709 -8.83502)
					(end 10.594086 -7.78002)
				)
				(arc
					(start 10.594086 0.40005)
					(mid 11.328661 2.173471)
					(end 13.102082 2.908046)
				)
				(arc
					(start 81.701894 2.908046)
					(mid 83.475315 2.173471)
					(end 84.20989 0.40005)
				)
				(arc
					(start 84.20989 -7.78002)
					(mid 84.646886 -8.83502)
					(end 85.701886 -9.272016)
				)
				(arc
					(start 122.102118 -9.272016)
					(mid 123.157118 -8.83502)
					(end 123.594114 -7.78002)
				)
				(arc
					(start 123.594114 -4.879848)
					(mid 124.328689 -3.106427)
					(end 126.10211 -2.371852)
				)
				(arc
					(start 194.701922 -2.371852)
					(mid 196.475343 -3.106427)
					(end 197.209918 -4.879848)
				)
				(arc
					(start 197.209918 -7.78002)
					(mid 197.646914 -8.83502)
					(end 198.701914 -9.272016)
				)
				(arc
					(start 223.300036 -9.272016)
					(mid 225.073457 -10.006591)
					(end 225.808032 -11.780012)
				)
				(arc
					(start 225.808032 -33.120076)
					(mid 225.952135 -33.467971)
					(end 226.30003 -33.612074)
				)
				(arc
					(start 255.800098 -33.612074)
					(mid 256.147993 -33.467971)
					(end 256.292096 -33.120076)
				)
				(arc
					(start 256.292096 -11.780012)
					(mid 257.026671 -10.006591)
					(end 258.800092 -9.272016)
				)
				(arc
					(start 383.601976 -9.272016)
					(mid 384.656976 -8.83502)
					(end 385.093972 -7.78002)
				)
				(arc
					(start 385.093972 0.40005)
					(mid 385.828547 2.173471)
					(end 387.601968 2.908046)
				)
				(arc
					(start 456.202034 2.908046)
					(mid 457.975455 2.173471)
					(end 458.71003 0.40005)
				)
				(arc
					(start 458.71003 -7.78002)
					(mid 459.147026 -8.83502)
					(end 460.202026 -9.272016)
				)
				(xy 464.439 -9.272016) (xy 464.439 -12.288012)
				(arc
					(start 458.20203 -12.288012)
					(mid 456.428609 -11.553437)
					(end 455.694034 -9.780016)
				)
				(xy 455.694034 -0.508) (xy 388.109968 -0.508)
				(arc
					(start 388.109968 -9.780016)
					(mid 387.375393 -11.553437)
					(end 385.601972 -12.288012)
				)
				(arc
					(start 260.800088 -12.288012)
					(mid 259.745088 -12.725008)
					(end 259.308092 -13.780008)
				)
				(arc
					(start 259.308092 -34.120074)
					(mid 258.573517 -35.893495)
					(end 256.800096 -36.62807)
				)
				(arc
					(start 225.300032 -36.62807)
					(mid 223.526611 -35.893495)
					(end 222.792036 -34.120074)
				)
				(arc
					(start 222.792036 -13.780008)
					(mid 222.35504 -12.725008)
					(end 221.30004 -12.288012)
				)
				(arc
					(start 196.701918 -12.288012)
					(mid 194.928497 -11.553437)
					(end 194.193922 -9.780016)
				)
				(xy 194.193922 -5.787898) (xy 126.61011 -5.787898)
				(arc
					(start 126.61011 -9.780016)
					(mid 125.875535 -11.553437)
					(end 124.102114 -12.288012)
				)
				(arc
					(start 83.70189 -12.288012)
					(mid 81.928469 -11.553437)
					(end 81.193894 -9.780016)
				)
				(xy 81.193894 -0.508) (xy 13.610082 -0.508)
				(arc
					(start 13.610082 -9.780016)
					(mid 12.875507 -11.553437)
					(end 11.102086 -12.288012)
				)
				(arc
					(start 1.999996 -12.288012)
					(mid 0.944996 -12.725008)
					(end 0.508 -13.780008)
				)
				(arc
					(start 0.508 -77.67193)
					(mid 0.621601 -78.242658)
					(end 0.94488 -78.726538)
				)
				(arc
					(start 1.773428 -79.555086)
					(mid 2.317047 -80.368624)
					(end 2.507996 -81.32826)
				)
				(arc
					(start 2.507996 -403.371812)
					(mid 2.621533 -403.942691)
					(end 2.944876 -404.426674)
				)
				(arc
					(start 6.273292 -407.75509)
					(mid 6.817042 -408.568731)
					(end 7.008114 -409.528518)
				)
				(arc
					(start 7.008114 -439.989976)
					(mid 7.44511 -441.044976)
					(end 8.50011 -441.481972)
				)
				(xy 194.496944 -441.481972)
				(arc
					(start 194.496944 -441.17006)
					(mid 194.792217 -440.457207)
					(end 195.50507 -440.161934)
				)
				(arc
					(start 276.314916 -440.161934)
					(mid 277.027769 -440.457207)
					(end 277.323042 -441.17006)
				)
				(xy 277.323042 -441.481972)
				(arc
					(start 463.300064 -441.481972)
					(mid 464.355064 -441.044976)
					(end 464.79206 -439.989976)
				)
				(xy 464.79206 -418.46881) (xy 467.808056 -418.46881)
				(arc
					(start 467.808056 -439.989976)
					(mid 468.245052 -441.044976)
					(end 469.300052 -441.481972)
				)
				(arc
					(start 471.79992 -441.481972)
					(mid 473.573341 -442.216547)
					(end 474.307916 -443.989968)
				)
			)
		)
	)
	(zone
		(layers "In2.Cu" "In4.Cu" "In6.Cu" "In13.Cu" "In15.Cu")
		(hatch none 0.5)
		(connect_pads
			(clearance 0)
		)
		(min_thickness 0.25)
		(keepout
			(tracks not_allowed)
			(vias allowed)
			(pads allowed)
			(copperpour not_allowed)
			(footprints allowed)
		)
		(placement
			(enabled no)
			(sheetname "")
		)
		(fill yes
			(thermal_gap 0.5)
			(thermal_bridge_width 0.5)
			(island_removal_mode 0)
		)
		(polygon
			(pts
				(arc
					(start 23.49754 -347.8149)
					(mid 16.94434 -347.8149)
					(end 23.49754 -347.8149)
				)
			)
		)
	)
	(zone
		(layers "In2.Cu" "In4.Cu" "In11.Cu" "In13.Cu" "In15.Cu")
		(hatch none 0.5)
		(connect_pads
			(clearance 0)
		)
		(min_thickness 0.25)
		(keepout
			(tracks allowed)
			(vias allowed)
			(pads allowed)
			(copperpour allowed)
			(footprints allowed)
		)
		(placement
			(enabled no)
			(sheetname "")
		)
		(fill yes
			(thermal_gap 0.5)
			(thermal_bridge_width 0.5)
			(island_removal_mode 0)
		)
		(polygon
			(pts
				(xy 75.955906 -296.612564) (xy 75.955906 -226.666044) (xy 76.494386 -226.127564) (xy 76.494386 -223.333564)
				(xy 78.653386 -221.174564) (xy 147.919186 -221.174564) (xy 147.919186 -296.612564)
			)
		)
	)
	(zone
		(layers "In2.Cu" "In6.Cu")
		(hatch none 0.5)
		(connect_pads
			(clearance 0)
		)
		(min_thickness 0.25)
		(keepout
			(tracks not_allowed)
			(vias allowed)
			(pads allowed)
			(copperpour not_allowed)
			(footprints allowed)
		)
		(placement
			(enabled no)
			(sheetname "")
		)
		(fill yes
			(thermal_gap 0.5)
			(thermal_bridge_width 0.5)
			(island_removal_mode 0)
		)
		(polygon
			(pts
				(xy 286.323786 -363.359192) (xy 286.323786 -362.42752) (xy 289.550094 -362.42752) (xy 289.550094 -363.359192)
			)
		)
	)
	(zone
		(layers "In2.Cu" "In8.Cu")
		(hatch none 0.5)
		(connect_pads
			(clearance 0)
		)
		(min_thickness 0.25)
		(keepout
			(tracks not_allowed)
			(vias allowed)
			(pads allowed)
			(copperpour not_allowed)
			(footprints allowed)
		)
		(placement
			(enabled no)
			(sheetname "")
		)
		(fill yes
			(thermal_gap 0.5)
			(thermal_bridge_width 0.5)
			(island_removal_mode 0)
		)
		(polygon
			(pts
				(xy 97.150174 -414.277302) (xy 102.150418 -414.277302) (xy 102.150418 -421.172894) (xy 97.150174 -421.172894)
			)
		)
	)
	(zone
		(layers "In2.Cu" "In8.Cu" "In9.Cu")
		(hatch none 0.5)
		(connect_pads
			(clearance 0)
		)
		(min_thickness 0.25)
		(keepout
			(tracks not_allowed)
			(vias allowed)
			(pads allowed)
			(copperpour not_allowed)
			(footprints allowed)
		)
		(placement
			(enabled no)
			(sheetname "")
		)
		(fill yes
			(thermal_gap 0.5)
			(thermal_bridge_width 0.5)
			(island_removal_mode 0)
		)
		(polygon
			(pts
				(arc
					(start 241.15395 -81.700116)
					(mid 239.615092 -85.415248)
					(end 235.89996 -86.954106)
				)
				(arc
					(start 235.89996 -86.725506)
					(mid 240.92535 -81.700116)
					(end 235.89996 -76.674726)
				)
				(arc
					(start 235.89996 -76.446126)
					(mid 239.615092 -77.984984)
					(end 241.15395 -81.700116)
				)
			)
		)
	)
	(zone
		(layers "In2.Cu" "In8.Cu" "In9.Cu")
		(hatch none 0.5)
		(connect_pads
			(clearance 0)
		)
		(min_thickness 0.25)
		(keepout
			(tracks not_allowed)
			(vias allowed)
			(pads allowed)
			(copperpour not_allowed)
			(footprints allowed)
		)
		(placement
			(enabled no)
			(sheetname "")
		)
		(fill yes
			(thermal_gap 0.5)
			(thermal_bridge_width 0.5)
			(island_removal_mode 0)
		)
		(polygon
			(pts
				(arc
					(start 230.64597 -81.700116)
					(mid 232.184828 -85.415248)
					(end 235.89996 -86.954106)
				)
				(arc
					(start 235.89996 -86.725506)
					(mid 230.87457 -81.700116)
					(end 235.89996 -76.674726)
				)
				(arc
					(start 235.89996 -76.446126)
					(mid 232.184828 -77.984984)
					(end 230.64597 -81.700116)
				)
			)
		)
	)
	(zone
		(layer "In3.Cu")
		(hatch none 0.5)
		(connect_pads
			(clearance 0)
		)
		(min_thickness 0.25)
		(keepout
			(tracks not_allowed)
			(vias allowed)
			(pads allowed)
			(copperpour not_allowed)
			(footprints allowed)
		)
		(placement
			(enabled no)
			(sheetname "")
		)
		(fill
			(thermal_gap 0.5)
			(thermal_bridge_width 0.5)
			(island_removal_mode 0)
		)
		(polygon
			(pts
				(arc
					(start 343.141554 -427.960536)
					(mid 343.163872 -428.014418)
					(end 343.217754 -428.036736)
				)
				(arc
					(start 344.157554 -428.036736)
					(mid 344.211436 -428.014418)
					(end 344.233754 -427.960536)
				)
				(arc
					(start 344.233754 -425.419012)
					(mid 344.211436 -425.36513)
					(end 344.157554 -425.342812)
				)
				(arc
					(start 343.217754 -425.342812)
					(mid 343.163872 -425.36513)
					(end 343.141554 -425.419012)
				)
			)
		)
	)
	(zone
		(layer "In3.Cu")
		(hatch none 0.5)
		(connect_pads
			(clearance 0)
		)
		(min_thickness 0.25)
		(keepout
			(tracks not_allowed)
			(vias allowed)
			(pads allowed)
			(copperpour not_allowed)
			(footprints allowed)
		)
		(placement
			(enabled no)
			(sheetname "")
		)
		(fill
			(thermal_gap 0.5)
			(thermal_bridge_width 0.5)
			(island_removal_mode 0)
		)
		(polygon
			(pts
				(arc
					(start 324.141592 -428.960534)
					(mid 324.16391 -429.014416)
					(end 324.217792 -429.036734)
				)
				(arc
					(start 325.157592 -429.036734)
					(mid 325.211474 -429.014416)
					(end 325.233792 -428.960534)
				)
				(arc
					(start 325.233792 -426.41901)
					(mid 325.211474 -426.365128)
					(end 325.157592 -426.34281)
				)
				(arc
					(start 324.217792 -426.34281)
					(mid 324.16391 -426.365128)
					(end 324.141592 -426.41901)
				)
			)
		)
	)
	(zone
		(layer "In3.Cu")
		(hatch none 0.5)
		(connect_pads
			(clearance 0)
		)
		(min_thickness 0.25)
		(keepout
			(tracks not_allowed)
			(vias allowed)
			(pads allowed)
			(copperpour not_allowed)
			(footprints allowed)
		)
		(placement
			(enabled no)
			(sheetname "")
		)
		(fill
			(thermal_gap 0.5)
			(thermal_bridge_width 0.5)
			(island_removal_mode 0)
		)
		(polygon
			(pts
				(arc
					(start 345.14155 -428.960534)
					(mid 345.163868 -429.014416)
					(end 345.21775 -429.036734)
				)
				(arc
					(start 346.15755 -429.036734)
					(mid 346.211432 -429.014416)
					(end 346.23375 -428.960534)
				)
				(arc
					(start 346.23375 -426.41901)
					(mid 346.211432 -426.365128)
					(end 346.15755 -426.34281)
				)
				(arc
					(start 345.21775 -426.34281)
					(mid 345.163868 -426.365128)
					(end 345.14155 -426.41901)
				)
			)
		)
	)
	(zone
		(layer "In3.Cu")
		(hatch none 0.5)
		(connect_pads
			(clearance 0)
		)
		(min_thickness 0.25)
		(keepout
			(tracks not_allowed)
			(vias allowed)
			(pads allowed)
			(copperpour not_allowed)
			(footprints allowed)
		)
		(placement
			(enabled no)
			(sheetname "")
		)
		(fill
			(thermal_gap 0.5)
			(thermal_bridge_width 0.5)
			(island_removal_mode 0)
		)
		(polygon
			(pts
				(xy 220.033596 -402.70303) (xy 220.033596 -401.13204) (xy 221.699328 -401.13204) (xy 221.699328 -402.70303)
			)
		)
	)
	(zone
		(layer "In3.Cu")
		(hatch none 0.5)
		(connect_pads
			(clearance 0)
		)
		(min_thickness 0.25)
		(keepout
			(tracks not_allowed)
			(vias allowed)
			(pads allowed)
			(copperpour not_allowed)
			(footprints allowed)
		)
		(placement
			(enabled no)
			(sheetname "")
		)
		(fill
			(thermal_gap 0.5)
			(thermal_bridge_width 0.5)
			(island_removal_mode 0)
		)
		(polygon
			(pts
				(arc
					(start 328.141584 -428.960534)
					(mid 328.163902 -429.014416)
					(end 328.217784 -429.036734)
				)
				(arc
					(start 329.157584 -429.036734)
					(mid 329.211466 -429.014416)
					(end 329.233784 -428.960534)
				)
				(arc
					(start 329.233784 -426.41901)
					(mid 329.211466 -426.365128)
					(end 329.157584 -426.34281)
				)
				(arc
					(start 328.217784 -426.34281)
					(mid 328.163902 -426.365128)
					(end 328.141584 -426.41901)
				)
			)
		)
	)
	(zone
		(layer "In3.Cu")
		(hatch none 0.5)
		(connect_pads
			(clearance 0)
		)
		(min_thickness 0.25)
		(keepout
			(tracks not_allowed)
			(vias allowed)
			(pads allowed)
			(copperpour not_allowed)
			(footprints allowed)
		)
		(placement
			(enabled no)
			(sheetname "")
		)
		(fill
			(thermal_gap 0.5)
			(thermal_bridge_width 0.5)
			(island_removal_mode 0)
		)
		(polygon
			(pts
				(xy 209.357722 -402.759672) (xy 209.357722 -401.11934) (xy 211.0613 -401.11934) (xy 211.0613 -402.759672)
			)
		)
	)
	(zone
		(layer "In3.Cu")
		(hatch none 0.5)
		(connect_pads
			(clearance 0)
		)
		(min_thickness 0.25)
		(keepout
			(tracks not_allowed)
			(vias allowed)
			(pads allowed)
			(copperpour not_allowed)
			(footprints allowed)
		)
		(placement
			(enabled no)
			(sheetname "")
		)
		(fill
			(thermal_gap 0.5)
			(thermal_bridge_width 0.5)
			(island_removal_mode 0)
		)
		(polygon
			(pts
				(arc
					(start 320.1416 -428.960534)
					(mid 320.163918 -429.014416)
					(end 320.2178 -429.036734)
				)
				(arc
					(start 321.1576 -429.036734)
					(mid 321.211482 -429.014416)
					(end 321.2338 -428.960534)
				)
				(arc
					(start 321.2338 -426.41901)
					(mid 321.211482 -426.365128)
					(end 321.1576 -426.34281)
				)
				(arc
					(start 320.2178 -426.34281)
					(mid 320.163918 -426.365128)
					(end 320.1416 -426.41901)
				)
			)
		)
	)
	(zone
		(layer "In3.Cu")
		(hatch none 0.5)
		(connect_pads
			(clearance 0)
		)
		(min_thickness 0.25)
		(keepout
			(tracks not_allowed)
			(vias allowed)
			(pads allowed)
			(copperpour not_allowed)
			(footprints allowed)
		)
		(placement
			(enabled no)
			(sheetname "")
		)
		(fill
			(thermal_gap 0.5)
			(thermal_bridge_width 0.5)
			(island_removal_mode 0)
		)
		(polygon
			(pts
				(xy 185.42 -402.71573) (xy 185.42 -401.100544) (xy 187.167774 -401.100544) (xy 187.167774 -402.71573)
			)
		)
	)
	(zone
		(layer "In3.Cu")
		(hatch none 0.5)
		(connect_pads
			(clearance 0)
		)
		(min_thickness 0.25)
		(keepout
			(tracks not_allowed)
			(vias allowed)
			(pads allowed)
			(copperpour not_allowed)
			(footprints allowed)
		)
		(placement
			(enabled no)
			(sheetname "")
		)
		(fill
			(thermal_gap 0.5)
			(thermal_bridge_width 0.5)
			(island_removal_mode 0)
		)
		(polygon
			(pts
				(xy 230.708962 -402.71573) (xy 230.708962 -401.100544) (xy 232.355898 -401.100544) (xy 232.355898 -402.71573)
			)
		)
	)
	(zone
		(layer "In3.Cu")
		(hatch none 0.5)
		(connect_pads
			(clearance 0)
		)
		(min_thickness 0.25)
		(keepout
			(tracks not_allowed)
			(vias allowed)
			(pads allowed)
			(copperpour not_allowed)
			(footprints allowed)
		)
		(placement
			(enabled no)
			(sheetname "")
		)
		(fill
			(thermal_gap 0.5)
			(thermal_bridge_width 0.5)
			(island_removal_mode 0)
		)
		(polygon
			(pts
				(arc
					(start 341.141558 -428.960534)
					(mid 341.163876 -429.014416)
					(end 341.217758 -429.036734)
				)
				(arc
					(start 342.157558 -429.036734)
					(mid 342.21144 -429.014416)
					(end 342.233758 -428.960534)
				)
				(arc
					(start 342.233758 -426.41901)
					(mid 342.21144 -426.365128)
					(end 342.157558 -426.34281)
				)
				(arc
					(start 341.217758 -426.34281)
					(mid 341.163876 -426.365128)
					(end 341.141558 -426.41901)
				)
			)
		)
	)
	(zone
		(layer "In3.Cu")
		(hatch none 0.5)
		(connect_pads
			(clearance 0)
		)
		(min_thickness 0.25)
		(keepout
			(tracks not_allowed)
			(vias allowed)
			(pads allowed)
			(copperpour not_allowed)
			(footprints allowed)
		)
		(placement
			(enabled no)
			(sheetname "")
		)
		(fill
			(thermal_gap 0.5)
			(thermal_bridge_width 0.5)
			(island_removal_mode 0)
		)
		(polygon
			(pts
				(arc
					(start 316.141608 -428.960534)
					(mid 316.163926 -429.014416)
					(end 316.217808 -429.036734)
				)
				(arc
					(start 317.157608 -429.036734)
					(mid 317.21149 -429.014416)
					(end 317.233808 -428.960534)
				)
				(arc
					(start 317.233808 -426.41901)
					(mid 317.21149 -426.365128)
					(end 317.157608 -426.34281)
				)
				(arc
					(start 316.217808 -426.34281)
					(mid 316.163926 -426.365128)
					(end 316.141608 -426.41901)
				)
			)
		)
	)
	(zone
		(layer "In3.Cu")
		(hatch none 0.5)
		(connect_pads
			(clearance 0)
		)
		(min_thickness 0.25)
		(keepout
			(tracks not_allowed)
			(vias allowed)
			(pads allowed)
			(copperpour not_allowed)
			(footprints allowed)
		)
		(placement
			(enabled no)
			(sheetname "")
		)
		(fill
			(thermal_gap 0.5)
			(thermal_bridge_width 0.5)
			(island_removal_mode 0)
		)
		(polygon
			(pts
				(arc
					(start 331.141578 -427.960536)
					(mid 331.163896 -428.014418)
					(end 331.217778 -428.036736)
				)
				(arc
					(start 332.157578 -428.036736)
					(mid 332.21146 -428.014418)
					(end 332.233778 -427.960536)
				)
				(arc
					(start 332.233778 -425.419012)
					(mid 332.21146 -425.36513)
					(end 332.157578 -425.342812)
				)
				(arc
					(start 331.217778 -425.342812)
					(mid 331.163896 -425.36513)
					(end 331.141578 -425.419012)
				)
			)
		)
	)
	(zone
		(layer "In3.Cu")
		(hatch none 0.5)
		(connect_pads
			(clearance 0)
		)
		(min_thickness 0.25)
		(keepout
			(tracks not_allowed)
			(vias allowed)
			(pads allowed)
			(copperpour not_allowed)
			(footprints allowed)
		)
		(placement
			(enabled no)
			(sheetname "")
		)
		(fill
			(thermal_gap 0.5)
			(thermal_bridge_width 0.5)
			(island_removal_mode 0)
		)
		(polygon
			(pts
				(arc
					(start 337.141566 -428.960534)
					(mid 337.163884 -429.014416)
					(end 337.217766 -429.036734)
				)
				(arc
					(start 338.157566 -429.036734)
					(mid 338.211448 -429.014416)
					(end 338.233766 -428.960534)
				)
				(arc
					(start 338.233766 -426.41901)
					(mid 338.211448 -426.365128)
					(end 338.157566 -426.34281)
				)
				(arc
					(start 337.217766 -426.34281)
					(mid 337.163884 -426.365128)
					(end 337.141566 -426.41901)
				)
			)
		)
	)
	(zone
		(layer "In3.Cu")
		(hatch none 0.5)
		(connect_pads
			(clearance 0)
		)
		(min_thickness 0.25)
		(keepout
			(tracks not_allowed)
			(vias allowed)
			(pads allowed)
			(copperpour not_allowed)
			(footprints allowed)
		)
		(placement
			(enabled no)
			(sheetname "")
		)
		(fill
			(thermal_gap 0.5)
			(thermal_bridge_width 0.5)
			(island_removal_mode 0)
		)
		(polygon
			(pts
				(arc
					(start 318.141604 -427.960536)
					(mid 318.163922 -428.014418)
					(end 318.217804 -428.036736)
				)
				(arc
					(start 319.157604 -428.036736)
					(mid 319.211486 -428.014418)
					(end 319.233804 -427.960536)
				)
				(arc
					(start 319.233804 -425.419012)
					(mid 319.211486 -425.36513)
					(end 319.157604 -425.342812)
				)
				(arc
					(start 318.217804 -425.342812)
					(mid 318.163922 -425.36513)
					(end 318.141604 -425.419012)
				)
			)
		)
	)
	(zone
		(layer "In3.Cu")
		(hatch none 0.5)
		(connect_pads
			(clearance 0)
		)
		(min_thickness 0.25)
		(keepout
			(tracks not_allowed)
			(vias allowed)
			(pads allowed)
			(copperpour not_allowed)
			(footprints allowed)
		)
		(placement
			(enabled no)
			(sheetname "")
		)
		(fill
			(thermal_gap 0.5)
			(thermal_bridge_width 0.5)
			(island_removal_mode 0)
		)
		(polygon
			(pts
				(arc
					(start 339.141562 -427.960536)
					(mid 339.16388 -428.014418)
					(end 339.217762 -428.036736)
				)
				(arc
					(start 340.157562 -428.036736)
					(mid 340.211444 -428.014418)
					(end 340.233762 -427.960536)
				)
				(arc
					(start 340.233762 -425.419012)
					(mid 340.211444 -425.36513)
					(end 340.157562 -425.342812)
				)
				(arc
					(start 339.217762 -425.342812)
					(mid 339.16388 -425.36513)
					(end 339.141562 -425.419012)
				)
			)
		)
	)
	(zone
		(layer "In3.Cu")
		(hatch none 0.5)
		(connect_pads
			(clearance 0)
		)
		(min_thickness 0.25)
		(keepout
			(tracks not_allowed)
			(vias allowed)
			(pads allowed)
			(copperpour not_allowed)
			(footprints allowed)
		)
		(placement
			(enabled no)
			(sheetname "")
		)
		(fill
			(thermal_gap 0.5)
			(thermal_bridge_width 0.5)
			(island_removal_mode 0)
		)
		(polygon
			(pts
				(arc
					(start 335.14157 -427.960536)
					(mid 335.163888 -428.014418)
					(end 335.21777 -428.036736)
				)
				(arc
					(start 336.15757 -428.036736)
					(mid 336.211452 -428.014418)
					(end 336.23377 -427.960536)
				)
				(arc
					(start 336.23377 -425.419012)
					(mid 336.211452 -425.36513)
					(end 336.15757 -425.342812)
				)
				(arc
					(start 335.21777 -425.342812)
					(mid 335.163888 -425.36513)
					(end 335.14157 -425.419012)
				)
			)
		)
	)
	(zone
		(layer "In3.Cu")
		(hatch none 0.5)
		(connect_pads
			(clearance 0)
		)
		(min_thickness 0.25)
		(keepout
			(tracks not_allowed)
			(vias allowed)
			(pads allowed)
			(copperpour not_allowed)
			(footprints allowed)
		)
		(placement
			(enabled no)
			(sheetname "")
		)
		(fill
			(thermal_gap 0.5)
			(thermal_bridge_width 0.5)
			(island_removal_mode 0)
		)
		(polygon
			(pts
				(xy 198.65721 -402.69668) (xy 198.65721 -401.119086) (xy 200.360534 -401.119086) (xy 200.360534 -402.69668)
			)
		)
	)
	(zone
		(layer "In3.Cu")
		(hatch none 0.5)
		(connect_pads
			(clearance 0)
		)
		(min_thickness 0.25)
		(keepout
			(tracks not_allowed)
			(vias allowed)
			(pads allowed)
			(copperpour not_allowed)
			(footprints allowed)
		)
		(placement
			(enabled no)
			(sheetname "")
		)
		(fill
			(thermal_gap 0.5)
			(thermal_bridge_width 0.5)
			(island_removal_mode 0)
		)
		(polygon
			(pts
				(arc
					(start 322.141596 -427.960536)
					(mid 322.163914 -428.014418)
					(end 322.217796 -428.036736)
				)
				(arc
					(start 323.157596 -428.036736)
					(mid 323.211478 -428.014418)
					(end 323.233796 -427.960536)
				)
				(arc
					(start 323.233796 -425.419012)
					(mid 323.211478 -425.36513)
					(end 323.157596 -425.342812)
				)
				(arc
					(start 322.217796 -425.342812)
					(mid 322.163914 -425.36513)
					(end 322.141596 -425.419012)
				)
			)
		)
	)
	(zone
		(layer "In3.Cu")
		(hatch none 0.5)
		(connect_pads
			(clearance 0)
		)
		(min_thickness 0.25)
		(keepout
			(tracks not_allowed)
			(vias allowed)
			(pads allowed)
			(copperpour not_allowed)
			(footprints allowed)
		)
		(placement
			(enabled no)
			(sheetname "")
		)
		(fill
			(thermal_gap 0.5)
			(thermal_bridge_width 0.5)
			(island_removal_mode 0)
		)
		(polygon
			(pts
				(arc
					(start 314.141612 -427.960536)
					(mid 314.16393 -428.014418)
					(end 314.217812 -428.036736)
				)
				(arc
					(start 315.157612 -428.036736)
					(mid 315.211494 -428.014418)
					(end 315.233812 -427.960536)
				)
				(arc
					(start 315.233812 -425.419012)
					(mid 315.211494 -425.36513)
					(end 315.157612 -425.342812)
				)
				(arc
					(start 314.217812 -425.342812)
					(mid 314.16393 -425.36513)
					(end 314.141612 -425.419012)
				)
			)
		)
	)
	(zone
		(layer "In3.Cu")
		(hatch none 0.5)
		(connect_pads
			(clearance 0)
		)
		(min_thickness 0.25)
		(keepout
			(tracks not_allowed)
			(vias allowed)
			(pads allowed)
			(copperpour not_allowed)
			(footprints allowed)
		)
		(placement
			(enabled no)
			(sheetname "")
		)
		(fill
			(thermal_gap 0.5)
			(thermal_bridge_width 0.5)
			(island_removal_mode 0)
		)
		(polygon
			(pts
				(arc
					(start 326.141588 -427.960536)
					(mid 326.163906 -428.014418)
					(end 326.217788 -428.036736)
				)
				(arc
					(start 327.157588 -428.036736)
					(mid 327.21147 -428.014418)
					(end 327.233788 -427.960536)
				)
				(arc
					(start 327.233788 -425.419012)
					(mid 327.21147 -425.36513)
					(end 327.157588 -425.342812)
				)
				(arc
					(start 326.217788 -425.342812)
					(mid 326.163906 -425.36513)
					(end 326.141588 -425.419012)
				)
			)
		)
	)
	(zone
		(layer "In3.Cu")
		(hatch none 0.5)
		(connect_pads
			(clearance 0)
		)
		(min_thickness 0.25)
		(keepout
			(tracks not_allowed)
			(vias allowed)
			(pads allowed)
			(copperpour not_allowed)
			(footprints allowed)
		)
		(placement
			(enabled no)
			(sheetname "")
		)
		(fill
			(thermal_gap 0.5)
			(thermal_bridge_width 0.5)
			(island_removal_mode 0)
		)
		(polygon
			(pts
				(arc
					(start 333.141574 -428.960534)
					(mid 333.163892 -429.014416)
					(end 333.217774 -429.036734)
				)
				(arc
					(start 334.157574 -429.036734)
					(mid 334.211456 -429.014416)
					(end 334.233774 -428.960534)
				)
				(arc
					(start 334.233774 -426.41901)
					(mid 334.211456 -426.365128)
					(end 334.157574 -426.34281)
				)
				(arc
					(start 333.217774 -426.34281)
					(mid 333.163892 -426.365128)
					(end 333.141574 -426.41901)
				)
			)
		)
	)
	(zone
		(layers "In3.Cu" "In5.Cu")
		(hatch none 0.5)
		(connect_pads
			(clearance 0)
		)
		(min_thickness 0.25)
		(keepout
			(tracks not_allowed)
			(vias allowed)
			(pads allowed)
			(copperpour not_allowed)
			(footprints allowed)
		)
		(placement
			(enabled no)
			(sheetname "")
		)
		(fill yes
			(thermal_gap 0.5)
			(thermal_bridge_width 0.5)
			(island_removal_mode 0)
		)
		(polygon
			(pts
				(arc
					(start 257.391408 -386.86232)
					(mid 255.613408 -386.86232)
					(end 257.391408 -386.86232)
				)
			)
		)
	)
	(zone
		(layers "In3.Cu" "In5.Cu")
		(hatch none 0.5)
		(connect_pads
			(clearance 0)
		)
		(min_thickness 0.25)
		(keepout
			(tracks not_allowed)
			(vias allowed)
			(pads allowed)
			(copperpour not_allowed)
			(footprints allowed)
		)
		(placement
			(enabled no)
			(sheetname "")
		)
		(fill yes
			(thermal_gap 0.5)
			(thermal_bridge_width 0.5)
			(island_removal_mode 0)
		)
		(polygon
			(pts
				(arc
					(start 269.39494 -389.3439)
					(mid 267.61694 -389.3439)
					(end 269.39494 -389.3439)
				)
			)
		)
	)
	(zone
		(layers "In3.Cu" "In5.Cu")
		(hatch none 0.5)
		(connect_pads
			(clearance 0)
		)
		(min_thickness 0.25)
		(keepout
			(tracks not_allowed)
			(vias allowed)
			(pads allowed)
			(copperpour not_allowed)
			(footprints allowed)
		)
		(placement
			(enabled no)
			(sheetname "")
		)
		(fill yes
			(thermal_gap 0.5)
			(thermal_bridge_width 0.5)
			(island_removal_mode 0)
		)
		(polygon
			(pts
				(arc
					(start 277.0632 -389.29564)
					(mid 275.2852 -389.29564)
					(end 277.0632 -389.29564)
				)
			)
		)
	)
	(zone
		(layers "In3.Cu" "In5.Cu")
		(hatch none 0.5)
		(connect_pads
			(clearance 0)
		)
		(min_thickness 0.25)
		(keepout
			(tracks not_allowed)
			(vias allowed)
			(pads allowed)
			(copperpour not_allowed)
			(footprints allowed)
		)
		(placement
			(enabled no)
			(sheetname "")
		)
		(fill yes
			(thermal_gap 0.5)
			(thermal_bridge_width 0.5)
			(island_removal_mode 0)
		)
		(polygon
			(pts
				(arc
					(start 260.58876 -389.36422)
					(mid 258.81076 -389.36422)
					(end 260.58876 -389.36422)
				)
			)
		)
	)
	(zone
		(layers "In3.Cu" "In5.Cu")
		(hatch none 0.5)
		(connect_pads
			(clearance 0)
		)
		(min_thickness 0.25)
		(keepout
			(tracks not_allowed)
			(vias allowed)
			(pads allowed)
			(copperpour not_allowed)
			(footprints allowed)
		)
		(placement
			(enabled no)
			(sheetname "")
		)
		(fill yes
			(thermal_gap 0.5)
			(thermal_bridge_width 0.5)
			(island_removal_mode 0)
		)
		(polygon
			(pts
				(arc
					(start 251.91212 -389.32104)
					(mid 250.13412 -389.32104)
					(end 251.91212 -389.32104)
				)
			)
		)
	)
	(zone
		(layers "In3.Cu" "In5.Cu")
		(hatch none 0.5)
		(connect_pads
			(clearance 0)
		)
		(min_thickness 0.25)
		(keepout
			(tracks not_allowed)
			(vias allowed)
			(pads allowed)
			(copperpour not_allowed)
			(footprints allowed)
		)
		(placement
			(enabled no)
			(sheetname "")
		)
		(fill yes
			(thermal_gap 0.5)
			(thermal_bridge_width 0.5)
			(island_removal_mode 0)
		)
		(polygon
			(pts
				(arc
					(start 263.326372 -386.86232)
					(mid 261.548372 -386.86232)
					(end 263.326372 -386.86232)
				)
			)
		)
	)
	(zone
		(layers "In3.Cu" "In5.Cu")
		(hatch none 0.5)
		(connect_pads
			(clearance 0)
		)
		(min_thickness 0.25)
		(keepout
			(tracks not_allowed)
			(vias allowed)
			(pads allowed)
			(copperpour not_allowed)
			(footprints allowed)
		)
		(placement
			(enabled no)
			(sheetname "")
		)
		(fill yes
			(thermal_gap 0.5)
			(thermal_bridge_width 0.5)
			(island_removal_mode 0)
		)
		(polygon
			(pts
				(arc
					(start 257.391408 -386.10032)
					(mid 255.613408 -386.10032)
					(end 257.391408 -386.10032)
				)
			)
		)
	)
	(zone
		(layers "In3.Cu" "In5.Cu")
		(hatch none 0.5)
		(connect_pads
			(clearance 0)
		)
		(min_thickness 0.25)
		(keepout
			(tracks not_allowed)
			(vias allowed)
			(pads allowed)
			(copperpour not_allowed)
			(footprints allowed)
		)
		(placement
			(enabled no)
			(sheetname "")
		)
		(fill yes
			(thermal_gap 0.5)
			(thermal_bridge_width 0.5)
			(island_removal_mode 0)
		)
		(polygon
			(pts
				(arc
					(start 254.96012 -389.32104)
					(mid 253.18212 -389.32104)
					(end 254.96012 -389.32104)
				)
			)
		)
	)
	(zone
		(layers "In3.Cu" "In5.Cu")
		(hatch none 0.5)
		(connect_pads
			(clearance 0)
		)
		(min_thickness 0.25)
		(keepout
			(tracks not_allowed)
			(vias allowed)
			(pads allowed)
			(copperpour not_allowed)
			(footprints allowed)
		)
		(placement
			(enabled no)
			(sheetname "")
		)
		(fill yes
			(thermal_gap 0.5)
			(thermal_bridge_width 0.5)
			(island_removal_mode 0)
		)
		(polygon
			(pts
				(arc
					(start 270.15694 -389.3439)
					(mid 268.37894 -389.3439)
					(end 270.15694 -389.3439)
				)
			)
		)
	)
	(zone
		(layers "In3.Cu" "In5.Cu")
		(hatch none 0.5)
		(connect_pads
			(clearance 0)
		)
		(min_thickness 0.25)
		(keepout
			(tracks not_allowed)
			(vias allowed)
			(pads allowed)
			(copperpour not_allowed)
			(footprints allowed)
		)
		(placement
			(enabled no)
			(sheetname "")
		)
		(fill yes
			(thermal_gap 0.5)
			(thermal_bridge_width 0.5)
			(island_removal_mode 0)
		)
		(polygon
			(pts
				(arc
					(start 245.52148 -386.86232)
					(mid 243.74348 -386.86232)
					(end 245.52148 -386.86232)
				)
			)
		)
	)
	(zone
		(layers "In3.Cu" "In5.Cu")
		(hatch none 0.5)
		(connect_pads
			(clearance 0)
		)
		(min_thickness 0.25)
		(keepout
			(tracks not_allowed)
			(vias allowed)
			(pads allowed)
			(copperpour not_allowed)
			(footprints allowed)
		)
		(placement
			(enabled no)
			(sheetname "")
		)
		(fill yes
			(thermal_gap 0.5)
			(thermal_bridge_width 0.5)
			(island_removal_mode 0)
		)
		(polygon
			(pts
				(arc
					(start 269.261336 -386.10032)
					(mid 267.483336 -386.10032)
					(end 269.261336 -386.10032)
				)
			)
		)
	)
	(zone
		(layers "In3.Cu" "In5.Cu")
		(hatch none 0.5)
		(connect_pads
			(clearance 0)
		)
		(min_thickness 0.25)
		(keepout
			(tracks not_allowed)
			(vias allowed)
			(pads allowed)
			(copperpour not_allowed)
			(footprints allowed)
		)
		(placement
			(enabled no)
			(sheetname "")
		)
		(fill yes
			(thermal_gap 0.5)
			(thermal_bridge_width 0.5)
			(island_removal_mode 0)
		)
		(polygon
			(pts
				(arc
					(start 251.456444 -387.62432)
					(mid 249.678444 -387.62432)
					(end 251.456444 -387.62432)
				)
			)
		)
	)
	(zone
		(layers "In3.Cu" "In5.Cu")
		(hatch none 0.5)
		(connect_pads
			(clearance 0)
		)
		(min_thickness 0.25)
		(keepout
			(tracks not_allowed)
			(vias allowed)
			(pads allowed)
			(copperpour not_allowed)
			(footprints allowed)
		)
		(placement
			(enabled no)
			(sheetname "")
		)
		(fill yes
			(thermal_gap 0.5)
			(thermal_bridge_width 0.5)
			(island_removal_mode 0)
		)
		(polygon
			(pts
				(arc
					(start 277.8252 -389.29564)
					(mid 276.0472 -389.29564)
					(end 277.8252 -389.29564)
				)
			)
		)
	)
	(zone
		(layers "In3.Cu" "In5.Cu")
		(hatch none 0.5)
		(connect_pads
			(clearance 0)
		)
		(min_thickness 0.25)
		(keepout
			(tracks not_allowed)
			(vias allowed)
			(pads allowed)
			(copperpour not_allowed)
			(footprints allowed)
		)
		(placement
			(enabled no)
			(sheetname "")
		)
		(fill yes
			(thermal_gap 0.5)
			(thermal_bridge_width 0.5)
			(island_removal_mode 0)
		)
		(polygon
			(pts
				(arc
					(start 251.456444 -386.86232)
					(mid 249.678444 -386.86232)
					(end 251.456444 -386.86232)
				)
			)
		)
	)
	(zone
		(layers "In3.Cu" "In5.Cu")
		(hatch none 0.5)
		(connect_pads
			(clearance 0)
		)
		(min_thickness 0.25)
		(keepout
			(tracks not_allowed)
			(vias allowed)
			(pads allowed)
			(copperpour not_allowed)
			(footprints allowed)
		)
		(placement
			(enabled no)
			(sheetname "")
		)
		(fill yes
			(thermal_gap 0.5)
			(thermal_bridge_width 0.5)
			(island_removal_mode 0)
		)
		(polygon
			(pts
				(arc
					(start 268.63294 -389.3439)
					(mid 266.85494 -389.3439)
					(end 268.63294 -389.3439)
				)
			)
		)
	)
	(zone
		(layers "In3.Cu" "In5.Cu")
		(hatch none 0.5)
		(connect_pads
			(clearance 0)
		)
		(min_thickness 0.25)
		(keepout
			(tracks not_allowed)
			(vias allowed)
			(pads allowed)
			(copperpour not_allowed)
			(footprints allowed)
		)
		(placement
			(enabled no)
			(sheetname "")
		)
		(fill yes
			(thermal_gap 0.5)
			(thermal_bridge_width 0.5)
			(island_removal_mode 0)
		)
		(polygon
			(pts
				(arc
					(start 253.43612 -389.32104)
					(mid 251.65812 -389.32104)
					(end 253.43612 -389.32104)
				)
			)
		)
	)
	(zone
		(layers "In3.Cu" "In5.Cu")
		(hatch none 0.5)
		(connect_pads
			(clearance 0)
		)
		(min_thickness 0.25)
		(keepout
			(tracks not_allowed)
			(vias allowed)
			(pads allowed)
			(copperpour not_allowed)
			(footprints allowed)
		)
		(placement
			(enabled no)
			(sheetname "")
		)
		(fill yes
			(thermal_gap 0.5)
			(thermal_bridge_width 0.5)
			(island_removal_mode 0)
		)
		(polygon
			(pts
				(arc
					(start 262.87476 -389.36422)
					(mid 261.09676 -389.36422)
					(end 262.87476 -389.36422)
				)
			)
		)
	)
	(zone
		(layers "In3.Cu" "In5.Cu")
		(hatch none 0.5)
		(connect_pads
			(clearance 0)
		)
		(min_thickness 0.25)
		(keepout
			(tracks not_allowed)
			(vias allowed)
			(pads allowed)
			(copperpour not_allowed)
			(footprints allowed)
		)
		(placement
			(enabled no)
			(sheetname "")
		)
		(fill yes
			(thermal_gap 0.5)
			(thermal_bridge_width 0.5)
			(island_removal_mode 0)
		)
		(polygon
			(pts
				(arc
					(start 245.8339 -389.32104)
					(mid 244.0559 -389.32104)
					(end 245.8339 -389.32104)
				)
			)
		)
	)
	(zone
		(layers "In3.Cu" "In5.Cu")
		(hatch none 0.5)
		(connect_pads
			(clearance 0)
		)
		(min_thickness 0.25)
		(keepout
			(tracks not_allowed)
			(vias allowed)
			(pads allowed)
			(copperpour not_allowed)
			(footprints allowed)
		)
		(placement
			(enabled no)
			(sheetname "")
		)
		(fill yes
			(thermal_gap 0.5)
			(thermal_bridge_width 0.5)
			(island_removal_mode 0)
		)
		(polygon
			(pts
				(arc
					(start 279.3492 -389.29564)
					(mid 277.5712 -389.29564)
					(end 279.3492 -389.29564)
				)
			)
		)
	)
	(zone
		(layers "In3.Cu" "In5.Cu")
		(hatch none 0.5)
		(connect_pads
			(clearance 0)
		)
		(min_thickness 0.25)
		(keepout
			(tracks not_allowed)
			(vias allowed)
			(pads allowed)
			(copperpour not_allowed)
			(footprints allowed)
		)
		(placement
			(enabled no)
			(sheetname "")
		)
		(fill yes
			(thermal_gap 0.5)
			(thermal_bridge_width 0.5)
			(island_removal_mode 0)
		)
		(polygon
			(pts
				(arc
					(start 254.19812 -389.32104)
					(mid 252.42012 -389.32104)
					(end 254.19812 -389.32104)
				)
			)
		)
	)
	(zone
		(layers "In3.Cu" "In5.Cu")
		(hatch none 0.5)
		(connect_pads
			(clearance 0)
		)
		(min_thickness 0.25)
		(keepout
			(tracks not_allowed)
			(vias allowed)
			(pads allowed)
			(copperpour not_allowed)
			(footprints allowed)
		)
		(placement
			(enabled no)
			(sheetname "")
		)
		(fill yes
			(thermal_gap 0.5)
			(thermal_bridge_width 0.5)
			(island_removal_mode 0)
		)
		(polygon
			(pts
				(arc
					(start 259.82676 -389.36422)
					(mid 258.04876 -389.36422)
					(end 259.82676 -389.36422)
				)
			)
		)
	)
	(zone
		(layers "In3.Cu" "In5.Cu")
		(hatch none 0.5)
		(connect_pads
			(clearance 0)
		)
		(min_thickness 0.25)
		(keepout
			(tracks not_allowed)
			(vias allowed)
			(pads allowed)
			(copperpour not_allowed)
			(footprints allowed)
		)
		(placement
			(enabled no)
			(sheetname "")
		)
		(fill yes
			(thermal_gap 0.5)
			(thermal_bridge_width 0.5)
			(island_removal_mode 0)
		)
		(polygon
			(pts
				(arc
					(start 261.35076 -389.36422)
					(mid 259.57276 -389.36422)
					(end 261.35076 -389.36422)
				)
			)
		)
	)
	(zone
		(layers "In3.Cu" "In5.Cu")
		(hatch none 0.5)
		(connect_pads
			(clearance 0)
		)
		(min_thickness 0.25)
		(keepout
			(tracks not_allowed)
			(vias allowed)
			(pads allowed)
			(copperpour not_allowed)
			(footprints allowed)
		)
		(placement
			(enabled no)
			(sheetname "")
		)
		(fill yes
			(thermal_gap 0.5)
			(thermal_bridge_width 0.5)
			(island_removal_mode 0)
		)
		(polygon
			(pts
				(arc
					(start 269.261336 -387.62432)
					(mid 267.483336 -387.62432)
					(end 269.261336 -387.62432)
				)
			)
		)
	)
	(zone
		(layers "In3.Cu" "In5.Cu")
		(hatch none 0.5)
		(connect_pads
			(clearance 0)
		)
		(min_thickness 0.25)
		(keepout
			(tracks not_allowed)
			(vias allowed)
			(pads allowed)
			(copperpour not_allowed)
			(footprints allowed)
		)
		(placement
			(enabled no)
			(sheetname "")
		)
		(fill yes
			(thermal_gap 0.5)
			(thermal_bridge_width 0.5)
			(island_removal_mode 0)
		)
		(polygon
			(pts
				(arc
					(start 270.91894 -389.3439)
					(mid 269.14094 -389.3439)
					(end 270.91894 -389.3439)
				)
			)
		)
	)
	(zone
		(layers "In3.Cu" "In5.Cu")
		(hatch none 0.5)
		(connect_pads
			(clearance 0)
		)
		(min_thickness 0.25)
		(keepout
			(tracks not_allowed)
			(vias allowed)
			(pads allowed)
			(copperpour not_allowed)
			(footprints allowed)
		)
		(placement
			(enabled no)
			(sheetname "")
		)
		(fill yes
			(thermal_gap 0.5)
			(thermal_bridge_width 0.5)
			(island_removal_mode 0)
		)
		(polygon
			(pts
				(arc
					(start 278.5872 -389.29564)
					(mid 276.8092 -389.29564)
					(end 278.5872 -389.29564)
				)
			)
		)
	)
	(zone
		(layers "In3.Cu" "In5.Cu")
		(hatch none 0.5)
		(connect_pads
			(clearance 0)
		)
		(min_thickness 0.25)
		(keepout
			(tracks not_allowed)
			(vias allowed)
			(pads allowed)
			(copperpour not_allowed)
			(footprints allowed)
		)
		(placement
			(enabled no)
			(sheetname "")
		)
		(fill yes
			(thermal_gap 0.5)
			(thermal_bridge_width 0.5)
			(island_removal_mode 0)
		)
		(polygon
			(pts
				(arc
					(start 251.456444 -386.10032)
					(mid 249.678444 -386.10032)
					(end 251.456444 -386.10032)
				)
			)
		)
	)
	(zone
		(layers "In3.Cu" "In5.Cu")
		(hatch none 0.5)
		(connect_pads
			(clearance 0)
		)
		(min_thickness 0.25)
		(keepout
			(tracks not_allowed)
			(vias allowed)
			(pads allowed)
			(copperpour not_allowed)
			(footprints allowed)
		)
		(placement
			(enabled no)
			(sheetname "")
		)
		(fill yes
			(thermal_gap 0.5)
			(thermal_bridge_width 0.5)
			(island_removal_mode 0)
		)
		(polygon
			(pts
				(arc
					(start 269.261336 -386.86232)
					(mid 267.483336 -386.86232)
					(end 269.261336 -386.86232)
				)
			)
		)
	)
	(zone
		(layers "In3.Cu" "In5.Cu")
		(hatch none 0.5)
		(connect_pads
			(clearance 0)
		)
		(min_thickness 0.25)
		(keepout
			(tracks not_allowed)
			(vias allowed)
			(pads allowed)
			(copperpour not_allowed)
			(footprints allowed)
		)
		(placement
			(enabled no)
			(sheetname "")
		)
		(fill yes
			(thermal_gap 0.5)
			(thermal_bridge_width 0.5)
			(island_removal_mode 0)
		)
		(polygon
			(pts
				(arc
					(start 245.52148 -387.62432)
					(mid 243.74348 -387.62432)
					(end 245.52148 -387.62432)
				)
			)
		)
	)
	(zone
		(layers "In3.Cu" "In5.Cu")
		(hatch none 0.5)
		(connect_pads
			(clearance 0)
		)
		(min_thickness 0.25)
		(keepout
			(tracks not_allowed)
			(vias allowed)
			(pads allowed)
			(copperpour not_allowed)
			(footprints allowed)
		)
		(placement
			(enabled no)
			(sheetname "")
		)
		(fill yes
			(thermal_gap 0.5)
			(thermal_bridge_width 0.5)
			(island_removal_mode 0)
		)
		(polygon
			(pts
				(arc
					(start 246.5959 -389.32104)
					(mid 244.8179 -389.32104)
					(end 246.5959 -389.32104)
				)
			)
		)
	)
	(zone
		(layers "In3.Cu" "In5.Cu")
		(hatch none 0.5)
		(connect_pads
			(clearance 0)
		)
		(min_thickness 0.25)
		(keepout
			(tracks not_allowed)
			(vias allowed)
			(pads allowed)
			(copperpour not_allowed)
			(footprints allowed)
		)
		(placement
			(enabled no)
			(sheetname "")
		)
		(fill yes
			(thermal_gap 0.5)
			(thermal_bridge_width 0.5)
			(island_removal_mode 0)
		)
		(polygon
			(pts
				(arc
					(start 244.3099 -389.32104)
					(mid 242.5319 -389.32104)
					(end 244.3099 -389.32104)
				)
			)
		)
	)
	(zone
		(layers "In3.Cu" "In5.Cu")
		(hatch none 0.5)
		(connect_pads
			(clearance 0)
		)
		(min_thickness 0.25)
		(keepout
			(tracks not_allowed)
			(vias allowed)
			(pads allowed)
			(copperpour not_allowed)
			(footprints allowed)
		)
		(placement
			(enabled no)
			(sheetname "")
		)
		(fill yes
			(thermal_gap 0.5)
			(thermal_bridge_width 0.5)
			(island_removal_mode 0)
		)
		(polygon
			(pts
				(arc
					(start 263.326372 -387.62432)
					(mid 261.548372 -387.62432)
					(end 263.326372 -387.62432)
				)
			)
		)
	)
	(zone
		(layers "In3.Cu" "In5.Cu")
		(hatch none 0.5)
		(connect_pads
			(clearance 0)
		)
		(min_thickness 0.25)
		(keepout
			(tracks not_allowed)
			(vias allowed)
			(pads allowed)
			(copperpour not_allowed)
			(footprints allowed)
		)
		(placement
			(enabled no)
			(sheetname "")
		)
		(fill yes
			(thermal_gap 0.5)
			(thermal_bridge_width 0.5)
			(island_removal_mode 0)
		)
		(polygon
			(pts
				(arc
					(start 252.67412 -389.32104)
					(mid 250.89612 -389.32104)
					(end 252.67412 -389.32104)
				)
			)
		)
	)
	(zone
		(layers "In3.Cu" "In5.Cu")
		(hatch none 0.5)
		(connect_pads
			(clearance 0)
		)
		(min_thickness 0.25)
		(keepout
			(tracks not_allowed)
			(vias allowed)
			(pads allowed)
			(copperpour not_allowed)
			(footprints allowed)
		)
		(placement
			(enabled no)
			(sheetname "")
		)
		(fill yes
			(thermal_gap 0.5)
			(thermal_bridge_width 0.5)
			(island_removal_mode 0)
		)
		(polygon
			(pts
				(arc
					(start 263.326372 -386.10032)
					(mid 261.548372 -386.10032)
					(end 263.326372 -386.10032)
				)
			)
		)
	)
	(zone
		(layers "In3.Cu" "In5.Cu")
		(hatch none 0.5)
		(connect_pads
			(clearance 0)
		)
		(min_thickness 0.25)
		(keepout
			(tracks not_allowed)
			(vias allowed)
			(pads allowed)
			(copperpour not_allowed)
			(footprints allowed)
		)
		(placement
			(enabled no)
			(sheetname "")
		)
		(fill yes
			(thermal_gap 0.5)
			(thermal_bridge_width 0.5)
			(island_removal_mode 0)
		)
		(polygon
			(pts
				(arc
					(start 245.0719 -389.32104)
					(mid 243.2939 -389.32104)
					(end 245.0719 -389.32104)
				)
			)
		)
	)
	(zone
		(layers "In3.Cu" "In5.Cu")
		(hatch none 0.5)
		(connect_pads
			(clearance 0)
		)
		(min_thickness 0.25)
		(keepout
			(tracks not_allowed)
			(vias allowed)
			(pads allowed)
			(copperpour not_allowed)
			(footprints allowed)
		)
		(placement
			(enabled no)
			(sheetname "")
		)
		(fill yes
			(thermal_gap 0.5)
			(thermal_bridge_width 0.5)
			(island_removal_mode 0)
		)
		(polygon
			(pts
				(arc
					(start 245.52148 -386.10032)
					(mid 243.74348 -386.10032)
					(end 245.52148 -386.10032)
				)
			)
		)
	)
	(zone
		(layers "In3.Cu" "In5.Cu")
		(hatch none 0.5)
		(connect_pads
			(clearance 0)
		)
		(min_thickness 0.25)
		(keepout
			(tracks not_allowed)
			(vias allowed)
			(pads allowed)
			(copperpour not_allowed)
			(footprints allowed)
		)
		(placement
			(enabled no)
			(sheetname "")
		)
		(fill yes
			(thermal_gap 0.5)
			(thermal_bridge_width 0.5)
			(island_removal_mode 0)
		)
		(polygon
			(pts
				(arc
					(start 257.391408 -387.62432)
					(mid 255.613408 -387.62432)
					(end 257.391408 -387.62432)
				)
			)
		)
	)
	(zone
		(layers "In3.Cu" "In5.Cu")
		(hatch none 0.5)
		(connect_pads
			(clearance 0)
		)
		(min_thickness 0.25)
		(keepout
			(tracks not_allowed)
			(vias allowed)
			(pads allowed)
			(copperpour not_allowed)
			(footprints allowed)
		)
		(placement
			(enabled no)
			(sheetname "")
		)
		(fill yes
			(thermal_gap 0.5)
			(thermal_bridge_width 0.5)
			(island_removal_mode 0)
		)
		(polygon
			(pts
				(arc
					(start 243.5479 -389.32104)
					(mid 241.7699 -389.32104)
					(end 243.5479 -389.32104)
				)
			)
		)
	)
	(zone
		(layers "In3.Cu" "In5.Cu")
		(hatch none 0.5)
		(connect_pads
			(clearance 0)
		)
		(min_thickness 0.25)
		(keepout
			(tracks not_allowed)
			(vias allowed)
			(pads allowed)
			(copperpour not_allowed)
			(footprints allowed)
		)
		(placement
			(enabled no)
			(sheetname "")
		)
		(fill yes
			(thermal_gap 0.5)
			(thermal_bridge_width 0.5)
			(island_removal_mode 0)
		)
		(polygon
			(pts
				(arc
					(start 240.768124 -389.328914)
					(mid 238.990124 -389.328914)
					(end 240.768124 -389.328914)
				)
			)
		)
	)
	(zone
		(layers "In3.Cu" "In5.Cu")
		(hatch none 0.5)
		(connect_pads
			(clearance 0)
		)
		(min_thickness 0.25)
		(keepout
			(tracks not_allowed)
			(vias allowed)
			(pads allowed)
			(copperpour not_allowed)
			(footprints allowed)
		)
		(placement
			(enabled no)
			(sheetname "")
		)
		(fill yes
			(thermal_gap 0.5)
			(thermal_bridge_width 0.5)
			(island_removal_mode 0)
		)
		(polygon
			(pts
				(arc
					(start 267.87094 -389.3439)
					(mid 266.09294 -389.3439)
					(end 267.87094 -389.3439)
				)
			)
		)
	)
	(zone
		(layers "In3.Cu" "In5.Cu")
		(hatch none 0.5)
		(connect_pads
			(clearance 0)
		)
		(min_thickness 0.25)
		(keepout
			(tracks not_allowed)
			(vias allowed)
			(pads allowed)
			(copperpour not_allowed)
			(footprints allowed)
		)
		(placement
			(enabled no)
			(sheetname "")
		)
		(fill yes
			(thermal_gap 0.5)
			(thermal_bridge_width 0.5)
			(island_removal_mode 0)
		)
		(polygon
			(pts
				(arc
					(start 262.11276 -389.36422)
					(mid 260.33476 -389.36422)
					(end 262.11276 -389.36422)
				)
			)
		)
	)
	(zone
		(layers "In3.Cu" "In5.Cu" "In7.Cu")
		(hatch none 0.5)
		(connect_pads
			(clearance 0)
		)
		(min_thickness 0.25)
		(keepout
			(tracks not_allowed)
			(vias allowed)
			(pads allowed)
			(copperpour not_allowed)
			(footprints allowed)
		)
		(placement
			(enabled no)
			(sheetname "")
		)
		(fill yes
			(thermal_gap 0.5)
			(thermal_bridge_width 0.5)
			(island_removal_mode 0)
		)
		(polygon
			(pts
				(arc
					(start 129.241804 -438.760362)
					(mid 129.264122 -438.814244)
					(end 129.318004 -438.836562)
				)
				(arc
					(start 130.257804 -438.836562)
					(mid 130.311686 -438.814244)
					(end 130.334004 -438.760362)
				)
				(arc
					(start 130.334004 -436.218838)
					(mid 130.311686 -436.164956)
					(end 130.257804 -436.142638)
				)
				(arc
					(start 129.318004 -436.142638)
					(mid 129.264122 -436.164956)
					(end 129.241804 -436.218838)
				)
			)
		)
	)
	(zone
		(layers "In3.Cu" "In5.Cu" "In7.Cu")
		(hatch none 0.5)
		(connect_pads
			(clearance 0)
		)
		(min_thickness 0.25)
		(keepout
			(tracks not_allowed)
			(vias allowed)
			(pads allowed)
			(copperpour not_allowed)
			(footprints allowed)
		)
		(placement
			(enabled no)
			(sheetname "")
		)
		(fill yes
			(thermal_gap 0.5)
			(thermal_bridge_width 0.5)
			(island_removal_mode 0)
		)
		(polygon
			(pts
				(arc
					(start 139.241784 -439.76036)
					(mid 139.264102 -439.814242)
					(end 139.317984 -439.83656)
				)
				(arc
					(start 140.257784 -439.83656)
					(mid 140.311666 -439.814242)
					(end 140.333984 -439.76036)
				)
				(arc
					(start 140.333984 -437.218836)
					(mid 140.311666 -437.164954)
					(end 140.257784 -437.142636)
				)
				(arc
					(start 139.317984 -437.142636)
					(mid 139.264102 -437.164954)
					(end 139.241784 -437.218836)
				)
			)
		)
	)
	(zone
		(layers "In3.Cu" "In5.Cu" "In7.Cu")
		(hatch none 0.5)
		(connect_pads
			(clearance 0)
		)
		(min_thickness 0.25)
		(keepout
			(tracks not_allowed)
			(vias allowed)
			(pads allowed)
			(copperpour not_allowed)
			(footprints allowed)
		)
		(placement
			(enabled no)
			(sheetname "")
		)
		(fill yes
			(thermal_gap 0.5)
			(thermal_bridge_width 0.5)
			(island_removal_mode 0)
		)
		(polygon
			(pts
				(arc
					(start 133.241796 -438.760362)
					(mid 133.264114 -438.814244)
					(end 133.317996 -438.836562)
				)
				(arc
					(start 134.257796 -438.836562)
					(mid 134.311678 -438.814244)
					(end 134.333996 -438.760362)
				)
				(arc
					(start 134.333996 -436.218838)
					(mid 134.311678 -436.164956)
					(end 134.257796 -436.142638)
				)
				(arc
					(start 133.317996 -436.142638)
					(mid 133.264114 -436.164956)
					(end 133.241796 -436.218838)
				)
			)
		)
	)
	(zone
		(layers "In3.Cu" "In5.Cu" "In7.Cu")
		(hatch none 0.5)
		(connect_pads
			(clearance 0)
		)
		(min_thickness 0.25)
		(keepout
			(tracks not_allowed)
			(vias allowed)
			(pads allowed)
			(copperpour not_allowed)
			(footprints allowed)
		)
		(placement
			(enabled no)
			(sheetname "")
		)
		(fill yes
			(thermal_gap 0.5)
			(thermal_bridge_width 0.5)
			(island_removal_mode 0)
		)
		(polygon
			(pts
				(arc
					(start 135.241792 -439.76036)
					(mid 135.26411 -439.814242)
					(end 135.317992 -439.83656)
				)
				(arc
					(start 136.257792 -439.83656)
					(mid 136.311674 -439.814242)
					(end 136.333992 -439.76036)
				)
				(arc
					(start 136.333992 -437.218836)
					(mid 136.311674 -437.164954)
					(end 136.257792 -437.142636)
				)
				(arc
					(start 135.317992 -437.142636)
					(mid 135.26411 -437.164954)
					(end 135.241792 -437.218836)
				)
			)
		)
	)
	(zone
		(layers "In3.Cu" "In5.Cu" "In7.Cu")
		(hatch none 0.5)
		(connect_pads
			(clearance 0)
		)
		(min_thickness 0.25)
		(keepout
			(tracks not_allowed)
			(vias allowed)
			(pads allowed)
			(copperpour not_allowed)
			(footprints allowed)
		)
		(placement
			(enabled no)
			(sheetname "")
		)
		(fill yes
			(thermal_gap 0.5)
			(thermal_bridge_width 0.5)
			(island_removal_mode 0)
		)
		(polygon
			(pts
				(arc
					(start 152.241758 -439.76036)
					(mid 152.264076 -439.814242)
					(end 152.317958 -439.83656)
				)
				(arc
					(start 153.257758 -439.83656)
					(mid 153.31164 -439.814242)
					(end 153.333958 -439.76036)
				)
				(arc
					(start 153.333958 -437.218836)
					(mid 153.31164 -437.164954)
					(end 153.257758 -437.142636)
				)
				(arc
					(start 152.317958 -437.142636)
					(mid 152.264076 -437.164954)
					(end 152.241758 -437.218836)
				)
			)
		)
	)
	(zone
		(layers "In3.Cu" "In5.Cu" "In7.Cu")
		(hatch none 0.5)
		(connect_pads
			(clearance 0)
		)
		(min_thickness 0.25)
		(keepout
			(tracks not_allowed)
			(vias allowed)
			(pads allowed)
			(copperpour not_allowed)
			(footprints allowed)
		)
		(placement
			(enabled no)
			(sheetname "")
		)
		(fill yes
			(thermal_gap 0.5)
			(thermal_bridge_width 0.5)
			(island_removal_mode 0)
		)
		(polygon
			(pts
				(arc
					(start 142.241778 -438.760362)
					(mid 142.264096 -438.814244)
					(end 142.317978 -438.836562)
				)
				(arc
					(start 143.257778 -438.836562)
					(mid 143.31166 -438.814244)
					(end 143.333978 -438.760362)
				)
				(arc
					(start 143.333978 -436.218838)
					(mid 143.31166 -436.164956)
					(end 143.257778 -436.142638)
				)
				(arc
					(start 142.317978 -436.142638)
					(mid 142.264096 -436.164956)
					(end 142.241778 -436.218838)
				)
			)
		)
	)
	(zone
		(layers "In3.Cu" "In5.Cu" "In7.Cu")
		(hatch none 0.5)
		(connect_pads
			(clearance 0)
		)
		(min_thickness 0.25)
		(keepout
			(tracks not_allowed)
			(vias allowed)
			(pads allowed)
			(copperpour not_allowed)
			(footprints allowed)
		)
		(placement
			(enabled no)
			(sheetname "")
		)
		(fill yes
			(thermal_gap 0.5)
			(thermal_bridge_width 0.5)
			(island_removal_mode 0)
		)
		(polygon
			(pts
				(arc
					(start 156.24175 -439.76036)
					(mid 156.264068 -439.814242)
					(end 156.31795 -439.83656)
				)
				(arc
					(start 157.25775 -439.83656)
					(mid 157.311632 -439.814242)
					(end 157.33395 -439.76036)
				)
				(arc
					(start 157.33395 -437.218836)
					(mid 157.311632 -437.164954)
					(end 157.25775 -437.142636)
				)
				(arc
					(start 156.31795 -437.142636)
					(mid 156.264068 -437.164954)
					(end 156.24175 -437.218836)
				)
			)
		)
	)
	(zone
		(layers "In3.Cu" "In5.Cu" "In7.Cu")
		(hatch none 0.5)
		(connect_pads
			(clearance 0)
		)
		(min_thickness 0.25)
		(keepout
			(tracks not_allowed)
			(vias allowed)
			(pads allowed)
			(copperpour not_allowed)
			(footprints allowed)
		)
		(placement
			(enabled no)
			(sheetname "")
		)
		(fill yes
			(thermal_gap 0.5)
			(thermal_bridge_width 0.5)
			(island_removal_mode 0)
		)
		(polygon
			(pts
				(arc
					(start 144.241774 -439.76036)
					(mid 144.264092 -439.814242)
					(end 144.317974 -439.83656)
				)
				(arc
					(start 145.257774 -439.83656)
					(mid 145.311656 -439.814242)
					(end 145.333974 -439.76036)
				)
				(arc
					(start 145.333974 -437.218836)
					(mid 145.311656 -437.164954)
					(end 145.257774 -437.142636)
				)
				(arc
					(start 144.317974 -437.142636)
					(mid 144.264092 -437.164954)
					(end 144.241774 -437.218836)
				)
			)
		)
	)
	(zone
		(layers "In3.Cu" "In5.Cu" "In7.Cu")
		(hatch none 0.5)
		(connect_pads
			(clearance 0)
		)
		(min_thickness 0.25)
		(keepout
			(tracks not_allowed)
			(vias allowed)
			(pads allowed)
			(copperpour not_allowed)
			(footprints allowed)
		)
		(placement
			(enabled no)
			(sheetname "")
		)
		(fill yes
			(thermal_gap 0.5)
			(thermal_bridge_width 0.5)
			(island_removal_mode 0)
		)
		(polygon
			(pts
				(arc
					(start 148.241766 -439.76036)
					(mid 148.264084 -439.814242)
					(end 148.317966 -439.83656)
				)
				(arc
					(start 149.257766 -439.83656)
					(mid 149.311648 -439.814242)
					(end 149.333966 -439.76036)
				)
				(arc
					(start 149.333966 -437.218836)
					(mid 149.311648 -437.164954)
					(end 149.257766 -437.142636)
				)
				(arc
					(start 148.317966 -437.142636)
					(mid 148.264084 -437.164954)
					(end 148.241766 -437.218836)
				)
			)
		)
	)
	(zone
		(layers "In3.Cu" "In5.Cu" "In7.Cu")
		(hatch none 0.5)
		(connect_pads
			(clearance 0)
		)
		(min_thickness 0.25)
		(keepout
			(tracks not_allowed)
			(vias allowed)
			(pads allowed)
			(copperpour not_allowed)
			(footprints allowed)
		)
		(placement
			(enabled no)
			(sheetname "")
		)
		(fill yes
			(thermal_gap 0.5)
			(thermal_bridge_width 0.5)
			(island_removal_mode 0)
		)
		(polygon
			(pts
				(arc
					(start 137.241788 -438.760362)
					(mid 137.264106 -438.814244)
					(end 137.317988 -438.836562)
				)
				(arc
					(start 138.257788 -438.836562)
					(mid 138.31167 -438.814244)
					(end 138.333988 -438.760362)
				)
				(arc
					(start 138.333988 -436.218838)
					(mid 138.31167 -436.164956)
					(end 138.257788 -436.142638)
				)
				(arc
					(start 137.317988 -436.142638)
					(mid 137.264106 -436.164956)
					(end 137.241788 -436.218838)
				)
			)
		)
	)
	(zone
		(layers "In3.Cu" "In5.Cu" "In7.Cu")
		(hatch none 0.5)
		(connect_pads
			(clearance 0)
		)
		(min_thickness 0.25)
		(keepout
			(tracks not_allowed)
			(vias allowed)
			(pads allowed)
			(copperpour not_allowed)
			(footprints allowed)
		)
		(placement
			(enabled no)
			(sheetname "")
		)
		(fill yes
			(thermal_gap 0.5)
			(thermal_bridge_width 0.5)
			(island_removal_mode 0)
		)
		(polygon
			(pts
				(arc
					(start 131.2418 -439.76036)
					(mid 131.264118 -439.814242)
					(end 131.318 -439.83656)
				)
				(arc
					(start 132.2578 -439.83656)
					(mid 132.311682 -439.814242)
					(end 132.334 -439.76036)
				)
				(arc
					(start 132.334 -437.218836)
					(mid 132.311682 -437.164954)
					(end 132.2578 -437.142636)
				)
				(arc
					(start 131.318 -437.142636)
					(mid 131.264118 -437.164954)
					(end 131.2418 -437.218836)
				)
			)
		)
	)
	(zone
		(layers "In3.Cu" "In5.Cu" "In7.Cu")
		(hatch none 0.5)
		(connect_pads
			(clearance 0)
		)
		(min_thickness 0.25)
		(keepout
			(tracks not_allowed)
			(vias allowed)
			(pads allowed)
			(copperpour not_allowed)
			(footprints allowed)
		)
		(placement
			(enabled no)
			(sheetname "")
		)
		(fill yes
			(thermal_gap 0.5)
			(thermal_bridge_width 0.5)
			(island_removal_mode 0)
		)
		(polygon
			(pts
				(arc
					(start 154.241754 -438.760362)
					(mid 154.264072 -438.814244)
					(end 154.317954 -438.836562)
				)
				(arc
					(start 155.257754 -438.836562)
					(mid 155.311636 -438.814244)
					(end 155.333954 -438.760362)
				)
				(arc
					(start 155.333954 -436.218838)
					(mid 155.311636 -436.164956)
					(end 155.257754 -436.142638)
				)
				(arc
					(start 154.317954 -436.142638)
					(mid 154.264072 -436.164956)
					(end 154.241754 -436.218838)
				)
			)
		)
	)
	(zone
		(layers "In3.Cu" "In5.Cu" "In7.Cu")
		(hatch none 0.5)
		(connect_pads
			(clearance 0)
		)
		(min_thickness 0.25)
		(keepout
			(tracks not_allowed)
			(vias allowed)
			(pads allowed)
			(copperpour not_allowed)
			(footprints allowed)
		)
		(placement
			(enabled no)
			(sheetname "")
		)
		(fill yes
			(thermal_gap 0.5)
			(thermal_bridge_width 0.5)
			(island_removal_mode 0)
		)
		(polygon
			(pts
				(arc
					(start 125.241812 -438.760362)
					(mid 125.26413 -438.814244)
					(end 125.318012 -438.836562)
				)
				(arc
					(start 126.257812 -438.836562)
					(mid 126.311694 -438.814244)
					(end 126.334012 -438.760362)
				)
				(arc
					(start 126.334012 -436.218838)
					(mid 126.311694 -436.164956)
					(end 126.257812 -436.142638)
				)
				(arc
					(start 125.318012 -436.142638)
					(mid 125.26413 -436.164956)
					(end 125.241812 -436.218838)
				)
			)
		)
	)
	(zone
		(layers "In3.Cu" "In5.Cu" "In7.Cu")
		(hatch none 0.5)
		(connect_pads
			(clearance 0)
		)
		(min_thickness 0.25)
		(keepout
			(tracks not_allowed)
			(vias allowed)
			(pads allowed)
			(copperpour not_allowed)
			(footprints allowed)
		)
		(placement
			(enabled no)
			(sheetname "")
		)
		(fill yes
			(thermal_gap 0.5)
			(thermal_bridge_width 0.5)
			(island_removal_mode 0)
		)
		(polygon
			(pts
				(arc
					(start 146.24177 -438.760362)
					(mid 146.264088 -438.814244)
					(end 146.31797 -438.836562)
				)
				(arc
					(start 147.25777 -438.836562)
					(mid 147.311652 -438.814244)
					(end 147.33397 -438.760362)
				)
				(arc
					(start 147.33397 -436.218838)
					(mid 147.311652 -436.164956)
					(end 147.25777 -436.142638)
				)
				(arc
					(start 146.31797 -436.142638)
					(mid 146.264088 -436.164956)
					(end 146.24177 -436.218838)
				)
			)
		)
	)
	(zone
		(layers "In3.Cu" "In5.Cu" "In7.Cu")
		(hatch none 0.5)
		(connect_pads
			(clearance 0)
		)
		(min_thickness 0.25)
		(keepout
			(tracks not_allowed)
			(vias allowed)
			(pads allowed)
			(copperpour not_allowed)
			(footprints allowed)
		)
		(placement
			(enabled no)
			(sheetname "")
		)
		(fill yes
			(thermal_gap 0.5)
			(thermal_bridge_width 0.5)
			(island_removal_mode 0)
		)
		(polygon
			(pts
				(arc
					(start 150.241762 -438.760362)
					(mid 150.26408 -438.814244)
					(end 150.317962 -438.836562)
				)
				(arc
					(start 151.257762 -438.836562)
					(mid 151.311644 -438.814244)
					(end 151.333962 -438.760362)
				)
				(arc
					(start 151.333962 -436.218838)
					(mid 151.311644 -436.164956)
					(end 151.257762 -436.142638)
				)
				(arc
					(start 150.317962 -436.142638)
					(mid 150.26408 -436.164956)
					(end 150.241762 -436.218838)
				)
			)
		)
	)
	(zone
		(layers "In3.Cu" "In5.Cu" "In7.Cu")
		(hatch none 0.5)
		(connect_pads
			(clearance 0)
		)
		(min_thickness 0.25)
		(keepout
			(tracks not_allowed)
			(vias allowed)
			(pads allowed)
			(copperpour not_allowed)
			(footprints allowed)
		)
		(placement
			(enabled no)
			(sheetname "")
		)
		(fill yes
			(thermal_gap 0.5)
			(thermal_bridge_width 0.5)
			(island_removal_mode 0)
		)
		(polygon
			(pts
				(arc
					(start 127.241808 -439.76036)
					(mid 127.264126 -439.814242)
					(end 127.318008 -439.83656)
				)
				(arc
					(start 128.257808 -439.83656)
					(mid 128.31169 -439.814242)
					(end 128.334008 -439.76036)
				)
				(arc
					(start 128.334008 -437.218836)
					(mid 128.31169 -437.164954)
					(end 128.257808 -437.142636)
				)
				(arc
					(start 127.318008 -437.142636)
					(mid 127.264126 -437.164954)
					(end 127.241808 -437.218836)
				)
			)
		)
	)
	(zone
		(layers "In3.Cu" "In5.Cu" "In7.Cu" "In8.Cu" "In9.Cu")
		(hatch none 0.5)
		(connect_pads
			(clearance 0)
		)
		(min_thickness 0.25)
		(keepout
			(tracks not_allowed)
			(vias allowed)
			(pads allowed)
			(copperpour not_allowed)
			(footprints allowed)
		)
		(placement
			(enabled no)
			(sheetname "")
		)
		(fill yes
			(thermal_gap 0.5)
			(thermal_bridge_width 0.5)
			(island_removal_mode 0)
		)
		(polygon
			(pts
				(arc
					(start 101.741224 -281.681174)
					(mid 102.046024 -281.376374)
					(end 101.741224 -281.071574)
				)
				(arc
					(start 100.80117 -281.071574)
					(mid 100.49637 -281.376374)
					(end 100.80117 -281.681174)
				)
			)
		)
	)
	(zone
		(layers "In3.Cu" "In5.Cu" "In7.Cu" "In8.Cu" "In9.Cu")
		(hatch none 0.5)
		(connect_pads
			(clearance 0)
		)
		(min_thickness 0.25)
		(keepout
			(tracks not_allowed)
			(vias allowed)
			(pads allowed)
			(copperpour not_allowed)
			(footprints allowed)
		)
		(placement
			(enabled no)
			(sheetname "")
		)
		(fill yes
			(thermal_gap 0.5)
			(thermal_bridge_width 0.5)
			(island_removal_mode 0)
		)
		(polygon
			(pts
				(arc
					(start 104.561132 -286.54121)
					(mid 104.865932 -286.23641)
					(end 104.561132 -285.93161)
				)
				(arc
					(start 103.621078 -285.93161)
					(mid 103.316278 -286.23641)
					(end 103.621078 -286.54121)
				)
			)
		)
	)
	(zone
		(layers "In3.Cu" "In5.Cu" "In7.Cu" "In8.Cu" "In9.Cu")
		(hatch none 0.5)
		(connect_pads
			(clearance 0)
		)
		(min_thickness 0.25)
		(keepout
			(tracks not_allowed)
			(vias allowed)
			(pads allowed)
			(copperpour not_allowed)
			(footprints allowed)
		)
		(placement
			(enabled no)
			(sheetname "")
		)
		(fill yes
			(thermal_gap 0.5)
			(thermal_bridge_width 0.5)
			(island_removal_mode 0)
		)
		(polygon
			(pts
				(arc
					(start 98.921062 -281.681174)
					(mid 99.225862 -281.376374)
					(end 98.921062 -281.071574)
				)
				(arc
					(start 97.981008 -281.071574)
					(mid 97.676208 -281.376374)
					(end 97.981008 -281.681174)
				)
			)
		)
	)
	(zone
		(layers "In3.Cu" "In5.Cu" "In7.Cu" "In8.Cu" "In9.Cu")
		(hatch none 0.5)
		(connect_pads
			(clearance 0)
		)
		(min_thickness 0.25)
		(keepout
			(tracks not_allowed)
			(vias allowed)
			(pads allowed)
			(copperpour not_allowed)
			(footprints allowed)
		)
		(placement
			(enabled no)
			(sheetname "")
		)
		(fill yes
			(thermal_gap 0.5)
			(thermal_bridge_width 0.5)
			(island_removal_mode 0)
		)
		(polygon
			(pts
				(arc
					(start 357.671116 -282.490926)
					(mid 357.975916 -282.186126)
					(end 357.671116 -281.881326)
				)
				(arc
					(start 356.731062 -281.881326)
					(mid 356.426262 -282.186126)
					(end 356.731062 -282.490926)
				)
			)
		)
	)
	(zone
		(layers "In3.Cu" "In5.Cu" "In7.Cu" "In8.Cu" "In9.Cu")
		(hatch none 0.5)
		(connect_pads
			(clearance 0)
		)
		(min_thickness 0.25)
		(keepout
			(tracks not_allowed)
			(vias allowed)
			(pads allowed)
			(copperpour not_allowed)
			(footprints allowed)
		)
		(placement
			(enabled no)
			(sheetname "")
		)
		(fill yes
			(thermal_gap 0.5)
			(thermal_bridge_width 0.5)
			(island_removal_mode 0)
		)
		(polygon
			(pts
				(arc
					(start 109.731048 -285.731204)
					(mid 110.035848 -285.426404)
					(end 109.731048 -285.121604)
				)
				(arc
					(start 108.790994 -285.121604)
					(mid 108.486194 -285.426404)
					(end 108.790994 -285.731204)
				)
			)
		)
	)
	(zone
		(layers "In3.Cu" "In5.Cu" "In7.Cu" "In8.Cu" "In9.Cu")
		(hatch none 0.5)
		(connect_pads
			(clearance 0)
		)
		(min_thickness 0.25)
		(keepout
			(tracks not_allowed)
			(vias allowed)
			(pads allowed)
			(copperpour not_allowed)
			(footprints allowed)
		)
		(placement
			(enabled no)
			(sheetname "")
		)
		(fill yes
			(thermal_gap 0.5)
			(thermal_bridge_width 0.5)
			(island_removal_mode 0)
		)
		(polygon
			(pts
				(arc
					(start 346.86113 -284.920944)
					(mid 347.16593 -284.616144)
					(end 346.86113 -284.311344)
				)
				(arc
					(start 345.921076 -284.311344)
					(mid 345.616276 -284.616144)
					(end 345.921076 -284.920944)
				)
			)
		)
	)
	(zone
		(layers "In3.Cu" "In5.Cu" "In7.Cu" "In8.Cu" "In9.Cu")
		(hatch none 0.5)
		(connect_pads
			(clearance 0)
		)
		(min_thickness 0.25)
		(keepout
			(tracks not_allowed)
			(vias allowed)
			(pads allowed)
			(copperpour not_allowed)
			(footprints allowed)
		)
		(placement
			(enabled no)
			(sheetname "")
		)
		(fill yes
			(thermal_gap 0.5)
			(thermal_bridge_width 0.5)
			(island_removal_mode 0)
		)
		(polygon
			(pts
				(arc
					(start 98.921062 -283.301186)
					(mid 99.225862 -282.996386)
					(end 98.921062 -282.691586)
				)
				(arc
					(start 97.981008 -282.691586)
					(mid 97.676208 -282.996386)
					(end 97.981008 -283.301186)
				)
			)
		)
	)
	(zone
		(layers "In3.Cu" "In5.Cu" "In7.Cu" "In8.Cu" "In9.Cu")
		(hatch none 0.5)
		(connect_pads
			(clearance 0)
		)
		(min_thickness 0.25)
		(keepout
			(tracks not_allowed)
			(vias allowed)
			(pads allowed)
			(copperpour not_allowed)
			(footprints allowed)
		)
		(placement
			(enabled no)
			(sheetname "")
		)
		(fill yes
			(thermal_gap 0.5)
			(thermal_bridge_width 0.5)
			(island_removal_mode 0)
		)
		(polygon
			(pts
				(arc
					(start 101.741224 -283.301186)
					(mid 102.046024 -282.996386)
					(end 101.741224 -282.691586)
				)
				(arc
					(start 100.80117 -282.691586)
					(mid 100.49637 -282.996386)
					(end 100.80117 -283.301186)
				)
			)
		)
	)
	(zone
		(layers "In3.Cu" "In5.Cu" "In7.Cu" "In8.Cu" "In9.Cu")
		(hatch none 0.5)
		(connect_pads
			(clearance 0)
		)
		(min_thickness 0.25)
		(keepout
			(tracks not_allowed)
			(vias allowed)
			(pads allowed)
			(copperpour not_allowed)
			(footprints allowed)
		)
		(placement
			(enabled no)
			(sheetname "")
		)
		(fill yes
			(thermal_gap 0.5)
			(thermal_bridge_width 0.5)
			(island_removal_mode 0)
		)
		(polygon
			(pts
				(arc
					(start 101.741224 -286.54121)
					(mid 102.046024 -286.23641)
					(end 101.741224 -285.93161)
				)
				(arc
					(start 100.80117 -285.93161)
					(mid 100.49637 -286.23641)
					(end 100.80117 -286.54121)
				)
			)
		)
	)
	(zone
		(layers "In3.Cu" "In5.Cu" "In7.Cu" "In8.Cu" "In9.Cu")
		(hatch none 0.5)
		(connect_pads
			(clearance 0)
		)
		(min_thickness 0.25)
		(keepout
			(tracks not_allowed)
			(vias allowed)
			(pads allowed)
			(copperpour not_allowed)
			(footprints allowed)
		)
		(placement
			(enabled no)
			(sheetname "")
		)
		(fill yes
			(thermal_gap 0.5)
			(thermal_bridge_width 0.5)
			(island_removal_mode 0)
		)
		(polygon
			(pts
				(arc
					(start 352.5012 -283.300932)
					(mid 352.806 -282.996132)
					(end 352.5012 -282.691332)
				)
				(arc
					(start 351.561146 -282.691332)
					(mid 351.256346 -282.996132)
					(end 351.561146 -283.300932)
				)
			)
		)
	)
	(zone
		(layers "In3.Cu" "In5.Cu" "In7.Cu" "In8.Cu" "In9.Cu")
		(hatch none 0.5)
		(connect_pads
			(clearance 0)
		)
		(min_thickness 0.25)
		(keepout
			(tracks not_allowed)
			(vias allowed)
			(pads allowed)
			(copperpour not_allowed)
			(footprints allowed)
		)
		(placement
			(enabled no)
			(sheetname "")
		)
		(fill yes
			(thermal_gap 0.5)
			(thermal_bridge_width 0.5)
			(island_removal_mode 0)
		)
		(polygon
			(pts
				(arc
					(start 349.681292 -283.300932)
					(mid 349.986092 -282.996132)
					(end 349.681292 -282.691332)
				)
				(arc
					(start 348.741238 -282.691332)
					(mid 348.436438 -282.996132)
					(end 348.741238 -283.300932)
				)
			)
		)
	)
	(zone
		(layers "In3.Cu" "In5.Cu" "In7.Cu" "In8.Cu" "In9.Cu")
		(hatch none 0.5)
		(connect_pads
			(clearance 0)
		)
		(min_thickness 0.25)
		(keepout
			(tracks not_allowed)
			(vias allowed)
			(pads allowed)
			(copperpour not_allowed)
			(footprints allowed)
		)
		(placement
			(enabled no)
			(sheetname "")
		)
		(fill yes
			(thermal_gap 0.5)
			(thermal_bridge_width 0.5)
			(island_removal_mode 0)
		)
		(polygon
			(pts
				(arc
					(start 357.671116 -285.73095)
					(mid 357.975916 -285.42615)
					(end 357.671116 -285.12135)
				)
				(arc
					(start 356.731062 -285.12135)
					(mid 356.426262 -285.42615)
					(end 356.731062 -285.73095)
				)
			)
		)
	)
	(zone
		(layers "In3.Cu" "In5.Cu" "In7.Cu" "In8.Cu" "In9.Cu")
		(hatch none 0.5)
		(connect_pads
			(clearance 0)
		)
		(min_thickness 0.25)
		(keepout
			(tracks not_allowed)
			(vias allowed)
			(pads allowed)
			(copperpour not_allowed)
			(footprints allowed)
		)
		(placement
			(enabled no)
			(sheetname "")
		)
		(fill yes
			(thermal_gap 0.5)
			(thermal_bridge_width 0.5)
			(island_removal_mode 0)
		)
		(polygon
			(pts
				(arc
					(start 107.38104 -283.301186)
					(mid 107.68584 -282.996386)
					(end 107.38104 -282.691586)
				)
				(arc
					(start 106.440986 -282.691586)
					(mid 106.136186 -282.996386)
					(end 106.440986 -283.301186)
				)
			)
		)
	)
	(zone
		(layers "In3.Cu" "In5.Cu" "In7.Cu" "In8.Cu" "In9.Cu")
		(hatch none 0.5)
		(connect_pads
			(clearance 0)
		)
		(min_thickness 0.25)
		(keepout
			(tracks not_allowed)
			(vias allowed)
			(pads allowed)
			(copperpour not_allowed)
			(footprints allowed)
		)
		(placement
			(enabled no)
			(sheetname "")
		)
		(fill yes
			(thermal_gap 0.5)
			(thermal_bridge_width 0.5)
			(island_removal_mode 0)
		)
		(polygon
			(pts
				(arc
					(start 352.5012 -284.920944)
					(mid 352.806 -284.616144)
					(end 352.5012 -284.311344)
				)
				(arc
					(start 351.561146 -284.311344)
					(mid 351.256346 -284.616144)
					(end 351.561146 -284.920944)
				)
			)
		)
	)
	(zone
		(layers "In3.Cu" "In5.Cu" "In7.Cu" "In8.Cu" "In9.Cu")
		(hatch none 0.5)
		(connect_pads
			(clearance 0)
		)
		(min_thickness 0.25)
		(keepout
			(tracks not_allowed)
			(vias allowed)
			(pads allowed)
			(copperpour not_allowed)
			(footprints allowed)
		)
		(placement
			(enabled no)
			(sheetname "")
		)
		(fill yes
			(thermal_gap 0.5)
			(thermal_bridge_width 0.5)
			(island_removal_mode 0)
		)
		(polygon
			(pts
				(arc
					(start 355.321108 -286.540956)
					(mid 355.625908 -286.236156)
					(end 355.321108 -285.931356)
				)
				(arc
					(start 354.381054 -285.931356)
					(mid 354.076254 -286.236156)
					(end 354.381054 -286.540956)
				)
			)
		)
	)
	(zone
		(layers "In3.Cu" "In5.Cu" "In7.Cu" "In8.Cu" "In9.Cu")
		(hatch none 0.5)
		(connect_pads
			(clearance 0)
		)
		(min_thickness 0.25)
		(keepout
			(tracks not_allowed)
			(vias allowed)
			(pads allowed)
			(copperpour not_allowed)
			(footprints allowed)
		)
		(placement
			(enabled no)
			(sheetname "")
		)
		(fill yes
			(thermal_gap 0.5)
			(thermal_bridge_width 0.5)
			(island_removal_mode 0)
		)
		(polygon
			(pts
				(arc
					(start 349.681292 -281.68092)
					(mid 349.986092 -281.37612)
					(end 349.681292 -281.07132)
				)
				(arc
					(start 348.741238 -281.07132)
					(mid 348.436438 -281.37612)
					(end 348.741238 -281.68092)
				)
			)
		)
	)
	(zone
		(layers "In3.Cu" "In5.Cu" "In7.Cu" "In8.Cu" "In9.Cu")
		(hatch none 0.5)
		(connect_pads
			(clearance 0)
		)
		(min_thickness 0.25)
		(keepout
			(tracks not_allowed)
			(vias allowed)
			(pads allowed)
			(copperpour not_allowed)
			(footprints allowed)
		)
		(placement
			(enabled no)
			(sheetname "")
		)
		(fill yes
			(thermal_gap 0.5)
			(thermal_bridge_width 0.5)
			(island_removal_mode 0)
		)
		(polygon
			(pts
				(arc
					(start 349.681292 -284.920944)
					(mid 349.986092 -284.616144)
					(end 349.681292 -284.311344)
				)
				(arc
					(start 348.741238 -284.311344)
					(mid 348.436438 -284.616144)
					(end 348.741238 -284.920944)
				)
			)
		)
	)
	(zone
		(layers "In3.Cu" "In5.Cu" "In7.Cu" "In8.Cu" "In9.Cu")
		(hatch none 0.5)
		(connect_pads
			(clearance 0)
		)
		(min_thickness 0.25)
		(keepout
			(tracks not_allowed)
			(vias allowed)
			(pads allowed)
			(copperpour not_allowed)
			(footprints allowed)
		)
		(placement
			(enabled no)
			(sheetname "")
		)
		(fill yes
			(thermal_gap 0.5)
			(thermal_bridge_width 0.5)
			(island_removal_mode 0)
		)
		(polygon
			(pts
				(arc
					(start 104.561132 -283.301186)
					(mid 104.865932 -282.996386)
					(end 104.561132 -282.691586)
				)
				(arc
					(start 103.621078 -282.691586)
					(mid 103.316278 -282.996386)
					(end 103.621078 -283.301186)
				)
			)
		)
	)
	(zone
		(layers "In3.Cu" "In5.Cu" "In7.Cu" "In8.Cu" "In9.Cu")
		(hatch none 0.5)
		(connect_pads
			(clearance 0)
		)
		(min_thickness 0.25)
		(keepout
			(tracks not_allowed)
			(vias allowed)
			(pads allowed)
			(copperpour not_allowed)
			(footprints allowed)
		)
		(placement
			(enabled no)
			(sheetname "")
		)
		(fill yes
			(thermal_gap 0.5)
			(thermal_bridge_width 0.5)
			(island_removal_mode 0)
		)
		(polygon
			(pts
				(arc
					(start 107.38104 -284.921198)
					(mid 107.68584 -284.616398)
					(end 107.38104 -284.311598)
				)
				(arc
					(start 106.440986 -284.311598)
					(mid 106.136186 -284.616398)
					(end 106.440986 -284.921198)
				)
			)
		)
	)
	(zone
		(layers "In3.Cu" "In5.Cu" "In7.Cu" "In8.Cu" "In9.Cu")
		(hatch none 0.5)
		(connect_pads
			(clearance 0)
		)
		(min_thickness 0.25)
		(keepout
			(tracks not_allowed)
			(vias allowed)
			(pads allowed)
			(copperpour not_allowed)
			(footprints allowed)
		)
		(placement
			(enabled no)
			(sheetname "")
		)
		(fill yes
			(thermal_gap 0.5)
			(thermal_bridge_width 0.5)
			(island_removal_mode 0)
		)
		(polygon
			(pts
				(arc
					(start 346.86113 -283.300932)
					(mid 347.16593 -282.996132)
					(end 346.86113 -282.691332)
				)
				(arc
					(start 345.921076 -282.691332)
					(mid 345.616276 -282.996132)
					(end 345.921076 -283.300932)
				)
			)
		)
	)
	(zone
		(layers "In3.Cu" "In5.Cu" "In7.Cu" "In8.Cu" "In9.Cu")
		(hatch none 0.5)
		(connect_pads
			(clearance 0)
		)
		(min_thickness 0.25)
		(keepout
			(tracks not_allowed)
			(vias allowed)
			(pads allowed)
			(copperpour not_allowed)
			(footprints allowed)
		)
		(placement
			(enabled no)
			(sheetname "")
		)
		(fill yes
			(thermal_gap 0.5)
			(thermal_bridge_width 0.5)
			(island_removal_mode 0)
		)
		(polygon
			(pts
				(arc
					(start 109.731048 -282.49118)
					(mid 110.035848 -282.18638)
					(end 109.731048 -281.88158)
				)
				(arc
					(start 108.790994 -281.88158)
					(mid 108.486194 -282.18638)
					(end 108.790994 -282.49118)
				)
			)
		)
	)
	(zone
		(layers "In3.Cu" "In5.Cu" "In7.Cu" "In8.Cu" "In9.Cu")
		(hatch none 0.5)
		(connect_pads
			(clearance 0)
		)
		(min_thickness 0.25)
		(keepout
			(tracks not_allowed)
			(vias allowed)
			(pads allowed)
			(copperpour not_allowed)
			(footprints allowed)
		)
		(placement
			(enabled no)
			(sheetname "")
		)
		(fill yes
			(thermal_gap 0.5)
			(thermal_bridge_width 0.5)
			(island_removal_mode 0)
		)
		(polygon
			(pts
				(arc
					(start 355.321108 -284.920944)
					(mid 355.625908 -284.616144)
					(end 355.321108 -284.311344)
				)
				(arc
					(start 354.381054 -284.311344)
					(mid 354.076254 -284.616144)
					(end 354.381054 -284.920944)
				)
			)
		)
	)
	(zone
		(layers "In3.Cu" "In5.Cu" "In7.Cu" "In8.Cu" "In9.Cu")
		(hatch none 0.5)
		(connect_pads
			(clearance 0)
		)
		(min_thickness 0.25)
		(keepout
			(tracks not_allowed)
			(vias allowed)
			(pads allowed)
			(copperpour not_allowed)
			(footprints allowed)
		)
		(placement
			(enabled no)
			(sheetname "")
		)
		(fill yes
			(thermal_gap 0.5)
			(thermal_bridge_width 0.5)
			(island_removal_mode 0)
		)
		(polygon
			(pts
				(arc
					(start 101.741224 -284.921198)
					(mid 102.046024 -284.616398)
					(end 101.741224 -284.311598)
				)
				(arc
					(start 100.80117 -284.311598)
					(mid 100.49637 -284.616398)
					(end 100.80117 -284.921198)
				)
			)
		)
	)
	(zone
		(layers "In3.Cu" "In5.Cu" "In7.Cu" "In8.Cu" "In9.Cu")
		(hatch none 0.5)
		(connect_pads
			(clearance 0)
		)
		(min_thickness 0.25)
		(keepout
			(tracks not_allowed)
			(vias allowed)
			(pads allowed)
			(copperpour not_allowed)
			(footprints allowed)
		)
		(placement
			(enabled no)
			(sheetname "")
		)
		(fill yes
			(thermal_gap 0.5)
			(thermal_bridge_width 0.5)
			(island_removal_mode 0)
		)
		(polygon
			(pts
				(arc
					(start 352.5012 -286.540956)
					(mid 352.806 -286.236156)
					(end 352.5012 -285.931356)
				)
				(arc
					(start 351.561146 -285.931356)
					(mid 351.256346 -286.236156)
					(end 351.561146 -286.540956)
				)
			)
		)
	)
	(zone
		(layers "In3.Cu" "In5.Cu" "In7.Cu" "In8.Cu" "In9.Cu")
		(hatch none 0.5)
		(connect_pads
			(clearance 0)
		)
		(min_thickness 0.25)
		(keepout
			(tracks not_allowed)
			(vias allowed)
			(pads allowed)
			(copperpour not_allowed)
			(footprints allowed)
		)
		(placement
			(enabled no)
			(sheetname "")
		)
		(fill yes
			(thermal_gap 0.5)
			(thermal_bridge_width 0.5)
			(island_removal_mode 0)
		)
		(polygon
			(pts
				(arc
					(start 104.561132 -284.921198)
					(mid 104.865932 -284.616398)
					(end 104.561132 -284.311598)
				)
				(arc
					(start 103.621078 -284.311598)
					(mid 103.316278 -284.616398)
					(end 103.621078 -284.921198)
				)
			)
		)
	)
	(zone
		(layers "In3.Cu" "In5.Cu" "In7.Cu" "In8.Cu" "In9.Cu")
		(hatch none 0.5)
		(connect_pads
			(clearance 0)
		)
		(min_thickness 0.25)
		(keepout
			(tracks not_allowed)
			(vias allowed)
			(pads allowed)
			(copperpour not_allowed)
			(footprints allowed)
		)
		(placement
			(enabled no)
			(sheetname "")
		)
		(fill yes
			(thermal_gap 0.5)
			(thermal_bridge_width 0.5)
			(island_removal_mode 0)
		)
		(polygon
			(pts
				(arc
					(start 357.671116 -284.110938)
					(mid 357.975916 -283.806138)
					(end 357.671116 -283.501338)
				)
				(arc
					(start 356.731062 -283.501338)
					(mid 356.426262 -283.806138)
					(end 356.731062 -284.110938)
				)
			)
		)
	)
	(zone
		(layers "In3.Cu" "In5.Cu" "In7.Cu" "In8.Cu" "In9.Cu")
		(hatch none 0.5)
		(connect_pads
			(clearance 0)
		)
		(min_thickness 0.25)
		(keepout
			(tracks not_allowed)
			(vias allowed)
			(pads allowed)
			(copperpour not_allowed)
			(footprints allowed)
		)
		(placement
			(enabled no)
			(sheetname "")
		)
		(fill yes
			(thermal_gap 0.5)
			(thermal_bridge_width 0.5)
			(island_removal_mode 0)
		)
		(polygon
			(pts
				(arc
					(start 349.681292 -286.540956)
					(mid 349.986092 -286.236156)
					(end 349.681292 -285.931356)
				)
				(arc
					(start 348.741238 -285.931356)
					(mid 348.436438 -286.236156)
					(end 348.741238 -286.540956)
				)
			)
		)
	)
	(zone
		(layers "In3.Cu" "In5.Cu" "In7.Cu" "In8.Cu" "In9.Cu")
		(hatch none 0.5)
		(connect_pads
			(clearance 0)
		)
		(min_thickness 0.25)
		(keepout
			(tracks not_allowed)
			(vias allowed)
			(pads allowed)
			(copperpour not_allowed)
			(footprints allowed)
		)
		(placement
			(enabled no)
			(sheetname "")
		)
		(fill yes
			(thermal_gap 0.5)
			(thermal_bridge_width 0.5)
			(island_removal_mode 0)
		)
		(polygon
			(pts
				(arc
					(start 355.321108 -283.300932)
					(mid 355.625908 -282.996132)
					(end 355.321108 -282.691332)
				)
				(arc
					(start 354.381054 -282.691332)
					(mid 354.076254 -282.996132)
					(end 354.381054 -283.300932)
				)
			)
		)
	)
	(zone
		(layers "In3.Cu" "In5.Cu" "In7.Cu" "In8.Cu" "In9.Cu")
		(hatch none 0.5)
		(connect_pads
			(clearance 0)
		)
		(min_thickness 0.25)
		(keepout
			(tracks not_allowed)
			(vias allowed)
			(pads allowed)
			(copperpour not_allowed)
			(footprints allowed)
		)
		(placement
			(enabled no)
			(sheetname "")
		)
		(fill yes
			(thermal_gap 0.5)
			(thermal_bridge_width 0.5)
			(island_removal_mode 0)
		)
		(polygon
			(pts
				(arc
					(start 98.921062 -284.921198)
					(mid 99.225862 -284.616398)
					(end 98.921062 -284.311598)
				)
				(arc
					(start 97.981008 -284.311598)
					(mid 97.676208 -284.616398)
					(end 97.981008 -284.921198)
				)
			)
		)
	)
	(zone
		(layers "In3.Cu" "In5.Cu" "In7.Cu" "In8.Cu" "In9.Cu")
		(hatch none 0.5)
		(connect_pads
			(clearance 0)
		)
		(min_thickness 0.25)
		(keepout
			(tracks not_allowed)
			(vias allowed)
			(pads allowed)
			(copperpour not_allowed)
			(footprints allowed)
		)
		(placement
			(enabled no)
			(sheetname "")
		)
		(fill yes
			(thermal_gap 0.5)
			(thermal_bridge_width 0.5)
			(island_removal_mode 0)
		)
		(polygon
			(pts
				(arc
					(start 346.86113 -281.68092)
					(mid 347.16593 -281.37612)
					(end 346.86113 -281.07132)
				)
				(arc
					(start 345.921076 -281.07132)
					(mid 345.616276 -281.37612)
					(end 345.921076 -281.68092)
				)
			)
		)
	)
	(zone
		(layers "In3.Cu" "In5.Cu" "In7.Cu" "In8.Cu" "In9.Cu")
		(hatch none 0.5)
		(connect_pads
			(clearance 0)
		)
		(min_thickness 0.25)
		(keepout
			(tracks not_allowed)
			(vias allowed)
			(pads allowed)
			(copperpour not_allowed)
			(footprints allowed)
		)
		(placement
			(enabled no)
			(sheetname "")
		)
		(fill yes
			(thermal_gap 0.5)
			(thermal_bridge_width 0.5)
			(island_removal_mode 0)
		)
		(polygon
			(pts
				(arc
					(start 109.731048 -284.111192)
					(mid 110.035848 -283.806392)
					(end 109.731048 -283.501592)
				)
				(arc
					(start 108.790994 -283.501592)
					(mid 108.486194 -283.806392)
					(end 108.790994 -284.111192)
				)
			)
		)
	)
	(zone
		(layers "In3.Cu" "In5.Cu" "In7.Cu" "In8.Cu" "In9.Cu")
		(hatch none 0.5)
		(connect_pads
			(clearance 0)
		)
		(min_thickness 0.25)
		(keepout
			(tracks not_allowed)
			(vias allowed)
			(pads allowed)
			(copperpour not_allowed)
			(footprints allowed)
		)
		(placement
			(enabled no)
			(sheetname "")
		)
		(fill yes
			(thermal_gap 0.5)
			(thermal_bridge_width 0.5)
			(island_removal_mode 0)
		)
		(polygon
			(pts
				(arc
					(start 107.38104 -286.54121)
					(mid 107.68584 -286.23641)
					(end 107.38104 -285.93161)
				)
				(arc
					(start 106.440986 -285.93161)
					(mid 106.136186 -286.23641)
					(end 106.440986 -286.54121)
				)
			)
		)
	)
	(zone
		(layers "In3.Cu" "In5.Cu" "In7.Cu" "In8.Cu" "In9.Cu" "In10.Cu")
		(hatch none 0.5)
		(connect_pads
			(clearance 0)
		)
		(min_thickness 0.25)
		(keepout
			(tracks not_allowed)
			(vias allowed)
			(pads allowed)
			(copperpour not_allowed)
			(footprints allowed)
		)
		(placement
			(enabled no)
			(sheetname "")
		)
		(fill yes
			(thermal_gap 0.5)
			(thermal_bridge_width 0.5)
			(island_removal_mode 0)
		)
		(polygon
			(pts
				(arc
					(start 98.621088 -246.40921)
					(mid 98.925888 -246.10441)
					(end 98.621088 -245.79961)
				)
				(arc
					(start 97.681034 -245.79961)
					(mid 97.376234 -246.10441)
					(end 97.681034 -246.40921)
				)
			)
		)
	)
	(zone
		(layers "In3.Cu" "In5.Cu" "In7.Cu" "In8.Cu" "In9.Cu" "In10.Cu")
		(hatch none 0.5)
		(connect_pads
			(clearance 0)
		)
		(min_thickness 0.25)
		(keepout
			(tracks not_allowed)
			(vias allowed)
			(pads allowed)
			(copperpour not_allowed)
			(footprints allowed)
		)
		(placement
			(enabled no)
			(sheetname "")
		)
		(fill yes
			(thermal_gap 0.5)
			(thermal_bridge_width 0.5)
			(island_removal_mode 0)
		)
		(polygon
			(pts
				(arc
					(start 101.440996 -244.789198)
					(mid 101.745796 -244.484398)
					(end 101.440996 -244.179598)
				)
				(arc
					(start 100.500942 -244.179598)
					(mid 100.196142 -244.484398)
					(end 100.500942 -244.789198)
				)
			)
		)
	)
	(zone
		(layers "In3.Cu" "In5.Cu" "In7.Cu" "In8.Cu" "In9.Cu" "In10.Cu")
		(hatch none 0.5)
		(connect_pads
			(clearance 0)
		)
		(min_thickness 0.25)
		(keepout
			(tracks not_allowed)
			(vias allowed)
			(pads allowed)
			(copperpour not_allowed)
			(footprints allowed)
		)
		(placement
			(enabled no)
			(sheetname "")
		)
		(fill yes
			(thermal_gap 0.5)
			(thermal_bridge_width 0.5)
			(island_removal_mode 0)
		)
		(polygon
			(pts
				(arc
					(start 104.261158 -244.789198)
					(mid 104.565958 -244.484398)
					(end 104.261158 -244.179598)
				)
				(arc
					(start 103.321104 -244.179598)
					(mid 103.016304 -244.484398)
					(end 103.321104 -244.789198)
				)
			)
		)
	)
	(zone
		(layers "In3.Cu" "In5.Cu" "In7.Cu" "In8.Cu" "In9.Cu" "In10.Cu")
		(hatch none 0.5)
		(connect_pads
			(clearance 0)
		)
		(min_thickness 0.25)
		(keepout
			(tracks not_allowed)
			(vias allowed)
			(pads allowed)
			(copperpour not_allowed)
			(footprints allowed)
		)
		(placement
			(enabled no)
			(sheetname "")
		)
		(fill yes
			(thermal_gap 0.5)
			(thermal_bridge_width 0.5)
			(island_removal_mode 0)
		)
		(polygon
			(pts
				(arc
					(start 363.004862 -243.978938)
					(mid 363.309662 -243.674138)
					(end 363.004862 -243.369338)
				)
				(arc
					(start 362.064808 -243.369338)
					(mid 361.760008 -243.674138)
					(end 362.064808 -243.978938)
				)
			)
		)
	)
	(zone
		(layers "In3.Cu" "In5.Cu" "In7.Cu" "In8.Cu" "In9.Cu" "In10.Cu")
		(hatch none 0.5)
		(connect_pads
			(clearance 0)
		)
		(min_thickness 0.25)
		(keepout
			(tracks not_allowed)
			(vias allowed)
			(pads allowed)
			(copperpour not_allowed)
			(footprints allowed)
		)
		(placement
			(enabled no)
			(sheetname "")
		)
		(fill yes
			(thermal_gap 0.5)
			(thermal_bridge_width 0.5)
			(island_removal_mode 0)
		)
		(polygon
			(pts
				(arc
					(start 107.081066 -248.029222)
					(mid 107.385866 -247.724422)
					(end 107.081066 -247.419622)
				)
				(arc
					(start 106.141012 -247.419622)
					(mid 105.836212 -247.724422)
					(end 106.141012 -248.029222)
				)
			)
		)
	)
	(zone
		(layers "In3.Cu" "In5.Cu" "In7.Cu" "In8.Cu" "In9.Cu" "In10.Cu")
		(hatch none 0.5)
		(connect_pads
			(clearance 0)
		)
		(min_thickness 0.25)
		(keepout
			(tracks not_allowed)
			(vias allowed)
			(pads allowed)
			(copperpour not_allowed)
			(footprints allowed)
		)
		(placement
			(enabled no)
			(sheetname "")
		)
		(fill yes
			(thermal_gap 0.5)
			(thermal_bridge_width 0.5)
			(island_removal_mode 0)
		)
		(polygon
			(pts
				(arc
					(start 363.004862 -245.59895)
					(mid 363.309662 -245.29415)
					(end 363.004862 -244.98935)
				)
				(arc
					(start 362.064808 -244.98935)
					(mid 361.760008 -245.29415)
					(end 362.064808 -245.59895)
				)
			)
		)
	)
	(zone
		(layers "In3.Cu" "In5.Cu" "In7.Cu" "In8.Cu" "In9.Cu" "In10.Cu")
		(hatch none 0.5)
		(connect_pads
			(clearance 0)
		)
		(min_thickness 0.25)
		(keepout
			(tracks not_allowed)
			(vias allowed)
			(pads allowed)
			(copperpour not_allowed)
			(footprints allowed)
		)
		(placement
			(enabled no)
			(sheetname "")
		)
		(fill yes
			(thermal_gap 0.5)
			(thermal_bridge_width 0.5)
			(island_removal_mode 0)
		)
		(polygon
			(pts
				(arc
					(start 373.814848 -248.028968)
					(mid 374.119648 -247.724168)
					(end 373.814848 -247.419368)
				)
				(arc
					(start 372.874794 -247.419368)
					(mid 372.569994 -247.724168)
					(end 372.874794 -248.028968)
				)
			)
		)
	)
	(zone
		(layers "In3.Cu" "In5.Cu" "In7.Cu" "In8.Cu" "In9.Cu" "In10.Cu")
		(hatch none 0.5)
		(connect_pads
			(clearance 0)
		)
		(min_thickness 0.25)
		(keepout
			(tracks not_allowed)
			(vias allowed)
			(pads allowed)
			(copperpour not_allowed)
			(footprints allowed)
		)
		(placement
			(enabled no)
			(sheetname "")
		)
		(fill yes
			(thermal_gap 0.5)
			(thermal_bridge_width 0.5)
			(island_removal_mode 0)
		)
		(polygon
			(pts
				(arc
					(start 368.174778 -248.028968)
					(mid 368.479578 -247.724168)
					(end 368.174778 -247.419368)
				)
				(arc
					(start 367.234724 -247.419368)
					(mid 366.929924 -247.724168)
					(end 367.234724 -248.028968)
				)
			)
		)
	)
	(zone
		(layers "In3.Cu" "In5.Cu" "In7.Cu" "In8.Cu" "In9.Cu" "In10.Cu")
		(hatch none 0.5)
		(connect_pads
			(clearance 0)
		)
		(min_thickness 0.25)
		(keepout
			(tracks not_allowed)
			(vias allowed)
			(pads allowed)
			(copperpour not_allowed)
			(footprints allowed)
		)
		(placement
			(enabled no)
			(sheetname "")
		)
		(fill yes
			(thermal_gap 0.5)
			(thermal_bridge_width 0.5)
			(island_removal_mode 0)
		)
		(polygon
			(pts
				(arc
					(start 107.081066 -246.40921)
					(mid 107.385866 -246.10441)
					(end 107.081066 -245.79961)
				)
				(arc
					(start 106.141012 -245.79961)
					(mid 105.836212 -246.10441)
					(end 106.141012 -246.40921)
				)
			)
		)
	)
	(zone
		(layers "In3.Cu" "In5.Cu" "In7.Cu" "In8.Cu" "In9.Cu" "In10.Cu")
		(hatch none 0.5)
		(connect_pads
			(clearance 0)
		)
		(min_thickness 0.25)
		(keepout
			(tracks not_allowed)
			(vias allowed)
			(pads allowed)
			(copperpour not_allowed)
			(footprints allowed)
		)
		(placement
			(enabled no)
			(sheetname "")
		)
		(fill yes
			(thermal_gap 0.5)
			(thermal_bridge_width 0.5)
			(island_removal_mode 0)
		)
		(polygon
			(pts
				(arc
					(start 370.99494 -244.788944)
					(mid 371.29974 -244.484144)
					(end 370.99494 -244.179344)
				)
				(arc
					(start 370.054886 -244.179344)
					(mid 369.750086 -244.484144)
					(end 370.054886 -244.788944)
				)
			)
		)
	)
	(zone
		(layers "In3.Cu" "In5.Cu" "In7.Cu" "In8.Cu" "In9.Cu" "In10.Cu")
		(hatch none 0.5)
		(connect_pads
			(clearance 0)
		)
		(min_thickness 0.25)
		(keepout
			(tracks not_allowed)
			(vias allowed)
			(pads allowed)
			(copperpour not_allowed)
			(footprints allowed)
		)
		(placement
			(enabled no)
			(sheetname "")
		)
		(fill yes
			(thermal_gap 0.5)
			(thermal_bridge_width 0.5)
			(island_removal_mode 0)
		)
		(polygon
			(pts
				(arc
					(start 373.814848 -246.408956)
					(mid 374.119648 -246.104156)
					(end 373.814848 -245.799356)
				)
				(arc
					(start 372.874794 -245.799356)
					(mid 372.569994 -246.104156)
					(end 372.874794 -246.408956)
				)
			)
		)
	)
	(zone
		(layers "In3.Cu" "In5.Cu" "In7.Cu" "In8.Cu" "In9.Cu" "In10.Cu")
		(hatch none 0.5)
		(connect_pads
			(clearance 0)
		)
		(min_thickness 0.25)
		(keepout
			(tracks not_allowed)
			(vias allowed)
			(pads allowed)
			(copperpour not_allowed)
			(footprints allowed)
		)
		(placement
			(enabled no)
			(sheetname "")
		)
		(fill yes
			(thermal_gap 0.5)
			(thermal_bridge_width 0.5)
			(island_removal_mode 0)
		)
		(polygon
			(pts
				(arc
					(start 363.004862 -248.838974)
					(mid 363.309662 -248.534174)
					(end 363.004862 -248.229374)
				)
				(arc
					(start 362.064808 -248.229374)
					(mid 361.760008 -248.534174)
					(end 362.064808 -248.838974)
				)
			)
		)
	)
	(zone
		(layers "In3.Cu" "In5.Cu" "In7.Cu" "In8.Cu" "In9.Cu" "In10.Cu")
		(hatch none 0.5)
		(connect_pads
			(clearance 0)
		)
		(min_thickness 0.25)
		(keepout
			(tracks not_allowed)
			(vias allowed)
			(pads allowed)
			(copperpour not_allowed)
			(footprints allowed)
		)
		(placement
			(enabled no)
			(sheetname "")
		)
		(fill yes
			(thermal_gap 0.5)
			(thermal_bridge_width 0.5)
			(island_removal_mode 0)
		)
		(polygon
			(pts
				(arc
					(start 370.99494 -248.028968)
					(mid 371.29974 -247.724168)
					(end 370.99494 -247.419368)
				)
				(arc
					(start 370.054886 -247.419368)
					(mid 369.750086 -247.724168)
					(end 370.054886 -248.028968)
				)
			)
		)
	)
	(zone
		(layers "In3.Cu" "In5.Cu" "In7.Cu" "In8.Cu" "In9.Cu" "In10.Cu")
		(hatch none 0.5)
		(connect_pads
			(clearance 0)
		)
		(min_thickness 0.25)
		(keepout
			(tracks not_allowed)
			(vias allowed)
			(pads allowed)
			(copperpour not_allowed)
			(footprints allowed)
		)
		(placement
			(enabled no)
			(sheetname "")
		)
		(fill yes
			(thermal_gap 0.5)
			(thermal_bridge_width 0.5)
			(island_removal_mode 0)
		)
		(polygon
			(pts
				(arc
					(start 368.174778 -246.408956)
					(mid 368.479578 -246.104156)
					(end 368.174778 -245.799356)
				)
				(arc
					(start 367.234724 -245.799356)
					(mid 366.929924 -246.104156)
					(end 367.234724 -246.408956)
				)
			)
		)
	)
	(zone
		(layers "In3.Cu" "In5.Cu" "In7.Cu" "In8.Cu" "In9.Cu" "In10.Cu")
		(hatch none 0.5)
		(connect_pads
			(clearance 0)
		)
		(min_thickness 0.25)
		(keepout
			(tracks not_allowed)
			(vias allowed)
			(pads allowed)
			(copperpour not_allowed)
			(footprints allowed)
		)
		(placement
			(enabled no)
			(sheetname "")
		)
		(fill yes
			(thermal_gap 0.5)
			(thermal_bridge_width 0.5)
			(island_removal_mode 0)
		)
		(polygon
			(pts
				(arc
					(start 107.081066 -244.789198)
					(mid 107.385866 -244.484398)
					(end 107.081066 -244.179598)
				)
				(arc
					(start 106.141012 -244.179598)
					(mid 105.836212 -244.484398)
					(end 106.141012 -244.789198)
				)
			)
		)
	)
	(zone
		(layers "In3.Cu" "In5.Cu" "In7.Cu" "In8.Cu" "In9.Cu" "In10.Cu")
		(hatch none 0.5)
		(connect_pads
			(clearance 0)
		)
		(min_thickness 0.25)
		(keepout
			(tracks not_allowed)
			(vias allowed)
			(pads allowed)
			(copperpour not_allowed)
			(footprints allowed)
		)
		(placement
			(enabled no)
			(sheetname "")
		)
		(fill yes
			(thermal_gap 0.5)
			(thermal_bridge_width 0.5)
			(island_removal_mode 0)
		)
		(polygon
			(pts
				(arc
					(start 109.431074 -243.979192)
					(mid 109.735874 -243.674392)
					(end 109.431074 -243.369592)
				)
				(arc
					(start 108.49102 -243.369592)
					(mid 108.18622 -243.674392)
					(end 108.49102 -243.979192)
				)
			)
		)
	)
	(zone
		(layers "In3.Cu" "In5.Cu" "In7.Cu" "In8.Cu" "In9.Cu" "In10.Cu")
		(hatch none 0.5)
		(connect_pads
			(clearance 0)
		)
		(min_thickness 0.25)
		(keepout
			(tracks not_allowed)
			(vias allowed)
			(pads allowed)
			(copperpour not_allowed)
			(footprints allowed)
		)
		(placement
			(enabled no)
			(sheetname "")
		)
		(fill yes
			(thermal_gap 0.5)
			(thermal_bridge_width 0.5)
			(island_removal_mode 0)
		)
		(polygon
			(pts
				(arc
					(start 101.440996 -246.40921)
					(mid 101.745796 -246.10441)
					(end 101.440996 -245.79961)
				)
				(arc
					(start 100.500942 -245.79961)
					(mid 100.196142 -246.10441)
					(end 100.500942 -246.40921)
				)
			)
		)
	)
	(zone
		(layers "In3.Cu" "In5.Cu" "In7.Cu" "In8.Cu" "In9.Cu" "In10.Cu")
		(hatch none 0.5)
		(connect_pads
			(clearance 0)
		)
		(min_thickness 0.25)
		(keepout
			(tracks not_allowed)
			(vias allowed)
			(pads allowed)
			(copperpour not_allowed)
			(footprints allowed)
		)
		(placement
			(enabled no)
			(sheetname "")
		)
		(fill yes
			(thermal_gap 0.5)
			(thermal_bridge_width 0.5)
			(island_removal_mode 0)
		)
		(polygon
			(pts
				(arc
					(start 370.99494 -246.408956)
					(mid 371.29974 -246.104156)
					(end 370.99494 -245.799356)
				)
				(arc
					(start 370.054886 -245.799356)
					(mid 369.750086 -246.104156)
					(end 370.054886 -246.408956)
				)
			)
		)
	)
	(zone
		(layers "In3.Cu" "In5.Cu" "In7.Cu" "In8.Cu" "In9.Cu" "In10.Cu")
		(hatch none 0.5)
		(connect_pads
			(clearance 0)
		)
		(min_thickness 0.25)
		(keepout
			(tracks not_allowed)
			(vias allowed)
			(pads allowed)
			(copperpour not_allowed)
			(footprints allowed)
		)
		(placement
			(enabled no)
			(sheetname "")
		)
		(fill yes
			(thermal_gap 0.5)
			(thermal_bridge_width 0.5)
			(island_removal_mode 0)
		)
		(polygon
			(pts
				(arc
					(start 109.431074 -248.839228)
					(mid 109.735874 -248.534428)
					(end 109.431074 -248.229628)
				)
				(arc
					(start 108.49102 -248.229628)
					(mid 108.18622 -248.534428)
					(end 108.49102 -248.839228)
				)
			)
		)
	)
	(zone
		(layers "In3.Cu" "In5.Cu" "In7.Cu" "In8.Cu" "In9.Cu" "In10.Cu")
		(hatch none 0.5)
		(connect_pads
			(clearance 0)
		)
		(min_thickness 0.25)
		(keepout
			(tracks not_allowed)
			(vias allowed)
			(pads allowed)
			(copperpour not_allowed)
			(footprints allowed)
		)
		(placement
			(enabled no)
			(sheetname "")
		)
		(fill yes
			(thermal_gap 0.5)
			(thermal_bridge_width 0.5)
			(island_removal_mode 0)
		)
		(polygon
			(pts
				(arc
					(start 101.440996 -248.029222)
					(mid 101.745796 -247.724422)
					(end 101.440996 -247.419622)
				)
				(arc
					(start 100.500942 -247.419622)
					(mid 100.196142 -247.724422)
					(end 100.500942 -248.029222)
				)
			)
		)
	)
	(zone
		(layers "In3.Cu" "In5.Cu" "In7.Cu" "In8.Cu" "In9.Cu" "In10.Cu")
		(hatch none 0.5)
		(connect_pads
			(clearance 0)
		)
		(min_thickness 0.25)
		(keepout
			(tracks not_allowed)
			(vias allowed)
			(pads allowed)
			(copperpour not_allowed)
			(footprints allowed)
		)
		(placement
			(enabled no)
			(sheetname "")
		)
		(fill yes
			(thermal_gap 0.5)
			(thermal_bridge_width 0.5)
			(island_removal_mode 0)
		)
		(polygon
			(pts
				(arc
					(start 373.814848 -244.788944)
					(mid 374.119648 -244.484144)
					(end 373.814848 -244.179344)
				)
				(arc
					(start 372.874794 -244.179344)
					(mid 372.569994 -244.484144)
					(end 372.874794 -244.788944)
				)
			)
		)
	)
	(zone
		(layers "In3.Cu" "In5.Cu" "In7.Cu" "In8.Cu" "In9.Cu" "In10.Cu")
		(hatch none 0.5)
		(connect_pads
			(clearance 0)
		)
		(min_thickness 0.25)
		(keepout
			(tracks not_allowed)
			(vias allowed)
			(pads allowed)
			(copperpour not_allowed)
			(footprints allowed)
		)
		(placement
			(enabled no)
			(sheetname "")
		)
		(fill yes
			(thermal_gap 0.5)
			(thermal_bridge_width 0.5)
			(island_removal_mode 0)
		)
		(polygon
			(pts
				(arc
					(start 109.431074 -247.219216)
					(mid 109.735874 -246.914416)
					(end 109.431074 -246.609616)
				)
				(arc
					(start 108.49102 -246.609616)
					(mid 108.18622 -246.914416)
					(end 108.49102 -247.219216)
				)
			)
		)
	)
	(zone
		(layers "In3.Cu" "In5.Cu" "In7.Cu" "In8.Cu" "In9.Cu" "In10.Cu")
		(hatch none 0.5)
		(connect_pads
			(clearance 0)
		)
		(min_thickness 0.25)
		(keepout
			(tracks not_allowed)
			(vias allowed)
			(pads allowed)
			(copperpour not_allowed)
			(footprints allowed)
		)
		(placement
			(enabled no)
			(sheetname "")
		)
		(fill yes
			(thermal_gap 0.5)
			(thermal_bridge_width 0.5)
			(island_removal_mode 0)
		)
		(polygon
			(pts
				(arc
					(start 109.431074 -245.599204)
					(mid 109.735874 -245.294404)
					(end 109.431074 -244.989604)
				)
				(arc
					(start 108.49102 -244.989604)
					(mid 108.18622 -245.294404)
					(end 108.49102 -245.599204)
				)
			)
		)
	)
	(zone
		(layers "In3.Cu" "In5.Cu" "In7.Cu" "In8.Cu" "In9.Cu" "In10.Cu")
		(hatch none 0.5)
		(connect_pads
			(clearance 0)
		)
		(min_thickness 0.25)
		(keepout
			(tracks not_allowed)
			(vias allowed)
			(pads allowed)
			(copperpour not_allowed)
			(footprints allowed)
		)
		(placement
			(enabled no)
			(sheetname "")
		)
		(fill yes
			(thermal_gap 0.5)
			(thermal_bridge_width 0.5)
			(island_removal_mode 0)
		)
		(polygon
			(pts
				(arc
					(start 104.261158 -246.40921)
					(mid 104.565958 -246.10441)
					(end 104.261158 -245.79961)
				)
				(arc
					(start 103.321104 -245.79961)
					(mid 103.016304 -246.10441)
					(end 103.321104 -246.40921)
				)
			)
		)
	)
	(zone
		(layers "In3.Cu" "In5.Cu" "In7.Cu" "In8.Cu" "In9.Cu" "In10.Cu")
		(hatch none 0.5)
		(connect_pads
			(clearance 0)
		)
		(min_thickness 0.25)
		(keepout
			(tracks not_allowed)
			(vias allowed)
			(pads allowed)
			(copperpour not_allowed)
			(footprints allowed)
		)
		(placement
			(enabled no)
			(sheetname "")
		)
		(fill yes
			(thermal_gap 0.5)
			(thermal_bridge_width 0.5)
			(island_removal_mode 0)
		)
		(polygon
			(pts
				(arc
					(start 365.35487 -244.788944)
					(mid 365.65967 -244.484144)
					(end 365.35487 -244.179344)
				)
				(arc
					(start 364.414816 -244.179344)
					(mid 364.110016 -244.484144)
					(end 364.414816 -244.788944)
				)
			)
		)
	)
	(zone
		(layers "In3.Cu" "In5.Cu" "In7.Cu" "In8.Cu" "In9.Cu" "In10.Cu")
		(hatch none 0.5)
		(connect_pads
			(clearance 0)
		)
		(min_thickness 0.25)
		(keepout
			(tracks not_allowed)
			(vias allowed)
			(pads allowed)
			(copperpour not_allowed)
			(footprints allowed)
		)
		(placement
			(enabled no)
			(sheetname "")
		)
		(fill yes
			(thermal_gap 0.5)
			(thermal_bridge_width 0.5)
			(island_removal_mode 0)
		)
		(polygon
			(pts
				(arc
					(start 363.004862 -247.218962)
					(mid 363.309662 -246.914162)
					(end 363.004862 -246.609362)
				)
				(arc
					(start 362.064808 -246.609362)
					(mid 361.760008 -246.914162)
					(end 362.064808 -247.218962)
				)
			)
		)
	)
	(zone
		(layers "In3.Cu" "In5.Cu" "In7.Cu" "In8.Cu" "In9.Cu" "In10.Cu")
		(hatch none 0.5)
		(connect_pads
			(clearance 0)
		)
		(min_thickness 0.25)
		(keepout
			(tracks not_allowed)
			(vias allowed)
			(pads allowed)
			(copperpour not_allowed)
			(footprints allowed)
		)
		(placement
			(enabled no)
			(sheetname "")
		)
		(fill yes
			(thermal_gap 0.5)
			(thermal_bridge_width 0.5)
			(island_removal_mode 0)
		)
		(polygon
			(pts
				(arc
					(start 365.35487 -248.028968)
					(mid 365.65967 -247.724168)
					(end 365.35487 -247.419368)
				)
				(arc
					(start 364.414816 -247.419368)
					(mid 364.110016 -247.724168)
					(end 364.414816 -248.028968)
				)
			)
		)
	)
	(zone
		(layers "In3.Cu" "In5.Cu" "In7.Cu" "In8.Cu" "In9.Cu" "In10.Cu")
		(hatch none 0.5)
		(connect_pads
			(clearance 0)
		)
		(min_thickness 0.25)
		(keepout
			(tracks not_allowed)
			(vias allowed)
			(pads allowed)
			(copperpour not_allowed)
			(footprints allowed)
		)
		(placement
			(enabled no)
			(sheetname "")
		)
		(fill yes
			(thermal_gap 0.5)
			(thermal_bridge_width 0.5)
			(island_removal_mode 0)
		)
		(polygon
			(pts
				(arc
					(start 104.261158 -248.029222)
					(mid 104.565958 -247.724422)
					(end 104.261158 -247.419622)
				)
				(arc
					(start 103.321104 -247.419622)
					(mid 103.016304 -247.724422)
					(end 103.321104 -248.029222)
				)
			)
		)
	)
	(zone
		(layers "In3.Cu" "In5.Cu" "In7.Cu" "In8.Cu" "In9.Cu" "In10.Cu")
		(hatch none 0.5)
		(connect_pads
			(clearance 0)
		)
		(min_thickness 0.25)
		(keepout
			(tracks not_allowed)
			(vias allowed)
			(pads allowed)
			(copperpour not_allowed)
			(footprints allowed)
		)
		(placement
			(enabled no)
			(sheetname "")
		)
		(fill yes
			(thermal_gap 0.5)
			(thermal_bridge_width 0.5)
			(island_removal_mode 0)
		)
		(polygon
			(pts
				(arc
					(start 98.621088 -244.789198)
					(mid 98.925888 -244.484398)
					(end 98.621088 -244.179598)
				)
				(arc
					(start 97.681034 -244.179598)
					(mid 97.376234 -244.484398)
					(end 97.681034 -244.789198)
				)
			)
		)
	)
	(zone
		(layers "In3.Cu" "In5.Cu" "In7.Cu" "In8.Cu" "In9.Cu" "In10.Cu")
		(hatch none 0.5)
		(connect_pads
			(clearance 0)
		)
		(min_thickness 0.25)
		(keepout
			(tracks not_allowed)
			(vias allowed)
			(pads allowed)
			(copperpour not_allowed)
			(footprints allowed)
		)
		(placement
			(enabled no)
			(sheetname "")
		)
		(fill yes
			(thermal_gap 0.5)
			(thermal_bridge_width 0.5)
			(island_removal_mode 0)
		)
		(polygon
			(pts
				(arc
					(start 98.621088 -248.029222)
					(mid 98.925888 -247.724422)
					(end 98.621088 -247.419622)
				)
				(arc
					(start 97.681034 -247.419622)
					(mid 97.376234 -247.724422)
					(end 97.681034 -248.029222)
				)
			)
		)
	)
	(zone
		(layers "In3.Cu" "In5.Cu" "In7.Cu" "In8.Cu" "In9.Cu" "In10.Cu")
		(hatch none 0.5)
		(connect_pads
			(clearance 0)
		)
		(min_thickness 0.25)
		(keepout
			(tracks not_allowed)
			(vias allowed)
			(pads allowed)
			(copperpour not_allowed)
			(footprints allowed)
		)
		(placement
			(enabled no)
			(sheetname "")
		)
		(fill yes
			(thermal_gap 0.5)
			(thermal_bridge_width 0.5)
			(island_removal_mode 0)
		)
		(polygon
			(pts
				(arc
					(start 368.174778 -244.788944)
					(mid 368.479578 -244.484144)
					(end 368.174778 -244.179344)
				)
				(arc
					(start 367.234724 -244.179344)
					(mid 366.929924 -244.484144)
					(end 367.234724 -244.788944)
				)
			)
		)
	)
	(zone
		(layers "In3.Cu" "In5.Cu" "In7.Cu" "In8.Cu" "In9.Cu" "In10.Cu")
		(hatch none 0.5)
		(connect_pads
			(clearance 0)
		)
		(min_thickness 0.25)
		(keepout
			(tracks not_allowed)
			(vias allowed)
			(pads allowed)
			(copperpour not_allowed)
			(footprints allowed)
		)
		(placement
			(enabled no)
			(sheetname "")
		)
		(fill yes
			(thermal_gap 0.5)
			(thermal_bridge_width 0.5)
			(island_removal_mode 0)
		)
		(polygon
			(pts
				(arc
					(start 365.35487 -246.408956)
					(mid 365.65967 -246.104156)
					(end 365.35487 -245.799356)
				)
				(arc
					(start 364.414816 -245.799356)
					(mid 364.110016 -246.104156)
					(end 364.414816 -246.408956)
				)
			)
		)
	)
	(zone
		(layers "In3.Cu" "In5.Cu" "In12.Cu" "In14.Cu")
		(hatch none 0.5)
		(connect_pads
			(clearance 0)
		)
		(min_thickness 0.25)
		(keepout
			(tracks not_allowed)
			(vias allowed)
			(pads allowed)
			(copperpour not_allowed)
			(footprints allowed)
		)
		(placement
			(enabled no)
			(sheetname "")
		)
		(fill yes
			(thermal_gap 0.5)
			(thermal_bridge_width 0.5)
			(island_removal_mode 0)
		)
		(polygon
			(pts
				(arc
					(start 210.3247 -405.773382)
					(mid 208.5467 -405.773382)
					(end 210.3247 -405.773382)
				)
			)
		)
	)
	(zone
		(layers "In3.Cu" "In5.Cu" "In12.Cu" "In14.Cu")
		(hatch none 0.5)
		(connect_pads
			(clearance 0)
		)
		(min_thickness 0.25)
		(keepout
			(tracks not_allowed)
			(vias allowed)
			(pads allowed)
			(copperpour not_allowed)
			(footprints allowed)
		)
		(placement
			(enabled no)
			(sheetname "")
		)
		(fill yes
			(thermal_gap 0.5)
			(thermal_bridge_width 0.5)
			(island_removal_mode 0)
		)
		(polygon
			(pts
				(arc
					(start 185.74512 -400.616674)
					(mid 183.96712 -400.616674)
					(end 185.74512 -400.616674)
				)
			)
		)
	)
	(zone
		(layers "In3.Cu" "In5.Cu" "In12.Cu" "In14.Cu")
		(hatch none 0.5)
		(connect_pads
			(clearance 0)
		)
		(min_thickness 0.25)
		(keepout
			(tracks not_allowed)
			(vias allowed)
			(pads allowed)
			(copperpour not_allowed)
			(footprints allowed)
		)
		(placement
			(enabled no)
			(sheetname "")
		)
		(fill yes
			(thermal_gap 0.5)
			(thermal_bridge_width 0.5)
			(island_removal_mode 0)
		)
		(polygon
			(pts
				(arc
					(start 232.4227 -405.773382)
					(mid 230.6447 -405.773382)
					(end 232.4227 -405.773382)
				)
			)
		)
	)
	(zone
		(layers "In3.Cu" "In5.Cu" "In12.Cu" "In14.Cu")
		(hatch none 0.5)
		(connect_pads
			(clearance 0)
		)
		(min_thickness 0.25)
		(keepout
			(tracks not_allowed)
			(vias allowed)
			(pads allowed)
			(copperpour not_allowed)
			(footprints allowed)
		)
		(placement
			(enabled no)
			(sheetname "")
		)
		(fill yes
			(thermal_gap 0.5)
			(thermal_bridge_width 0.5)
			(island_removal_mode 0)
		)
		(polygon
			(pts
				(arc
					(start 212.6107 -406.535382)
					(mid 210.8327 -406.535382)
					(end 212.6107 -406.535382)
				)
			)
		)
	)
	(zone
		(layers "In3.Cu" "In5.Cu" "In12.Cu" "In14.Cu")
		(hatch none 0.5)
		(connect_pads
			(clearance 0)
		)
		(min_thickness 0.25)
		(keepout
			(tracks not_allowed)
			(vias allowed)
			(pads allowed)
			(copperpour not_allowed)
			(footprints allowed)
		)
		(placement
			(enabled no)
			(sheetname "")
		)
		(fill yes
			(thermal_gap 0.5)
			(thermal_bridge_width 0.5)
			(island_removal_mode 0)
		)
		(polygon
			(pts
				(arc
					(start 223.158558 -400.617182)
					(mid 221.380558 -400.617182)
					(end 223.158558 -400.617182)
				)
			)
		)
	)
	(zone
		(layers "In3.Cu" "In5.Cu" "In12.Cu" "In14.Cu")
		(hatch none 0.5)
		(connect_pads
			(clearance 0)
		)
		(min_thickness 0.25)
		(keepout
			(tracks not_allowed)
			(vias allowed)
			(pads allowed)
			(copperpour not_allowed)
			(footprints allowed)
		)
		(placement
			(enabled no)
			(sheetname "")
		)
		(fill yes
			(thermal_gap 0.5)
			(thermal_bridge_width 0.5)
			(island_removal_mode 0)
		)
		(polygon
			(pts
				(arc
					(start 211.8487 -406.535382)
					(mid 210.0707 -406.535382)
					(end 211.8487 -406.535382)
				)
			)
		)
	)
	(zone
		(layers "In3.Cu" "In5.Cu" "In12.Cu" "In14.Cu")
		(hatch none 0.5)
		(connect_pads
			(clearance 0)
		)
		(min_thickness 0.25)
		(keepout
			(tracks not_allowed)
			(vias allowed)
			(pads allowed)
			(copperpour not_allowed)
			(footprints allowed)
		)
		(placement
			(enabled no)
			(sheetname "")
		)
		(fill yes
			(thermal_gap 0.5)
			(thermal_bridge_width 0.5)
			(island_removal_mode 0)
		)
		(polygon
			(pts
				(arc
					(start 220.2307 -405.773382)
					(mid 218.4527 -405.773382)
					(end 220.2307 -405.773382)
				)
			)
		)
	)
	(zone
		(layers "In3.Cu" "In5.Cu" "In12.Cu" "In14.Cu")
		(hatch none 0.5)
		(connect_pads
			(clearance 0)
		)
		(min_thickness 0.25)
		(keepout
			(tracks not_allowed)
			(vias allowed)
			(pads allowed)
			(copperpour not_allowed)
			(footprints allowed)
		)
		(placement
			(enabled no)
			(sheetname "")
		)
		(fill yes
			(thermal_gap 0.5)
			(thermal_bridge_width 0.5)
			(island_removal_mode 0)
		)
		(polygon
			(pts
				(arc
					(start 201.9427 -407.297382)
					(mid 200.1647 -407.297382)
					(end 201.9427 -407.297382)
				)
			)
		)
	)
	(zone
		(layers "In3.Cu" "In5.Cu" "In12.Cu" "In14.Cu")
		(hatch none 0.5)
		(connect_pads
			(clearance 0)
		)
		(min_thickness 0.25)
		(keepout
			(tracks not_allowed)
			(vias allowed)
			(pads allowed)
			(copperpour not_allowed)
			(footprints allowed)
		)
		(placement
			(enabled no)
			(sheetname "")
		)
		(fill yes
			(thermal_gap 0.5)
			(thermal_bridge_width 0.5)
			(island_removal_mode 0)
		)
		(polygon
			(pts
				(arc
					(start 233.826558 -400.617182)
					(mid 232.048558 -400.617182)
					(end 233.826558 -400.617182)
				)
			)
		)
	)
	(zone
		(layers "In3.Cu" "In5.Cu" "In12.Cu" "In14.Cu")
		(hatch none 0.5)
		(connect_pads
			(clearance 0)
		)
		(min_thickness 0.25)
		(keepout
			(tracks not_allowed)
			(vias allowed)
			(pads allowed)
			(copperpour not_allowed)
			(footprints allowed)
		)
		(placement
			(enabled no)
			(sheetname "")
		)
		(fill yes
			(thermal_gap 0.5)
			(thermal_bridge_width 0.5)
			(island_removal_mode 0)
		)
		(polygon
			(pts
				(arc
					(start 223.2787 -405.773382)
					(mid 221.5007 -405.773382)
					(end 223.2787 -405.773382)
				)
			)
		)
	)
	(zone
		(layers "In3.Cu" "In5.Cu" "In12.Cu" "In14.Cu")
		(hatch none 0.5)
		(connect_pads
			(clearance 0)
		)
		(min_thickness 0.25)
		(keepout
			(tracks not_allowed)
			(vias allowed)
			(pads allowed)
			(copperpour not_allowed)
			(footprints allowed)
		)
		(placement
			(enabled no)
			(sheetname "")
		)
		(fill yes
			(thermal_gap 0.5)
			(thermal_bridge_width 0.5)
			(island_removal_mode 0)
		)
		(polygon
			(pts
				(arc
					(start 190.372492 -408.092402)
					(mid 188.594492 -408.092402)
					(end 190.372492 -408.092402)
				)
			)
		)
	)
	(zone
		(layers "In3.Cu" "In5.Cu" "In12.Cu" "In14.Cu")
		(hatch none 0.5)
		(connect_pads
			(clearance 0)
		)
		(min_thickness 0.25)
		(keepout
			(tracks not_allowed)
			(vias allowed)
			(pads allowed)
			(copperpour not_allowed)
			(footprints allowed)
		)
		(placement
			(enabled no)
			(sheetname "")
		)
		(fill yes
			(thermal_gap 0.5)
			(thermal_bridge_width 0.5)
			(island_removal_mode 0)
		)
		(polygon
			(pts
				(arc
					(start 220.339158 -401.920202)
					(mid 218.561158 -401.920202)
					(end 220.339158 -401.920202)
				)
			)
		)
	)
	(zone
		(layers "In3.Cu" "In5.Cu" "In12.Cu" "In14.Cu")
		(hatch none 0.5)
		(connect_pads
			(clearance 0)
		)
		(min_thickness 0.25)
		(keepout
			(tracks not_allowed)
			(vias allowed)
			(pads allowed)
			(copperpour not_allowed)
			(footprints allowed)
		)
		(placement
			(enabled no)
			(sheetname "")
		)
		(fill yes
			(thermal_gap 0.5)
			(thermal_bridge_width 0.5)
			(island_removal_mode 0)
		)
		(polygon
			(pts
				(arc
					(start 198.8947 -408.059382)
					(mid 197.1167 -408.059382)
					(end 198.8947 -408.059382)
				)
			)
		)
	)
	(zone
		(layers "In3.Cu" "In5.Cu" "In12.Cu" "In14.Cu")
		(hatch none 0.5)
		(connect_pads
			(clearance 0)
		)
		(min_thickness 0.25)
		(keepout
			(tracks not_allowed)
			(vias allowed)
			(pads allowed)
			(copperpour not_allowed)
			(footprints allowed)
		)
		(placement
			(enabled no)
			(sheetname "")
		)
		(fill yes
			(thermal_gap 0.5)
			(thermal_bridge_width 0.5)
			(island_removal_mode 0)
		)
		(polygon
			(pts
				(arc
					(start 188.848492 -405.755602)
					(mid 187.070492 -405.755602)
					(end 188.848492 -405.755602)
				)
			)
		)
	)
	(zone
		(layers "In3.Cu" "In5.Cu" "In12.Cu" "In14.Cu")
		(hatch none 0.5)
		(connect_pads
			(clearance 0)
		)
		(min_thickness 0.25)
		(keepout
			(tracks not_allowed)
			(vias allowed)
			(pads allowed)
			(copperpour not_allowed)
			(footprints allowed)
		)
		(placement
			(enabled no)
			(sheetname "")
		)
		(fill yes
			(thermal_gap 0.5)
			(thermal_bridge_width 0.5)
			(island_removal_mode 0)
		)
		(polygon
			(pts
				(arc
					(start 209.671158 -401.920202)
					(mid 207.893158 -401.920202)
					(end 209.671158 -401.920202)
				)
			)
		)
	)
	(zone
		(layers "In3.Cu" "In5.Cu" "In12.Cu" "In14.Cu")
		(hatch none 0.5)
		(connect_pads
			(clearance 0)
		)
		(min_thickness 0.25)
		(keepout
			(tracks not_allowed)
			(vias allowed)
			(pads allowed)
			(copperpour not_allowed)
			(footprints allowed)
		)
		(placement
			(enabled no)
			(sheetname "")
		)
		(fill yes
			(thermal_gap 0.5)
			(thermal_bridge_width 0.5)
			(island_removal_mode 0)
		)
		(polygon
			(pts
				(arc
					(start 220.339158 -400.617182)
					(mid 218.561158 -400.617182)
					(end 220.339158 -400.617182)
				)
			)
		)
	)
	(zone
		(layers "In3.Cu" "In5.Cu" "In12.Cu" "In14.Cu")
		(hatch none 0.5)
		(connect_pads
			(clearance 0)
		)
		(min_thickness 0.25)
		(keepout
			(tracks not_allowed)
			(vias allowed)
			(pads allowed)
			(copperpour not_allowed)
			(footprints allowed)
		)
		(placement
			(enabled no)
			(sheetname "")
		)
		(fill yes
			(thermal_gap 0.5)
			(thermal_bridge_width 0.5)
			(island_removal_mode 0)
		)
		(polygon
			(pts
				(arc
					(start 233.1847 -407.297382)
					(mid 231.4067 -407.297382)
					(end 233.1847 -407.297382)
				)
			)
		)
	)
	(zone
		(layers "In3.Cu" "In5.Cu" "In12.Cu" "In14.Cu")
		(hatch none 0.5)
		(connect_pads
			(clearance 0)
		)
		(min_thickness 0.25)
		(keepout
			(tracks not_allowed)
			(vias allowed)
			(pads allowed)
			(copperpour not_allowed)
			(footprints allowed)
		)
		(placement
			(enabled no)
			(sheetname "")
		)
		(fill yes
			(thermal_gap 0.5)
			(thermal_bridge_width 0.5)
			(island_removal_mode 0)
		)
		(polygon
			(pts
				(arc
					(start 220.9927 -406.535382)
					(mid 219.2147 -406.535382)
					(end 220.9927 -406.535382)
				)
			)
		)
	)
	(zone
		(layers "In3.Cu" "In5.Cu" "In12.Cu" "In14.Cu")
		(hatch none 0.5)
		(connect_pads
			(clearance 0)
		)
		(min_thickness 0.25)
		(keepout
			(tracks not_allowed)
			(vias allowed)
			(pads allowed)
			(copperpour not_allowed)
			(footprints allowed)
		)
		(placement
			(enabled no)
			(sheetname "")
		)
		(fill yes
			(thermal_gap 0.5)
			(thermal_bridge_width 0.5)
			(island_removal_mode 0)
		)
		(polygon
			(pts
				(arc
					(start 220.9927 -405.011382)
					(mid 219.2147 -405.011382)
					(end 220.9927 -405.011382)
				)
			)
		)
	)
	(zone
		(layers "In3.Cu" "In5.Cu" "In12.Cu" "In14.Cu")
		(hatch none 0.5)
		(connect_pads
			(clearance 0)
		)
		(min_thickness 0.25)
		(keepout
			(tracks not_allowed)
			(vias allowed)
			(pads allowed)
			(copperpour not_allowed)
			(footprints allowed)
		)
		(placement
			(enabled no)
			(sheetname "")
		)
		(fill yes
			(thermal_gap 0.5)
			(thermal_bridge_width 0.5)
			(island_removal_mode 0)
		)
		(polygon
			(pts
				(arc
					(start 198.8947 -405.773382)
					(mid 197.1167 -405.773382)
					(end 198.8947 -405.773382)
				)
			)
		)
	)
	(zone
		(layers "In3.Cu" "In5.Cu" "In12.Cu" "In14.Cu")
		(hatch none 0.5)
		(connect_pads
			(clearance 0)
		)
		(min_thickness 0.25)
		(keepout
			(tracks not_allowed)
			(vias allowed)
			(pads allowed)
			(copperpour not_allowed)
			(footprints allowed)
		)
		(placement
			(enabled no)
			(sheetname "")
		)
		(fill yes
			(thermal_gap 0.5)
			(thermal_bridge_width 0.5)
			(island_removal_mode 0)
		)
		(polygon
			(pts
				(arc
					(start 220.9927 -408.059382)
					(mid 219.2147 -408.059382)
					(end 220.9927 -408.059382)
				)
			)
		)
	)
	(zone
		(layers "In3.Cu" "In5.Cu" "In12.Cu" "In14.Cu")
		(hatch none 0.5)
		(connect_pads
			(clearance 0)
		)
		(min_thickness 0.25)
		(keepout
			(tracks not_allowed)
			(vias allowed)
			(pads allowed)
			(copperpour not_allowed)
			(footprints allowed)
		)
		(placement
			(enabled no)
			(sheetname "")
		)
		(fill yes
			(thermal_gap 0.5)
			(thermal_bridge_width 0.5)
			(island_removal_mode 0)
		)
		(polygon
			(pts
				(arc
					(start 233.826558 -401.920202)
					(mid 232.048558 -401.920202)
					(end 233.826558 -401.920202)
				)
			)
		)
	)
	(zone
		(layers "In3.Cu" "In5.Cu" "In12.Cu" "In14.Cu")
		(hatch none 0.5)
		(connect_pads
			(clearance 0)
		)
		(min_thickness 0.25)
		(keepout
			(tracks not_allowed)
			(vias allowed)
			(pads allowed)
			(copperpour not_allowed)
			(footprints allowed)
		)
		(placement
			(enabled no)
			(sheetname "")
		)
		(fill yes
			(thermal_gap 0.5)
			(thermal_bridge_width 0.5)
			(island_removal_mode 0)
		)
		(polygon
			(pts
				(arc
					(start 188.086492 -405.755602)
					(mid 186.308492 -405.755602)
					(end 188.086492 -405.755602)
				)
			)
		)
	)
	(zone
		(layers "In3.Cu" "In5.Cu" "In12.Cu" "In14.Cu")
		(hatch none 0.5)
		(connect_pads
			(clearance 0)
		)
		(min_thickness 0.25)
		(keepout
			(tracks not_allowed)
			(vias allowed)
			(pads allowed)
			(copperpour not_allowed)
			(footprints allowed)
		)
		(placement
			(enabled no)
			(sheetname "")
		)
		(fill yes
			(thermal_gap 0.5)
			(thermal_bridge_width 0.5)
			(island_removal_mode 0)
		)
		(polygon
			(pts
				(arc
					(start 200.4187 -408.059382)
					(mid 198.6407 -408.059382)
					(end 200.4187 -408.059382)
				)
			)
		)
	)
	(zone
		(layers "In3.Cu" "In5.Cu" "In12.Cu" "In14.Cu")
		(hatch none 0.5)
		(connect_pads
			(clearance 0)
		)
		(min_thickness 0.25)
		(keepout
			(tracks not_allowed)
			(vias allowed)
			(pads allowed)
			(copperpour not_allowed)
			(footprints allowed)
		)
		(placement
			(enabled no)
			(sheetname "")
		)
		(fill yes
			(thermal_gap 0.5)
			(thermal_bridge_width 0.5)
			(island_removal_mode 0)
		)
		(polygon
			(pts
				(arc
					(start 186.562492 -408.092402)
					(mid 184.784492 -408.092402)
					(end 186.562492 -408.092402)
				)
			)
		)
	)
	(zone
		(layers "In3.Cu" "In5.Cu" "In12.Cu" "In14.Cu")
		(hatch none 0.5)
		(connect_pads
			(clearance 0)
		)
		(min_thickness 0.25)
		(keepout
			(tracks not_allowed)
			(vias allowed)
			(pads allowed)
			(copperpour not_allowed)
			(footprints allowed)
		)
		(placement
			(enabled no)
			(sheetname "")
		)
		(fill yes
			(thermal_gap 0.5)
			(thermal_bridge_width 0.5)
			(island_removal_mode 0)
		)
		(polygon
			(pts
				(arc
					(start 224.0407 -408.059382)
					(mid 222.2627 -408.059382)
					(end 224.0407 -408.059382)
				)
			)
		)
	)
	(zone
		(layers "In3.Cu" "In5.Cu" "In12.Cu" "In14.Cu")
		(hatch none 0.5)
		(connect_pads
			(clearance 0)
		)
		(min_thickness 0.25)
		(keepout
			(tracks not_allowed)
			(vias allowed)
			(pads allowed)
			(copperpour not_allowed)
			(footprints allowed)
		)
		(placement
			(enabled no)
			(sheetname "")
		)
		(fill yes
			(thermal_gap 0.5)
			(thermal_bridge_width 0.5)
			(island_removal_mode 0)
		)
		(polygon
			(pts
				(arc
					(start 212.490558 -400.617182)
					(mid 210.712558 -400.617182)
					(end 212.490558 -400.617182)
				)
			)
		)
	)
	(zone
		(layers "In3.Cu" "In5.Cu" "In12.Cu" "In14.Cu")
		(hatch none 0.5)
		(connect_pads
			(clearance 0)
		)
		(min_thickness 0.25)
		(keepout
			(tracks not_allowed)
			(vias allowed)
			(pads allowed)
			(copperpour not_allowed)
			(footprints allowed)
		)
		(placement
			(enabled no)
			(sheetname "")
		)
		(fill yes
			(thermal_gap 0.5)
			(thermal_bridge_width 0.5)
			(island_removal_mode 0)
		)
		(polygon
			(pts
				(arc
					(start 209.5627 -405.773382)
					(mid 207.7847 -405.773382)
					(end 209.5627 -405.773382)
				)
			)
		)
	)
	(zone
		(layers "In3.Cu" "In5.Cu" "In12.Cu" "In14.Cu")
		(hatch none 0.5)
		(connect_pads
			(clearance 0)
		)
		(min_thickness 0.25)
		(keepout
			(tracks not_allowed)
			(vias allowed)
			(pads allowed)
			(copperpour not_allowed)
			(footprints allowed)
		)
		(placement
			(enabled no)
			(sheetname "")
		)
		(fill yes
			(thermal_gap 0.5)
			(thermal_bridge_width 0.5)
			(island_removal_mode 0)
		)
		(polygon
			(pts
				(arc
					(start 211.0867 -406.535382)
					(mid 209.3087 -406.535382)
					(end 211.0867 -406.535382)
				)
			)
		)
	)
	(zone
		(layers "In3.Cu" "In5.Cu" "In12.Cu" "In14.Cu")
		(hatch none 0.5)
		(connect_pads
			(clearance 0)
		)
		(min_thickness 0.25)
		(keepout
			(tracks not_allowed)
			(vias allowed)
			(pads allowed)
			(copperpour not_allowed)
			(footprints allowed)
		)
		(placement
			(enabled no)
			(sheetname "")
		)
		(fill yes
			(thermal_gap 0.5)
			(thermal_bridge_width 0.5)
			(island_removal_mode 0)
		)
		(polygon
			(pts
				(arc
					(start 211.093558 -403.223222)
					(mid 209.315558 -403.223222)
					(end 211.093558 -403.223222)
				)
			)
		)
	)
	(zone
		(layers "In3.Cu" "In5.Cu" "In12.Cu" "In14.Cu")
		(hatch none 0.5)
		(connect_pads
			(clearance 0)
		)
		(min_thickness 0.25)
		(keepout
			(tracks not_allowed)
			(vias allowed)
			(pads allowed)
			(copperpour not_allowed)
			(footprints allowed)
		)
		(placement
			(enabled no)
			(sheetname "")
		)
		(fill yes
			(thermal_gap 0.5)
			(thermal_bridge_width 0.5)
			(island_removal_mode 0)
		)
		(polygon
			(pts
				(arc
					(start 201.9427 -406.535382)
					(mid 200.1647 -406.535382)
					(end 201.9427 -406.535382)
				)
			)
		)
	)
	(zone
		(layers "In3.Cu" "In5.Cu" "In12.Cu" "In14.Cu")
		(hatch none 0.5)
		(connect_pads
			(clearance 0)
		)
		(min_thickness 0.25)
		(keepout
			(tracks not_allowed)
			(vias allowed)
			(pads allowed)
			(copperpour not_allowed)
			(footprints allowed)
		)
		(placement
			(enabled no)
			(sheetname "")
		)
		(fill yes
			(thermal_gap 0.5)
			(thermal_bridge_width 0.5)
			(island_removal_mode 0)
		)
		(polygon
			(pts
				(arc
					(start 188.848492 -406.517602)
					(mid 187.070492 -406.517602)
					(end 188.848492 -406.517602)
				)
			)
		)
	)
	(zone
		(layers "In3.Cu" "In5.Cu" "In12.Cu" "In14.Cu")
		(hatch none 0.5)
		(connect_pads
			(clearance 0)
		)
		(min_thickness 0.25)
		(keepout
			(tracks not_allowed)
			(vias allowed)
			(pads allowed)
			(copperpour not_allowed)
			(footprints allowed)
		)
		(placement
			(enabled no)
			(sheetname "")
		)
		(fill yes
			(thermal_gap 0.5)
			(thermal_bridge_width 0.5)
			(island_removal_mode 0)
		)
		(polygon
			(pts
				(arc
					(start 198.1327 -406.535382)
					(mid 196.3547 -406.535382)
					(end 198.1327 -406.535382)
				)
			)
		)
	)
	(zone
		(layers "In3.Cu" "In5.Cu" "In12.Cu" "In14.Cu")
		(hatch none 0.5)
		(connect_pads
			(clearance 0)
		)
		(min_thickness 0.25)
		(keepout
			(tracks not_allowed)
			(vias allowed)
			(pads allowed)
			(copperpour not_allowed)
			(footprints allowed)
		)
		(placement
			(enabled no)
			(sheetname "")
		)
		(fill yes
			(thermal_gap 0.5)
			(thermal_bridge_width 0.5)
			(island_removal_mode 0)
		)
		(polygon
			(pts
				(arc
					(start 230.1367 -407.297382)
					(mid 228.3587 -407.297382)
					(end 230.1367 -407.297382)
				)
			)
		)
	)
	(zone
		(layers "In3.Cu" "In5.Cu" "In12.Cu" "In14.Cu")
		(hatch none 0.5)
		(connect_pads
			(clearance 0)
		)
		(min_thickness 0.25)
		(keepout
			(tracks not_allowed)
			(vias allowed)
			(pads allowed)
			(copperpour not_allowed)
			(footprints allowed)
		)
		(placement
			(enabled no)
			(sheetname "")
		)
		(fill yes
			(thermal_gap 0.5)
			(thermal_bridge_width 0.5)
			(island_removal_mode 0)
		)
		(polygon
			(pts
				(arc
					(start 199.003158 -400.617182)
					(mid 197.225158 -400.617182)
					(end 199.003158 -400.617182)
				)
			)
		)
	)
	(zone
		(layers "In3.Cu" "In5.Cu" "In12.Cu" "In14.Cu")
		(hatch none 0.5)
		(connect_pads
			(clearance 0)
		)
		(min_thickness 0.25)
		(keepout
			(tracks not_allowed)
			(vias allowed)
			(pads allowed)
			(copperpour not_allowed)
			(footprints allowed)
		)
		(placement
			(enabled no)
			(sheetname "")
		)
		(fill yes
			(thermal_gap 0.5)
			(thermal_bridge_width 0.5)
			(island_removal_mode 0)
		)
		(polygon
			(pts
				(arc
					(start 219.4687 -407.297382)
					(mid 217.6907 -407.297382)
					(end 219.4687 -407.297382)
				)
			)
		)
	)
	(zone
		(layers "In3.Cu" "In5.Cu" "In12.Cu" "In14.Cu")
		(hatch none 0.5)
		(connect_pads
			(clearance 0)
		)
		(min_thickness 0.25)
		(keepout
			(tracks not_allowed)
			(vias allowed)
			(pads allowed)
			(copperpour not_allowed)
			(footprints allowed)
		)
		(placement
			(enabled no)
			(sheetname "")
		)
		(fill yes
			(thermal_gap 0.5)
			(thermal_bridge_width 0.5)
			(island_removal_mode 0)
		)
		(polygon
			(pts
				(arc
					(start 187.324492 -406.517602)
					(mid 185.546492 -406.517602)
					(end 187.324492 -406.517602)
				)
			)
		)
	)
	(zone
		(layers "In3.Cu" "In5.Cu" "In12.Cu" "In14.Cu")
		(hatch none 0.5)
		(connect_pads
			(clearance 0)
		)
		(min_thickness 0.25)
		(keepout
			(tracks not_allowed)
			(vias allowed)
			(pads allowed)
			(copperpour not_allowed)
			(footprints allowed)
		)
		(placement
			(enabled no)
			(sheetname "")
		)
		(fill yes
			(thermal_gap 0.5)
			(thermal_bridge_width 0.5)
			(island_removal_mode 0)
		)
		(polygon
			(pts
				(arc
					(start 213.3727 -408.059382)
					(mid 211.5947 -408.059382)
					(end 213.3727 -408.059382)
				)
			)
		)
	)
	(zone
		(layers "In3.Cu" "In5.Cu" "In12.Cu" "In14.Cu")
		(hatch none 0.5)
		(connect_pads
			(clearance 0)
		)
		(min_thickness 0.25)
		(keepout
			(tracks not_allowed)
			(vias allowed)
			(pads allowed)
			(copperpour not_allowed)
			(footprints allowed)
		)
		(placement
			(enabled no)
			(sheetname "")
		)
		(fill yes
			(thermal_gap 0.5)
			(thermal_bridge_width 0.5)
			(island_removal_mode 0)
		)
		(polygon
			(pts
				(arc
					(start 231.6607 -405.773382)
					(mid 229.8827 -405.773382)
					(end 231.6607 -405.773382)
				)
			)
		)
	)
	(zone
		(layers "In3.Cu" "In5.Cu" "In12.Cu" "In14.Cu")
		(hatch none 0.5)
		(connect_pads
			(clearance 0)
		)
		(min_thickness 0.25)
		(keepout
			(tracks not_allowed)
			(vias allowed)
			(pads allowed)
			(copperpour not_allowed)
			(footprints allowed)
		)
		(placement
			(enabled no)
			(sheetname "")
		)
		(fill yes
			(thermal_gap 0.5)
			(thermal_bridge_width 0.5)
			(island_removal_mode 0)
		)
		(polygon
			(pts
				(arc
					(start 233.1847 -406.535382)
					(mid 231.4067 -406.535382)
					(end 233.1847 -406.535382)
				)
			)
		)
	)
	(zone
		(layers "In3.Cu" "In5.Cu" "In12.Cu" "In14.Cu")
		(hatch none 0.5)
		(connect_pads
			(clearance 0)
		)
		(min_thickness 0.25)
		(keepout
			(tracks not_allowed)
			(vias allowed)
			(pads allowed)
			(copperpour not_allowed)
			(footprints allowed)
		)
		(placement
			(enabled no)
			(sheetname "")
		)
		(fill yes
			(thermal_gap 0.5)
			(thermal_bridge_width 0.5)
			(island_removal_mode 0)
		)
		(polygon
			(pts
				(arc
					(start 212.6107 -405.011382)
					(mid 210.8327 -405.011382)
					(end 212.6107 -405.011382)
				)
			)
		)
	)
	(zone
		(layers "In3.Cu" "In5.Cu" "In12.Cu" "In14.Cu")
		(hatch none 0.5)
		(connect_pads
			(clearance 0)
		)
		(min_thickness 0.25)
		(keepout
			(tracks not_allowed)
			(vias allowed)
			(pads allowed)
			(copperpour not_allowed)
			(footprints allowed)
		)
		(placement
			(enabled no)
			(sheetname "")
		)
		(fill yes
			(thermal_gap 0.5)
			(thermal_bridge_width 0.5)
			(island_removal_mode 0)
		)
		(polygon
			(pts
				(arc
					(start 201.9427 -405.011382)
					(mid 200.1647 -405.011382)
					(end 201.9427 -405.011382)
				)
			)
		)
	)
	(zone
		(layers "In3.Cu" "In5.Cu" "In12.Cu" "In14.Cu")
		(hatch none 0.5)
		(connect_pads
			(clearance 0)
		)
		(min_thickness 0.25)
		(keepout
			(tracks not_allowed)
			(vias allowed)
			(pads allowed)
			(copperpour not_allowed)
			(footprints allowed)
		)
		(placement
			(enabled no)
			(sheetname "")
		)
		(fill yes
			(thermal_gap 0.5)
			(thermal_bridge_width 0.5)
			(island_removal_mode 0)
		)
		(polygon
			(pts
				(arc
					(start 188.086492 -406.517602)
					(mid 186.308492 -406.517602)
					(end 188.086492 -406.517602)
				)
			)
		)
	)
	(zone
		(layers "In3.Cu" "In5.Cu" "In12.Cu" "In14.Cu")
		(hatch none 0.5)
		(connect_pads
			(clearance 0)
		)
		(min_thickness 0.25)
		(keepout
			(tracks not_allowed)
			(vias allowed)
			(pads allowed)
			(copperpour not_allowed)
			(footprints allowed)
		)
		(placement
			(enabled no)
			(sheetname "")
		)
		(fill yes
			(thermal_gap 0.5)
			(thermal_bridge_width 0.5)
			(island_removal_mode 0)
		)
		(polygon
			(pts
				(arc
					(start 187.16752 -400.616674)
					(mid 185.38952 -400.616674)
					(end 187.16752 -400.616674)
				)
			)
		)
	)
	(zone
		(layers "In3.Cu" "In5.Cu" "In12.Cu" "In14.Cu")
		(hatch none 0.5)
		(connect_pads
			(clearance 0)
		)
		(min_thickness 0.25)
		(keepout
			(tracks not_allowed)
			(vias allowed)
			(pads allowed)
			(copperpour not_allowed)
			(footprints allowed)
		)
		(placement
			(enabled no)
			(sheetname "")
		)
		(fill yes
			(thermal_gap 0.5)
			(thermal_bridge_width 0.5)
			(island_removal_mode 0)
		)
		(polygon
			(pts
				(arc
					(start 201.1807 -405.773382)
					(mid 199.4027 -405.773382)
					(end 201.1807 -405.773382)
				)
			)
		)
	)
	(zone
		(layers "In3.Cu" "In5.Cu" "In12.Cu" "In14.Cu")
		(hatch none 0.5)
		(connect_pads
			(clearance 0)
		)
		(min_thickness 0.25)
		(keepout
			(tracks not_allowed)
			(vias allowed)
			(pads allowed)
			(copperpour not_allowed)
			(footprints allowed)
		)
		(placement
			(enabled no)
			(sheetname "")
		)
		(fill yes
			(thermal_gap 0.5)
			(thermal_bridge_width 0.5)
			(island_removal_mode 0)
		)
		(polygon
			(pts
				(arc
					(start 222.5167 -405.773382)
					(mid 220.7387 -405.773382)
					(end 222.5167 -405.773382)
				)
			)
		)
	)
	(zone
		(layers "In3.Cu" "In5.Cu" "In12.Cu" "In14.Cu")
		(hatch none 0.5)
		(connect_pads
			(clearance 0)
		)
		(min_thickness 0.25)
		(keepout
			(tracks not_allowed)
			(vias allowed)
			(pads allowed)
			(copperpour not_allowed)
			(footprints allowed)
		)
		(placement
			(enabled no)
			(sheetname "")
		)
		(fill yes
			(thermal_gap 0.5)
			(thermal_bridge_width 0.5)
			(island_removal_mode 0)
		)
		(polygon
			(pts
				(arc
					(start 211.8487 -407.297382)
					(mid 210.0707 -407.297382)
					(end 211.8487 -407.297382)
				)
			)
		)
	)
	(zone
		(layers "In3.Cu" "In5.Cu" "In12.Cu" "In14.Cu")
		(hatch none 0.5)
		(connect_pads
			(clearance 0)
		)
		(min_thickness 0.25)
		(keepout
			(tracks not_allowed)
			(vias allowed)
			(pads allowed)
			(copperpour not_allowed)
			(footprints allowed)
		)
		(placement
			(enabled no)
			(sheetname "")
		)
		(fill yes
			(thermal_gap 0.5)
			(thermal_bridge_width 0.5)
			(island_removal_mode 0)
		)
		(polygon
			(pts
				(arc
					(start 201.1807 -408.059382)
					(mid 199.4027 -408.059382)
					(end 201.1807 -408.059382)
				)
			)
		)
	)
	(zone
		(layers "In3.Cu" "In5.Cu" "In12.Cu" "In14.Cu")
		(hatch none 0.5)
		(connect_pads
			(clearance 0)
		)
		(min_thickness 0.25)
		(keepout
			(tracks not_allowed)
			(vias allowed)
			(pads allowed)
			(copperpour not_allowed)
			(footprints allowed)
		)
		(placement
			(enabled no)
			(sheetname "")
		)
		(fill yes
			(thermal_gap 0.5)
			(thermal_bridge_width 0.5)
			(island_removal_mode 0)
		)
		(polygon
			(pts
				(arc
					(start 223.2787 -406.535382)
					(mid 221.5007 -406.535382)
					(end 223.2787 -406.535382)
				)
			)
		)
	)
	(zone
		(layers "In3.Cu" "In5.Cu" "In12.Cu" "In14.Cu")
		(hatch none 0.5)
		(connect_pads
			(clearance 0)
		)
		(min_thickness 0.25)
		(keepout
			(tracks not_allowed)
			(vias allowed)
			(pads allowed)
			(copperpour not_allowed)
			(footprints allowed)
		)
		(placement
			(enabled no)
			(sheetname "")
		)
		(fill yes
			(thermal_gap 0.5)
			(thermal_bridge_width 0.5)
			(island_removal_mode 0)
		)
		(polygon
			(pts
				(arc
					(start 233.9467 -408.059382)
					(mid 232.1687 -408.059382)
					(end 233.9467 -408.059382)
				)
			)
		)
	)
	(zone
		(layers "In3.Cu" "In5.Cu" "In12.Cu" "In14.Cu")
		(hatch none 0.5)
		(connect_pads
			(clearance 0)
		)
		(min_thickness 0.25)
		(keepout
			(tracks not_allowed)
			(vias allowed)
			(pads allowed)
			(copperpour not_allowed)
			(footprints allowed)
		)
		(placement
			(enabled no)
			(sheetname "")
		)
		(fill yes
			(thermal_gap 0.5)
			(thermal_bridge_width 0.5)
			(island_removal_mode 0)
		)
		(polygon
			(pts
				(arc
					(start 233.9467 -405.773382)
					(mid 232.1687 -405.773382)
					(end 233.9467 -405.773382)
				)
			)
		)
	)
	(zone
		(layers "In3.Cu" "In5.Cu" "In12.Cu" "In14.Cu")
		(hatch none 0.5)
		(connect_pads
			(clearance 0)
		)
		(min_thickness 0.25)
		(keepout
			(tracks not_allowed)
			(vias allowed)
			(pads allowed)
			(copperpour not_allowed)
			(footprints allowed)
		)
		(placement
			(enabled no)
			(sheetname "")
		)
		(fill yes
			(thermal_gap 0.5)
			(thermal_bridge_width 0.5)
			(island_removal_mode 0)
		)
		(polygon
			(pts
				(arc
					(start 211.8487 -408.059382)
					(mid 210.0707 -408.059382)
					(end 211.8487 -408.059382)
				)
			)
		)
	)
	(zone
		(layers "In3.Cu" "In5.Cu" "In12.Cu" "In14.Cu")
		(hatch none 0.5)
		(connect_pads
			(clearance 0)
		)
		(min_thickness 0.25)
		(keepout
			(tracks not_allowed)
			(vias allowed)
			(pads allowed)
			(copperpour not_allowed)
			(footprints allowed)
		)
		(placement
			(enabled no)
			(sheetname "")
		)
		(fill yes
			(thermal_gap 0.5)
			(thermal_bridge_width 0.5)
			(island_removal_mode 0)
		)
		(polygon
			(pts
				(arc
					(start 233.1847 -405.011382)
					(mid 231.4067 -405.011382)
					(end 233.1847 -405.011382)
				)
			)
		)
	)
	(zone
		(layers "In3.Cu" "In5.Cu" "In12.Cu" "In14.Cu")
		(hatch none 0.5)
		(connect_pads
			(clearance 0)
		)
		(min_thickness 0.25)
		(keepout
			(tracks not_allowed)
			(vias allowed)
			(pads allowed)
			(copperpour not_allowed)
			(footprints allowed)
		)
		(placement
			(enabled no)
			(sheetname "")
		)
		(fill yes
			(thermal_gap 0.5)
			(thermal_bridge_width 0.5)
			(island_removal_mode 0)
		)
		(polygon
			(pts
				(arc
					(start 223.2787 -408.059382)
					(mid 221.5007 -408.059382)
					(end 223.2787 -408.059382)
				)
			)
		)
	)
	(zone
		(layers "In3.Cu" "In5.Cu" "In12.Cu" "In14.Cu")
		(hatch none 0.5)
		(connect_pads
			(clearance 0)
		)
		(min_thickness 0.25)
		(keepout
			(tracks not_allowed)
			(vias allowed)
			(pads allowed)
			(copperpour not_allowed)
			(footprints allowed)
		)
		(placement
			(enabled no)
			(sheetname "")
		)
		(fill yes
			(thermal_gap 0.5)
			(thermal_bridge_width 0.5)
			(island_removal_mode 0)
		)
		(polygon
			(pts
				(arc
					(start 198.8947 -405.011382)
					(mid 197.1167 -405.011382)
					(end 198.8947 -405.011382)
				)
			)
		)
	)
	(zone
		(layers "In3.Cu" "In5.Cu" "In12.Cu" "In14.Cu")
		(hatch none 0.5)
		(connect_pads
			(clearance 0)
		)
		(min_thickness 0.25)
		(keepout
			(tracks not_allowed)
			(vias allowed)
			(pads allowed)
			(copperpour not_allowed)
			(footprints allowed)
		)
		(placement
			(enabled no)
			(sheetname "")
		)
		(fill yes
			(thermal_gap 0.5)
			(thermal_bridge_width 0.5)
			(island_removal_mode 0)
		)
		(polygon
			(pts
				(arc
					(start 198.8947 -407.297382)
					(mid 197.1167 -407.297382)
					(end 198.8947 -407.297382)
				)
			)
		)
	)
	(zone
		(layers "In3.Cu" "In5.Cu" "In12.Cu" "In14.Cu")
		(hatch none 0.5)
		(connect_pads
			(clearance 0)
		)
		(min_thickness 0.25)
		(keepout
			(tracks not_allowed)
			(vias allowed)
			(pads allowed)
			(copperpour not_allowed)
			(footprints allowed)
		)
		(placement
			(enabled no)
			(sheetname "")
		)
		(fill yes
			(thermal_gap 0.5)
			(thermal_bridge_width 0.5)
			(island_removal_mode 0)
		)
		(polygon
			(pts
				(arc
					(start 221.761558 -403.223222)
					(mid 219.983558 -403.223222)
					(end 221.761558 -403.223222)
				)
			)
		)
	)
	(zone
		(layers "In3.Cu" "In5.Cu" "In12.Cu" "In14.Cu")
		(hatch none 0.5)
		(connect_pads
			(clearance 0)
		)
		(min_thickness 0.25)
		(keepout
			(tracks not_allowed)
			(vias allowed)
			(pads allowed)
			(copperpour not_allowed)
			(footprints allowed)
		)
		(placement
			(enabled no)
			(sheetname "")
		)
		(fill yes
			(thermal_gap 0.5)
			(thermal_bridge_width 0.5)
			(island_removal_mode 0)
		)
		(polygon
			(pts
				(arc
					(start 231.6607 -405.011382)
					(mid 229.8827 -405.011382)
					(end 231.6607 -405.011382)
				)
			)
		)
	)
	(zone
		(layers "In3.Cu" "In5.Cu" "In12.Cu" "In14.Cu")
		(hatch none 0.5)
		(connect_pads
			(clearance 0)
		)
		(min_thickness 0.25)
		(keepout
			(tracks not_allowed)
			(vias allowed)
			(pads allowed)
			(copperpour not_allowed)
			(footprints allowed)
		)
		(placement
			(enabled no)
			(sheetname "")
		)
		(fill yes
			(thermal_gap 0.5)
			(thermal_bridge_width 0.5)
			(island_removal_mode 0)
		)
		(polygon
			(pts
				(arc
					(start 221.761558 -400.617182)
					(mid 219.983558 -400.617182)
					(end 221.761558 -400.617182)
				)
			)
		)
	)
	(zone
		(layers "In3.Cu" "In5.Cu" "In12.Cu" "In14.Cu")
		(hatch none 0.5)
		(connect_pads
			(clearance 0)
		)
		(min_thickness 0.25)
		(keepout
			(tracks not_allowed)
			(vias allowed)
			(pads allowed)
			(copperpour not_allowed)
			(footprints allowed)
		)
		(placement
			(enabled no)
			(sheetname "")
		)
		(fill yes
			(thermal_gap 0.5)
			(thermal_bridge_width 0.5)
			(island_removal_mode 0)
		)
		(polygon
			(pts
				(arc
					(start 189.610492 -408.092402)
					(mid 187.832492 -408.092402)
					(end 189.610492 -408.092402)
				)
			)
		)
	)
	(zone
		(layers "In3.Cu" "In5.Cu" "In12.Cu" "In14.Cu")
		(hatch none 0.5)
		(connect_pads
			(clearance 0)
		)
		(min_thickness 0.25)
		(keepout
			(tracks not_allowed)
			(vias allowed)
			(pads allowed)
			(copperpour not_allowed)
			(footprints allowed)
		)
		(placement
			(enabled no)
			(sheetname "")
		)
		(fill yes
			(thermal_gap 0.5)
			(thermal_bridge_width 0.5)
			(island_removal_mode 0)
		)
		(polygon
			(pts
				(arc
					(start 209.5627 -407.297382)
					(mid 207.7847 -407.297382)
					(end 209.5627 -407.297382)
				)
			)
		)
	)
	(zone
		(layers "In3.Cu" "In5.Cu" "In12.Cu" "In14.Cu")
		(hatch none 0.5)
		(connect_pads
			(clearance 0)
		)
		(min_thickness 0.25)
		(keepout
			(tracks not_allowed)
			(vias allowed)
			(pads allowed)
			(copperpour not_allowed)
			(footprints allowed)
		)
		(placement
			(enabled no)
			(sheetname "")
		)
		(fill yes
			(thermal_gap 0.5)
			(thermal_bridge_width 0.5)
			(island_removal_mode 0)
		)
		(polygon
			(pts
				(arc
					(start 232.4227 -407.297382)
					(mid 230.6447 -407.297382)
					(end 232.4227 -407.297382)
				)
			)
		)
	)
	(zone
		(layers "In3.Cu" "In5.Cu" "In12.Cu" "In14.Cu")
		(hatch none 0.5)
		(connect_pads
			(clearance 0)
		)
		(min_thickness 0.25)
		(keepout
			(tracks not_allowed)
			(vias allowed)
			(pads allowed)
			(copperpour not_allowed)
			(footprints allowed)
		)
		(placement
			(enabled no)
			(sheetname "")
		)
		(fill yes
			(thermal_gap 0.5)
			(thermal_bridge_width 0.5)
			(island_removal_mode 0)
		)
		(polygon
			(pts
				(arc
					(start 209.671158 -400.617182)
					(mid 207.893158 -400.617182)
					(end 209.671158 -400.617182)
				)
			)
		)
	)
	(zone
		(layers "In3.Cu" "In5.Cu" "In12.Cu" "In14.Cu")
		(hatch none 0.5)
		(connect_pads
			(clearance 0)
		)
		(min_thickness 0.25)
		(keepout
			(tracks not_allowed)
			(vias allowed)
			(pads allowed)
			(copperpour not_allowed)
			(footprints allowed)
		)
		(placement
			(enabled no)
			(sheetname "")
		)
		(fill yes
			(thermal_gap 0.5)
			(thermal_bridge_width 0.5)
			(island_removal_mode 0)
		)
		(polygon
			(pts
				(arc
					(start 186.562492 -407.330402)
					(mid 184.784492 -407.330402)
					(end 186.562492 -407.330402)
				)
			)
		)
	)
	(zone
		(layers "In3.Cu" "In5.Cu" "In12.Cu" "In14.Cu")
		(hatch none 0.5)
		(connect_pads
			(clearance 0)
		)
		(min_thickness 0.25)
		(keepout
			(tracks not_allowed)
			(vias allowed)
			(pads allowed)
			(copperpour not_allowed)
			(footprints allowed)
		)
		(placement
			(enabled no)
			(sheetname "")
		)
		(fill yes
			(thermal_gap 0.5)
			(thermal_bridge_width 0.5)
			(island_removal_mode 0)
		)
		(polygon
			(pts
				(arc
					(start 232.4227 -406.535382)
					(mid 230.6447 -406.535382)
					(end 232.4227 -406.535382)
				)
			)
		)
	)
	(zone
		(layers "In3.Cu" "In5.Cu" "In12.Cu" "In14.Cu")
		(hatch none 0.5)
		(connect_pads
			(clearance 0)
		)
		(min_thickness 0.25)
		(keepout
			(tracks not_allowed)
			(vias allowed)
			(pads allowed)
			(copperpour not_allowed)
			(footprints allowed)
		)
		(placement
			(enabled no)
			(sheetname "")
		)
		(fill yes
			(thermal_gap 0.5)
			(thermal_bridge_width 0.5)
			(island_removal_mode 0)
		)
		(polygon
			(pts
				(arc
					(start 231.6607 -406.535382)
					(mid 229.8827 -406.535382)
					(end 231.6607 -406.535382)
				)
			)
		)
	)
	(zone
		(layers "In3.Cu" "In5.Cu" "In12.Cu" "In14.Cu")
		(hatch none 0.5)
		(connect_pads
			(clearance 0)
		)
		(min_thickness 0.25)
		(keepout
			(tracks not_allowed)
			(vias allowed)
			(pads allowed)
			(copperpour not_allowed)
			(footprints allowed)
		)
		(placement
			(enabled no)
			(sheetname "")
		)
		(fill yes
			(thermal_gap 0.5)
			(thermal_bridge_width 0.5)
			(island_removal_mode 0)
		)
		(polygon
			(pts
				(arc
					(start 188.56452 -403.222714)
					(mid 186.78652 -403.222714)
					(end 188.56452 -403.222714)
				)
			)
		)
	)
	(zone
		(layers "In3.Cu" "In5.Cu" "In12.Cu" "In14.Cu")
		(hatch none 0.5)
		(connect_pads
			(clearance 0)
		)
		(min_thickness 0.25)
		(keepout
			(tracks not_allowed)
			(vias allowed)
			(pads allowed)
			(copperpour not_allowed)
			(footprints allowed)
		)
		(placement
			(enabled no)
			(sheetname "")
		)
		(fill yes
			(thermal_gap 0.5)
			(thermal_bridge_width 0.5)
			(island_removal_mode 0)
		)
		(polygon
			(pts
				(arc
					(start 188.086492 -408.092402)
					(mid 186.308492 -408.092402)
					(end 188.086492 -408.092402)
				)
			)
		)
	)
	(zone
		(layers "In3.Cu" "In5.Cu" "In12.Cu" "In14.Cu")
		(hatch none 0.5)
		(connect_pads
			(clearance 0)
		)
		(min_thickness 0.25)
		(keepout
			(tracks not_allowed)
			(vias allowed)
			(pads allowed)
			(copperpour not_allowed)
			(footprints allowed)
		)
		(placement
			(enabled no)
			(sheetname "")
		)
		(fill yes
			(thermal_gap 0.5)
			(thermal_bridge_width 0.5)
			(island_removal_mode 0)
		)
		(polygon
			(pts
				(arc
					(start 233.9467 -405.011382)
					(mid 232.1687 -405.011382)
					(end 233.9467 -405.011382)
				)
			)
		)
	)
	(zone
		(layers "In3.Cu" "In5.Cu" "In12.Cu" "In14.Cu")
		(hatch none 0.5)
		(connect_pads
			(clearance 0)
		)
		(min_thickness 0.25)
		(keepout
			(tracks not_allowed)
			(vias allowed)
			(pads allowed)
			(copperpour not_allowed)
			(footprints allowed)
		)
		(placement
			(enabled no)
			(sheetname "")
		)
		(fill yes
			(thermal_gap 0.5)
			(thermal_bridge_width 0.5)
			(island_removal_mode 0)
		)
		(polygon
			(pts
				(arc
					(start 187.324492 -404.993602)
					(mid 185.546492 -404.993602)
					(end 187.324492 -404.993602)
				)
			)
		)
	)
	(zone
		(layers "In3.Cu" "In5.Cu" "In12.Cu" "In14.Cu")
		(hatch none 0.5)
		(connect_pads
			(clearance 0)
		)
		(min_thickness 0.25)
		(keepout
			(tracks not_allowed)
			(vias allowed)
			(pads allowed)
			(copperpour not_allowed)
			(footprints allowed)
		)
		(placement
			(enabled no)
			(sheetname "")
		)
		(fill yes
			(thermal_gap 0.5)
			(thermal_bridge_width 0.5)
			(island_removal_mode 0)
		)
		(polygon
			(pts
				(arc
					(start 186.562492 -405.755602)
					(mid 184.784492 -405.755602)
					(end 186.562492 -405.755602)
				)
			)
		)
	)
	(zone
		(layers "In3.Cu" "In5.Cu" "In12.Cu" "In14.Cu")
		(hatch none 0.5)
		(connect_pads
			(clearance 0)
		)
		(min_thickness 0.25)
		(keepout
			(tracks not_allowed)
			(vias allowed)
			(pads allowed)
			(copperpour not_allowed)
			(footprints allowed)
		)
		(placement
			(enabled no)
			(sheetname "")
		)
		(fill yes
			(thermal_gap 0.5)
			(thermal_bridge_width 0.5)
			(island_removal_mode 0)
		)
		(polygon
			(pts
				(arc
					(start 200.425558 -400.617182)
					(mid 198.647558 -400.617182)
					(end 200.425558 -400.617182)
				)
			)
		)
	)
	(zone
		(layers "In3.Cu" "In5.Cu" "In12.Cu" "In14.Cu")
		(hatch none 0.5)
		(connect_pads
			(clearance 0)
		)
		(min_thickness 0.25)
		(keepout
			(tracks not_allowed)
			(vias allowed)
			(pads allowed)
			(copperpour not_allowed)
			(footprints allowed)
		)
		(placement
			(enabled no)
			(sheetname "")
		)
		(fill yes
			(thermal_gap 0.5)
			(thermal_bridge_width 0.5)
			(island_removal_mode 0)
		)
		(polygon
			(pts
				(arc
					(start 234.7087 -407.297382)
					(mid 232.9307 -407.297382)
					(end 234.7087 -407.297382)
				)
			)
		)
	)
	(zone
		(layers "In3.Cu" "In5.Cu" "In12.Cu" "In14.Cu")
		(hatch none 0.5)
		(connect_pads
			(clearance 0)
		)
		(min_thickness 0.25)
		(keepout
			(tracks not_allowed)
			(vias allowed)
			(pads allowed)
			(copperpour not_allowed)
			(footprints allowed)
		)
		(placement
			(enabled no)
			(sheetname "")
		)
		(fill yes
			(thermal_gap 0.5)
			(thermal_bridge_width 0.5)
			(island_removal_mode 0)
		)
		(polygon
			(pts
				(arc
					(start 188.848492 -404.993602)
					(mid 187.070492 -404.993602)
					(end 188.848492 -404.993602)
				)
			)
		)
	)
	(zone
		(layers "In3.Cu" "In5.Cu" "In12.Cu" "In14.Cu")
		(hatch none 0.5)
		(connect_pads
			(clearance 0)
		)
		(min_thickness 0.25)
		(keepout
			(tracks not_allowed)
			(vias allowed)
			(pads allowed)
			(copperpour not_allowed)
			(footprints allowed)
		)
		(placement
			(enabled no)
			(sheetname "")
		)
		(fill yes
			(thermal_gap 0.5)
			(thermal_bridge_width 0.5)
			(island_removal_mode 0)
		)
		(polygon
			(pts
				(arc
					(start 198.1327 -405.773382)
					(mid 196.3547 -405.773382)
					(end 198.1327 -405.773382)
				)
			)
		)
	)
	(zone
		(layers "In3.Cu" "In5.Cu" "In12.Cu" "In14.Cu")
		(hatch none 0.5)
		(connect_pads
			(clearance 0)
		)
		(min_thickness 0.25)
		(keepout
			(tracks not_allowed)
			(vias allowed)
			(pads allowed)
			(copperpour not_allowed)
			(footprints allowed)
		)
		(placement
			(enabled no)
			(sheetname "")
		)
		(fill yes
			(thermal_gap 0.5)
			(thermal_bridge_width 0.5)
			(island_removal_mode 0)
		)
		(polygon
			(pts
				(arc
					(start 231.007158 -400.617182)
					(mid 229.229158 -400.617182)
					(end 231.007158 -400.617182)
				)
			)
		)
	)
	(zone
		(layers "In3.Cu" "In5.Cu" "In12.Cu" "In14.Cu")
		(hatch none 0.5)
		(connect_pads
			(clearance 0)
		)
		(min_thickness 0.25)
		(keepout
			(tracks not_allowed)
			(vias allowed)
			(pads allowed)
			(copperpour not_allowed)
			(footprints allowed)
		)
		(placement
			(enabled no)
			(sheetname "")
		)
		(fill yes
			(thermal_gap 0.5)
			(thermal_bridge_width 0.5)
			(island_removal_mode 0)
		)
		(polygon
			(pts
				(arc
					(start 190.372492 -406.517602)
					(mid 188.594492 -406.517602)
					(end 190.372492 -406.517602)
				)
			)
		)
	)
	(zone
		(layers "In3.Cu" "In5.Cu" "In12.Cu" "In14.Cu")
		(hatch none 0.5)
		(connect_pads
			(clearance 0)
		)
		(min_thickness 0.25)
		(keepout
			(tracks not_allowed)
			(vias allowed)
			(pads allowed)
			(copperpour not_allowed)
			(footprints allowed)
		)
		(placement
			(enabled no)
			(sheetname "")
		)
		(fill yes
			(thermal_gap 0.5)
			(thermal_bridge_width 0.5)
			(island_removal_mode 0)
		)
		(polygon
			(pts
				(arc
					(start 232.4227 -405.011382)
					(mid 230.6447 -405.011382)
					(end 232.4227 -405.011382)
				)
			)
		)
	)
	(zone
		(layers "In3.Cu" "In5.Cu" "In12.Cu" "In14.Cu")
		(hatch none 0.5)
		(connect_pads
			(clearance 0)
		)
		(min_thickness 0.25)
		(keepout
			(tracks not_allowed)
			(vias allowed)
			(pads allowed)
			(copperpour not_allowed)
			(footprints allowed)
		)
		(placement
			(enabled no)
			(sheetname "")
		)
		(fill yes
			(thermal_gap 0.5)
			(thermal_bridge_width 0.5)
			(island_removal_mode 0)
		)
		(polygon
			(pts
				(arc
					(start 208.0387 -408.059382)
					(mid 206.2607 -408.059382)
					(end 208.0387 -408.059382)
				)
			)
		)
	)
	(zone
		(layers "In3.Cu" "In5.Cu" "In12.Cu" "In14.Cu")
		(hatch none 0.5)
		(connect_pads
			(clearance 0)
		)
		(min_thickness 0.25)
		(keepout
			(tracks not_allowed)
			(vias allowed)
			(pads allowed)
			(copperpour not_allowed)
			(footprints allowed)
		)
		(placement
			(enabled no)
			(sheetname "")
		)
		(fill yes
			(thermal_gap 0.5)
			(thermal_bridge_width 0.5)
			(island_removal_mode 0)
		)
		(polygon
			(pts
				(arc
					(start 188.848492 -408.092402)
					(mid 187.070492 -408.092402)
					(end 188.848492 -408.092402)
				)
			)
		)
	)
	(zone
		(layers "In3.Cu" "In5.Cu" "In12.Cu" "In14.Cu")
		(hatch none 0.5)
		(connect_pads
			(clearance 0)
		)
		(min_thickness 0.25)
		(keepout
			(tracks not_allowed)
			(vias allowed)
			(pads allowed)
			(copperpour not_allowed)
			(footprints allowed)
		)
		(placement
			(enabled no)
			(sheetname "")
		)
		(fill yes
			(thermal_gap 0.5)
			(thermal_bridge_width 0.5)
			(island_removal_mode 0)
		)
		(polygon
			(pts
				(arc
					(start 189.610492 -404.993602)
					(mid 187.832492 -404.993602)
					(end 189.610492 -404.993602)
				)
			)
		)
	)
	(zone
		(layers "In3.Cu" "In5.Cu" "In12.Cu" "In14.Cu")
		(hatch none 0.5)
		(connect_pads
			(clearance 0)
		)
		(min_thickness 0.25)
		(keepout
			(tracks not_allowed)
			(vias allowed)
			(pads allowed)
			(copperpour not_allowed)
			(footprints allowed)
		)
		(placement
			(enabled no)
			(sheetname "")
		)
		(fill yes
			(thermal_gap 0.5)
			(thermal_bridge_width 0.5)
			(island_removal_mode 0)
		)
		(polygon
			(pts
				(arc
					(start 187.324492 -407.330402)
					(mid 185.546492 -407.330402)
					(end 187.324492 -407.330402)
				)
			)
		)
	)
	(zone
		(layers "In3.Cu" "In5.Cu" "In12.Cu" "In14.Cu")
		(hatch none 0.5)
		(connect_pads
			(clearance 0)
		)
		(min_thickness 0.25)
		(keepout
			(tracks not_allowed)
			(vias allowed)
			(pads allowed)
			(copperpour not_allowed)
			(footprints allowed)
		)
		(placement
			(enabled no)
			(sheetname "")
		)
		(fill yes
			(thermal_gap 0.5)
			(thermal_bridge_width 0.5)
			(island_removal_mode 0)
		)
		(polygon
			(pts
				(arc
					(start 201.1807 -405.011382)
					(mid 199.4027 -405.011382)
					(end 201.1807 -405.011382)
				)
			)
		)
	)
	(zone
		(layers "In3.Cu" "In5.Cu" "In12.Cu" "In14.Cu")
		(hatch none 0.5)
		(connect_pads
			(clearance 0)
		)
		(min_thickness 0.25)
		(keepout
			(tracks not_allowed)
			(vias allowed)
			(pads allowed)
			(copperpour not_allowed)
			(footprints allowed)
		)
		(placement
			(enabled no)
			(sheetname "")
		)
		(fill yes
			(thermal_gap 0.5)
			(thermal_bridge_width 0.5)
			(island_removal_mode 0)
		)
		(polygon
			(pts
				(arc
					(start 233.1847 -408.059382)
					(mid 231.4067 -408.059382)
					(end 233.1847 -408.059382)
				)
			)
		)
	)
	(zone
		(layers "In3.Cu" "In5.Cu" "In12.Cu" "In14.Cu")
		(hatch none 0.5)
		(connect_pads
			(clearance 0)
		)
		(min_thickness 0.25)
		(keepout
			(tracks not_allowed)
			(vias allowed)
			(pads allowed)
			(copperpour not_allowed)
			(footprints allowed)
		)
		(placement
			(enabled no)
			(sheetname "")
		)
		(fill yes
			(thermal_gap 0.5)
			(thermal_bridge_width 0.5)
			(island_removal_mode 0)
		)
		(polygon
			(pts
				(arc
					(start 233.1847 -405.773382)
					(mid 231.4067 -405.773382)
					(end 233.1847 -405.773382)
				)
			)
		)
	)
	(zone
		(layers "In3.Cu" "In5.Cu" "In12.Cu" "In14.Cu")
		(hatch none 0.5)
		(connect_pads
			(clearance 0)
		)
		(min_thickness 0.25)
		(keepout
			(tracks not_allowed)
			(vias allowed)
			(pads allowed)
			(copperpour not_allowed)
			(footprints allowed)
		)
		(placement
			(enabled no)
			(sheetname "")
		)
		(fill yes
			(thermal_gap 0.5)
			(thermal_bridge_width 0.5)
			(island_removal_mode 0)
		)
		(polygon
			(pts
				(arc
					(start 187.324492 -408.092402)
					(mid 185.546492 -408.092402)
					(end 187.324492 -408.092402)
				)
			)
		)
	)
	(zone
		(layers "In3.Cu" "In5.Cu" "In12.Cu" "In14.Cu")
		(hatch none 0.5)
		(connect_pads
			(clearance 0)
		)
		(min_thickness 0.25)
		(keepout
			(tracks not_allowed)
			(vias allowed)
			(pads allowed)
			(copperpour not_allowed)
			(footprints allowed)
		)
		(placement
			(enabled no)
			(sheetname "")
		)
		(fill yes
			(thermal_gap 0.5)
			(thermal_bridge_width 0.5)
			(island_removal_mode 0)
		)
		(polygon
			(pts
				(arc
					(start 190.372492 -405.755602)
					(mid 188.594492 -405.755602)
					(end 190.372492 -405.755602)
				)
			)
		)
	)
	(zone
		(layers "In3.Cu" "In5.Cu" "In12.Cu" "In14.Cu")
		(hatch none 0.5)
		(connect_pads
			(clearance 0)
		)
		(min_thickness 0.25)
		(keepout
			(tracks not_allowed)
			(vias allowed)
			(pads allowed)
			(copperpour not_allowed)
			(footprints allowed)
		)
		(placement
			(enabled no)
			(sheetname "")
		)
		(fill yes
			(thermal_gap 0.5)
			(thermal_bridge_width 0.5)
			(island_removal_mode 0)
		)
		(polygon
			(pts
				(arc
					(start 233.9467 -406.535382)
					(mid 232.1687 -406.535382)
					(end 233.9467 -406.535382)
				)
			)
		)
	)
	(zone
		(layers "In3.Cu" "In5.Cu" "In12.Cu" "In14.Cu")
		(hatch none 0.5)
		(connect_pads
			(clearance 0)
		)
		(min_thickness 0.25)
		(keepout
			(tracks not_allowed)
			(vias allowed)
			(pads allowed)
			(copperpour not_allowed)
			(footprints allowed)
		)
		(placement
			(enabled no)
			(sheetname "")
		)
		(fill yes
			(thermal_gap 0.5)
			(thermal_bridge_width 0.5)
			(island_removal_mode 0)
		)
		(polygon
			(pts
				(arc
					(start 198.1327 -407.297382)
					(mid 196.3547 -407.297382)
					(end 198.1327 -407.297382)
				)
			)
		)
	)
	(zone
		(layers "In3.Cu" "In5.Cu" "In12.Cu" "In14.Cu")
		(hatch none 0.5)
		(connect_pads
			(clearance 0)
		)
		(min_thickness 0.25)
		(keepout
			(tracks not_allowed)
			(vias allowed)
			(pads allowed)
			(copperpour not_allowed)
			(footprints allowed)
		)
		(placement
			(enabled no)
			(sheetname "")
		)
		(fill yes
			(thermal_gap 0.5)
			(thermal_bridge_width 0.5)
			(island_removal_mode 0)
		)
		(polygon
			(pts
				(arc
					(start 234.7087 -408.059382)
					(mid 232.9307 -408.059382)
					(end 234.7087 -408.059382)
				)
			)
		)
	)
	(zone
		(layers "In3.Cu" "In5.Cu" "In12.Cu" "In14.Cu")
		(hatch none 0.5)
		(connect_pads
			(clearance 0)
		)
		(min_thickness 0.25)
		(keepout
			(tracks not_allowed)
			(vias allowed)
			(pads allowed)
			(copperpour not_allowed)
			(footprints allowed)
		)
		(placement
			(enabled no)
			(sheetname "")
		)
		(fill yes
			(thermal_gap 0.5)
			(thermal_bridge_width 0.5)
			(island_removal_mode 0)
		)
		(polygon
			(pts
				(arc
					(start 199.003158 -401.920202)
					(mid 197.225158 -401.920202)
					(end 199.003158 -401.920202)
				)
			)
		)
	)
	(zone
		(layers "In3.Cu" "In5.Cu" "In12.Cu" "In14.Cu")
		(hatch none 0.5)
		(connect_pads
			(clearance 0)
		)
		(min_thickness 0.25)
		(keepout
			(tracks not_allowed)
			(vias allowed)
			(pads allowed)
			(copperpour not_allowed)
			(footprints allowed)
		)
		(placement
			(enabled no)
			(sheetname "")
		)
		(fill yes
			(thermal_gap 0.5)
			(thermal_bridge_width 0.5)
			(island_removal_mode 0)
		)
		(polygon
			(pts
				(arc
					(start 187.324492 -405.755602)
					(mid 185.546492 -405.755602)
					(end 187.324492 -405.755602)
				)
			)
		)
	)
	(zone
		(layers "In3.Cu" "In5.Cu" "In12.Cu" "In14.Cu")
		(hatch none 0.5)
		(connect_pads
			(clearance 0)
		)
		(min_thickness 0.25)
		(keepout
			(tracks not_allowed)
			(vias allowed)
			(pads allowed)
			(copperpour not_allowed)
			(footprints allowed)
		)
		(placement
			(enabled no)
			(sheetname "")
		)
		(fill yes
			(thermal_gap 0.5)
			(thermal_bridge_width 0.5)
			(island_removal_mode 0)
		)
		(polygon
			(pts
				(arc
					(start 212.6107 -405.773382)
					(mid 210.8327 -405.773382)
					(end 212.6107 -405.773382)
				)
			)
		)
	)
	(zone
		(layers "In3.Cu" "In5.Cu" "In12.Cu" "In14.Cu")
		(hatch none 0.5)
		(connect_pads
			(clearance 0)
		)
		(min_thickness 0.25)
		(keepout
			(tracks not_allowed)
			(vias allowed)
			(pads allowed)
			(copperpour not_allowed)
			(footprints allowed)
		)
		(placement
			(enabled no)
			(sheetname "")
		)
		(fill yes
			(thermal_gap 0.5)
			(thermal_bridge_width 0.5)
			(island_removal_mode 0)
		)
		(polygon
			(pts
				(arc
					(start 199.6567 -407.297382)
					(mid 197.8787 -407.297382)
					(end 199.6567 -407.297382)
				)
			)
		)
	)
	(zone
		(layers "In3.Cu" "In5.Cu" "In12.Cu" "In14.Cu")
		(hatch none 0.5)
		(connect_pads
			(clearance 0)
		)
		(min_thickness 0.25)
		(keepout
			(tracks not_allowed)
			(vias allowed)
			(pads allowed)
			(copperpour not_allowed)
			(footprints allowed)
		)
		(placement
			(enabled no)
			(sheetname "")
		)
		(fill yes
			(thermal_gap 0.5)
			(thermal_bridge_width 0.5)
			(island_removal_mode 0)
		)
		(polygon
			(pts
				(arc
					(start 220.2307 -407.297382)
					(mid 218.4527 -407.297382)
					(end 220.2307 -407.297382)
				)
			)
		)
	)
	(zone
		(layers "In3.Cu" "In5.Cu" "In12.Cu" "In14.Cu")
		(hatch none 0.5)
		(connect_pads
			(clearance 0)
		)
		(min_thickness 0.25)
		(keepout
			(tracks not_allowed)
			(vias allowed)
			(pads allowed)
			(copperpour not_allowed)
			(footprints allowed)
		)
		(placement
			(enabled no)
			(sheetname "")
		)
		(fill yes
			(thermal_gap 0.5)
			(thermal_bridge_width 0.5)
			(island_removal_mode 0)
		)
		(polygon
			(pts
				(arc
					(start 200.4187 -405.011382)
					(mid 198.6407 -405.011382)
					(end 200.4187 -405.011382)
				)
			)
		)
	)
	(zone
		(layers "In3.Cu" "In5.Cu" "In12.Cu" "In14.Cu")
		(hatch none 0.5)
		(connect_pads
			(clearance 0)
		)
		(min_thickness 0.25)
		(keepout
			(tracks not_allowed)
			(vias allowed)
			(pads allowed)
			(copperpour not_allowed)
			(footprints allowed)
		)
		(placement
			(enabled no)
			(sheetname "")
		)
		(fill yes
			(thermal_gap 0.5)
			(thermal_bridge_width 0.5)
			(island_removal_mode 0)
		)
		(polygon
			(pts
				(arc
					(start 220.2307 -405.011382)
					(mid 218.4527 -405.011382)
					(end 220.2307 -405.011382)
				)
			)
		)
	)
	(zone
		(layers "In3.Cu" "In5.Cu" "In12.Cu" "In14.Cu")
		(hatch none 0.5)
		(connect_pads
			(clearance 0)
		)
		(min_thickness 0.25)
		(keepout
			(tracks not_allowed)
			(vias allowed)
			(pads allowed)
			(copperpour not_allowed)
			(footprints allowed)
		)
		(placement
			(enabled no)
			(sheetname "")
		)
		(fill yes
			(thermal_gap 0.5)
			(thermal_bridge_width 0.5)
			(island_removal_mode 0)
		)
		(polygon
			(pts
				(arc
					(start 201.9427 -408.059382)
					(mid 200.1647 -408.059382)
					(end 201.9427 -408.059382)
				)
			)
		)
	)
	(zone
		(layers "In3.Cu" "In5.Cu" "In12.Cu" "In14.Cu")
		(hatch none 0.5)
		(connect_pads
			(clearance 0)
		)
		(min_thickness 0.25)
		(keepout
			(tracks not_allowed)
			(vias allowed)
			(pads allowed)
			(copperpour not_allowed)
			(footprints allowed)
		)
		(placement
			(enabled no)
			(sheetname "")
		)
		(fill yes
			(thermal_gap 0.5)
			(thermal_bridge_width 0.5)
			(island_removal_mode 0)
		)
		(polygon
			(pts
				(arc
					(start 213.3727 -407.297382)
					(mid 211.5947 -407.297382)
					(end 213.3727 -407.297382)
				)
			)
		)
	)
	(zone
		(layers "In3.Cu" "In5.Cu" "In12.Cu" "In14.Cu")
		(hatch none 0.5)
		(connect_pads
			(clearance 0)
		)
		(min_thickness 0.25)
		(keepout
			(tracks not_allowed)
			(vias allowed)
			(pads allowed)
			(copperpour not_allowed)
			(footprints allowed)
		)
		(placement
			(enabled no)
			(sheetname "")
		)
		(fill yes
			(thermal_gap 0.5)
			(thermal_bridge_width 0.5)
			(island_removal_mode 0)
		)
		(polygon
			(pts
				(arc
					(start 200.4187 -406.535382)
					(mid 198.6407 -406.535382)
					(end 200.4187 -406.535382)
				)
			)
		)
	)
	(zone
		(layers "In3.Cu" "In5.Cu" "In12.Cu" "In14.Cu")
		(hatch none 0.5)
		(connect_pads
			(clearance 0)
		)
		(min_thickness 0.25)
		(keepout
			(tracks not_allowed)
			(vias allowed)
			(pads allowed)
			(copperpour not_allowed)
			(footprints allowed)
		)
		(placement
			(enabled no)
			(sheetname "")
		)
		(fill yes
			(thermal_gap 0.5)
			(thermal_bridge_width 0.5)
			(island_removal_mode 0)
		)
		(polygon
			(pts
				(arc
					(start 189.610492 -406.517602)
					(mid 187.832492 -406.517602)
					(end 189.610492 -406.517602)
				)
			)
		)
	)
	(zone
		(layers "In3.Cu" "In5.Cu" "In12.Cu" "In14.Cu")
		(hatch none 0.5)
		(connect_pads
			(clearance 0)
		)
		(min_thickness 0.25)
		(keepout
			(tracks not_allowed)
			(vias allowed)
			(pads allowed)
			(copperpour not_allowed)
			(footprints allowed)
		)
		(placement
			(enabled no)
			(sheetname "")
		)
		(fill yes
			(thermal_gap 0.5)
			(thermal_bridge_width 0.5)
			(island_removal_mode 0)
		)
		(polygon
			(pts
				(arc
					(start 223.158558 -403.223222)
					(mid 221.380558 -403.223222)
					(end 223.158558 -403.223222)
				)
			)
		)
	)
	(zone
		(layers "In3.Cu" "In5.Cu" "In12.Cu" "In14.Cu")
		(hatch none 0.5)
		(connect_pads
			(clearance 0)
		)
		(min_thickness 0.25)
		(keepout
			(tracks not_allowed)
			(vias allowed)
			(pads allowed)
			(copperpour not_allowed)
			(footprints allowed)
		)
		(placement
			(enabled no)
			(sheetname "")
		)
		(fill yes
			(thermal_gap 0.5)
			(thermal_bridge_width 0.5)
			(island_removal_mode 0)
		)
		(polygon
			(pts
				(arc
					(start 210.3247 -407.297382)
					(mid 208.5467 -407.297382)
					(end 210.3247 -407.297382)
				)
			)
		)
	)
	(zone
		(layers "In3.Cu" "In5.Cu" "In12.Cu" "In14.Cu")
		(hatch none 0.5)
		(connect_pads
			(clearance 0)
		)
		(min_thickness 0.25)
		(keepout
			(tracks not_allowed)
			(vias allowed)
			(pads allowed)
			(copperpour not_allowed)
			(footprints allowed)
		)
		(placement
			(enabled no)
			(sheetname "")
		)
		(fill yes
			(thermal_gap 0.5)
			(thermal_bridge_width 0.5)
			(island_removal_mode 0)
		)
		(polygon
			(pts
				(arc
					(start 201.822558 -400.617182)
					(mid 200.044558 -400.617182)
					(end 201.822558 -400.617182)
				)
			)
		)
	)
	(zone
		(layers "In3.Cu" "In5.Cu" "In12.Cu" "In14.Cu")
		(hatch none 0.5)
		(connect_pads
			(clearance 0)
		)
		(min_thickness 0.25)
		(keepout
			(tracks not_allowed)
			(vias allowed)
			(pads allowed)
			(copperpour not_allowed)
			(footprints allowed)
		)
		(placement
			(enabled no)
			(sheetname "")
		)
		(fill yes
			(thermal_gap 0.5)
			(thermal_bridge_width 0.5)
			(island_removal_mode 0)
		)
		(polygon
			(pts
				(arc
					(start 230.1367 -408.059382)
					(mid 228.3587 -408.059382)
					(end 230.1367 -408.059382)
				)
			)
		)
	)
	(zone
		(layers "In3.Cu" "In5.Cu" "In12.Cu" "In14.Cu")
		(hatch none 0.5)
		(connect_pads
			(clearance 0)
		)
		(min_thickness 0.25)
		(keepout
			(tracks not_allowed)
			(vias allowed)
			(pads allowed)
			(copperpour not_allowed)
			(footprints allowed)
		)
		(placement
			(enabled no)
			(sheetname "")
		)
		(fill yes
			(thermal_gap 0.5)
			(thermal_bridge_width 0.5)
			(island_removal_mode 0)
		)
		(polygon
			(pts
				(arc
					(start 188.086492 -404.993602)
					(mid 186.308492 -404.993602)
					(end 188.086492 -404.993602)
				)
			)
		)
	)
	(zone
		(layers "In3.Cu" "In5.Cu" "In12.Cu" "In14.Cu")
		(hatch none 0.5)
		(connect_pads
			(clearance 0)
		)
		(min_thickness 0.25)
		(keepout
			(tracks not_allowed)
			(vias allowed)
			(pads allowed)
			(copperpour not_allowed)
			(footprints allowed)
		)
		(placement
			(enabled no)
			(sheetname "")
		)
		(fill yes
			(thermal_gap 0.5)
			(thermal_bridge_width 0.5)
			(island_removal_mode 0)
		)
		(polygon
			(pts
				(arc
					(start 201.1807 -406.535382)
					(mid 199.4027 -406.535382)
					(end 201.1807 -406.535382)
				)
			)
		)
	)
	(zone
		(layers "In3.Cu" "In5.Cu" "In12.Cu" "In14.Cu")
		(hatch none 0.5)
		(connect_pads
			(clearance 0)
		)
		(min_thickness 0.25)
		(keepout
			(tracks not_allowed)
			(vias allowed)
			(pads allowed)
			(copperpour not_allowed)
			(footprints allowed)
		)
		(placement
			(enabled no)
			(sheetname "")
		)
		(fill yes
			(thermal_gap 0.5)
			(thermal_bridge_width 0.5)
			(island_removal_mode 0)
		)
		(polygon
			(pts
				(arc
					(start 199.6567 -406.535382)
					(mid 197.8787 -406.535382)
					(end 199.6567 -406.535382)
				)
			)
		)
	)
	(zone
		(layers "In3.Cu" "In5.Cu" "In12.Cu" "In14.Cu")
		(hatch none 0.5)
		(connect_pads
			(clearance 0)
		)
		(min_thickness 0.25)
		(keepout
			(tracks not_allowed)
			(vias allowed)
			(pads allowed)
			(copperpour not_allowed)
			(footprints allowed)
		)
		(placement
			(enabled no)
			(sheetname "")
		)
		(fill yes
			(thermal_gap 0.5)
			(thermal_bridge_width 0.5)
			(island_removal_mode 0)
		)
		(polygon
			(pts
				(arc
					(start 219.4687 -408.059382)
					(mid 217.6907 -408.059382)
					(end 219.4687 -408.059382)
				)
			)
		)
	)
	(zone
		(layers "In3.Cu" "In5.Cu" "In12.Cu" "In14.Cu")
		(hatch none 0.5)
		(connect_pads
			(clearance 0)
		)
		(min_thickness 0.25)
		(keepout
			(tracks not_allowed)
			(vias allowed)
			(pads allowed)
			(copperpour not_allowed)
			(footprints allowed)
		)
		(placement
			(enabled no)
			(sheetname "")
		)
		(fill yes
			(thermal_gap 0.5)
			(thermal_bridge_width 0.5)
			(island_removal_mode 0)
		)
		(polygon
			(pts
				(arc
					(start 212.6107 -408.059382)
					(mid 210.8327 -408.059382)
					(end 212.6107 -408.059382)
				)
			)
		)
	)
	(zone
		(layers "In3.Cu" "In5.Cu" "In12.Cu" "In14.Cu")
		(hatch none 0.5)
		(connect_pads
			(clearance 0)
		)
		(min_thickness 0.25)
		(keepout
			(tracks not_allowed)
			(vias allowed)
			(pads allowed)
			(copperpour not_allowed)
			(footprints allowed)
		)
		(placement
			(enabled no)
			(sheetname "")
		)
		(fill yes
			(thermal_gap 0.5)
			(thermal_bridge_width 0.5)
			(island_removal_mode 0)
		)
		(polygon
			(pts
				(arc
					(start 200.425558 -403.223222)
					(mid 198.647558 -403.223222)
					(end 200.425558 -403.223222)
				)
			)
		)
	)
	(zone
		(layers "In3.Cu" "In5.Cu" "In12.Cu" "In14.Cu")
		(hatch none 0.5)
		(connect_pads
			(clearance 0)
		)
		(min_thickness 0.25)
		(keepout
			(tracks not_allowed)
			(vias allowed)
			(pads allowed)
			(copperpour not_allowed)
			(footprints allowed)
		)
		(placement
			(enabled no)
			(sheetname "")
		)
		(fill yes
			(thermal_gap 0.5)
			(thermal_bridge_width 0.5)
			(island_removal_mode 0)
		)
		(polygon
			(pts
				(arc
					(start 189.610492 -407.330402)
					(mid 187.832492 -407.330402)
					(end 189.610492 -407.330402)
				)
			)
		)
	)
	(zone
		(layers "In3.Cu" "In5.Cu" "In12.Cu" "In14.Cu")
		(hatch none 0.5)
		(connect_pads
			(clearance 0)
		)
		(min_thickness 0.25)
		(keepout
			(tracks not_allowed)
			(vias allowed)
			(pads allowed)
			(copperpour not_allowed)
			(footprints allowed)
		)
		(placement
			(enabled no)
			(sheetname "")
		)
		(fill yes
			(thermal_gap 0.5)
			(thermal_bridge_width 0.5)
			(island_removal_mode 0)
		)
		(polygon
			(pts
				(arc
					(start 232.429558 -403.223222)
					(mid 230.651558 -403.223222)
					(end 232.429558 -403.223222)
				)
			)
		)
	)
	(zone
		(layers "In3.Cu" "In5.Cu" "In12.Cu" "In14.Cu")
		(hatch none 0.5)
		(connect_pads
			(clearance 0)
		)
		(min_thickness 0.25)
		(keepout
			(tracks not_allowed)
			(vias allowed)
			(pads allowed)
			(copperpour not_allowed)
			(footprints allowed)
		)
		(placement
			(enabled no)
			(sheetname "")
		)
		(fill yes
			(thermal_gap 0.5)
			(thermal_bridge_width 0.5)
			(island_removal_mode 0)
		)
		(polygon
			(pts
				(arc
					(start 211.8487 -405.773382)
					(mid 210.0707 -405.773382)
					(end 211.8487 -405.773382)
				)
			)
		)
	)
	(zone
		(layers "In3.Cu" "In5.Cu" "In12.Cu" "In14.Cu")
		(hatch none 0.5)
		(connect_pads
			(clearance 0)
		)
		(min_thickness 0.25)
		(keepout
			(tracks not_allowed)
			(vias allowed)
			(pads allowed)
			(copperpour not_allowed)
			(footprints allowed)
		)
		(placement
			(enabled no)
			(sheetname "")
		)
		(fill yes
			(thermal_gap 0.5)
			(thermal_bridge_width 0.5)
			(island_removal_mode 0)
		)
		(polygon
			(pts
				(arc
					(start 209.5627 -405.011382)
					(mid 207.7847 -405.011382)
					(end 209.5627 -405.011382)
				)
			)
		)
	)
	(zone
		(layers "In3.Cu" "In5.Cu" "In12.Cu" "In14.Cu")
		(hatch none 0.5)
		(connect_pads
			(clearance 0)
		)
		(min_thickness 0.25)
		(keepout
			(tracks not_allowed)
			(vias allowed)
			(pads allowed)
			(copperpour not_allowed)
			(footprints allowed)
		)
		(placement
			(enabled no)
			(sheetname "")
		)
		(fill yes
			(thermal_gap 0.5)
			(thermal_bridge_width 0.5)
			(island_removal_mode 0)
		)
		(polygon
			(pts
				(arc
					(start 210.3247 -408.059382)
					(mid 208.5467 -408.059382)
					(end 210.3247 -408.059382)
				)
			)
		)
	)
	(zone
		(layers "In3.Cu" "In5.Cu" "In12.Cu" "In14.Cu")
		(hatch none 0.5)
		(connect_pads
			(clearance 0)
		)
		(min_thickness 0.25)
		(keepout
			(tracks not_allowed)
			(vias allowed)
			(pads allowed)
			(copperpour not_allowed)
			(footprints allowed)
		)
		(placement
			(enabled no)
			(sheetname "")
		)
		(fill yes
			(thermal_gap 0.5)
			(thermal_bridge_width 0.5)
			(island_removal_mode 0)
		)
		(polygon
			(pts
				(arc
					(start 198.8947 -406.535382)
					(mid 197.1167 -406.535382)
					(end 198.8947 -406.535382)
				)
			)
		)
	)
	(zone
		(layers "In3.Cu" "In5.Cu" "In12.Cu" "In14.Cu")
		(hatch none 0.5)
		(connect_pads
			(clearance 0)
		)
		(min_thickness 0.25)
		(keepout
			(tracks not_allowed)
			(vias allowed)
			(pads allowed)
			(copperpour not_allowed)
			(footprints allowed)
		)
		(placement
			(enabled no)
			(sheetname "")
		)
		(fill yes
			(thermal_gap 0.5)
			(thermal_bridge_width 0.5)
			(island_removal_mode 0)
		)
		(polygon
			(pts
				(arc
					(start 220.2307 -408.059382)
					(mid 218.4527 -408.059382)
					(end 220.2307 -408.059382)
				)
			)
		)
	)
	(zone
		(layers "In3.Cu" "In5.Cu" "In12.Cu" "In14.Cu")
		(hatch none 0.5)
		(connect_pads
			(clearance 0)
		)
		(min_thickness 0.25)
		(keepout
			(tracks not_allowed)
			(vias allowed)
			(pads allowed)
			(copperpour not_allowed)
			(footprints allowed)
		)
		(placement
			(enabled no)
			(sheetname "")
		)
		(fill yes
			(thermal_gap 0.5)
			(thermal_bridge_width 0.5)
			(island_removal_mode 0)
		)
		(polygon
			(pts
				(arc
					(start 232.429558 -400.617182)
					(mid 230.651558 -400.617182)
					(end 232.429558 -400.617182)
				)
			)
		)
	)
	(zone
		(layers "In3.Cu" "In5.Cu" "In12.Cu" "In14.Cu")
		(hatch none 0.5)
		(connect_pads
			(clearance 0)
		)
		(min_thickness 0.25)
		(keepout
			(tracks not_allowed)
			(vias allowed)
			(pads allowed)
			(copperpour not_allowed)
			(footprints allowed)
		)
		(placement
			(enabled no)
			(sheetname "")
		)
		(fill yes
			(thermal_gap 0.5)
			(thermal_bridge_width 0.5)
			(island_removal_mode 0)
		)
		(polygon
			(pts
				(arc
					(start 209.5627 -408.059382)
					(mid 207.7847 -408.059382)
					(end 209.5627 -408.059382)
				)
			)
		)
	)
	(zone
		(layers "In3.Cu" "In5.Cu" "In12.Cu" "In14.Cu")
		(hatch none 0.5)
		(connect_pads
			(clearance 0)
		)
		(min_thickness 0.25)
		(keepout
			(tracks not_allowed)
			(vias allowed)
			(pads allowed)
			(copperpour not_allowed)
			(footprints allowed)
		)
		(placement
			(enabled no)
			(sheetname "")
		)
		(fill yes
			(thermal_gap 0.5)
			(thermal_bridge_width 0.5)
			(island_removal_mode 0)
		)
		(polygon
			(pts
				(arc
					(start 185.74512 -403.222714)
					(mid 183.96712 -403.222714)
					(end 185.74512 -403.222714)
				)
			)
		)
	)
	(zone
		(layers "In3.Cu" "In5.Cu" "In12.Cu" "In14.Cu")
		(hatch none 0.5)
		(connect_pads
			(clearance 0)
		)
		(min_thickness 0.25)
		(keepout
			(tracks not_allowed)
			(vias allowed)
			(pads allowed)
			(copperpour not_allowed)
			(footprints allowed)
		)
		(placement
			(enabled no)
			(sheetname "")
		)
		(fill yes
			(thermal_gap 0.5)
			(thermal_bridge_width 0.5)
			(island_removal_mode 0)
		)
		(polygon
			(pts
				(arc
					(start 186.562492 -404.993602)
					(mid 184.784492 -404.993602)
					(end 186.562492 -404.993602)
				)
			)
		)
	)
	(zone
		(layers "In3.Cu" "In5.Cu" "In12.Cu" "In14.Cu")
		(hatch none 0.5)
		(connect_pads
			(clearance 0)
		)
		(min_thickness 0.25)
		(keepout
			(tracks not_allowed)
			(vias allowed)
			(pads allowed)
			(copperpour not_allowed)
			(footprints allowed)
		)
		(placement
			(enabled no)
			(sheetname "")
		)
		(fill yes
			(thermal_gap 0.5)
			(thermal_bridge_width 0.5)
			(island_removal_mode 0)
		)
		(polygon
			(pts
				(arc
					(start 222.5167 -406.535382)
					(mid 220.7387 -406.535382)
					(end 222.5167 -406.535382)
				)
			)
		)
	)
	(zone
		(layers "In3.Cu" "In5.Cu" "In12.Cu" "In14.Cu")
		(hatch none 0.5)
		(connect_pads
			(clearance 0)
		)
		(min_thickness 0.25)
		(keepout
			(tracks not_allowed)
			(vias allowed)
			(pads allowed)
			(copperpour not_allowed)
			(footprints allowed)
		)
		(placement
			(enabled no)
			(sheetname "")
		)
		(fill yes
			(thermal_gap 0.5)
			(thermal_bridge_width 0.5)
			(island_removal_mode 0)
		)
		(polygon
			(pts
				(arc
					(start 188.848492 -407.330402)
					(mid 187.070492 -407.330402)
					(end 188.848492 -407.330402)
				)
			)
		)
	)
	(zone
		(layers "In3.Cu" "In5.Cu" "In12.Cu" "In14.Cu")
		(hatch none 0.5)
		(connect_pads
			(clearance 0)
		)
		(min_thickness 0.25)
		(keepout
			(tracks not_allowed)
			(vias allowed)
			(pads allowed)
			(copperpour not_allowed)
			(footprints allowed)
		)
		(placement
			(enabled no)
			(sheetname "")
		)
		(fill yes
			(thermal_gap 0.5)
			(thermal_bridge_width 0.5)
			(island_removal_mode 0)
		)
		(polygon
			(pts
				(arc
					(start 211.0867 -408.059382)
					(mid 209.3087 -408.059382)
					(end 211.0867 -408.059382)
				)
			)
		)
	)
	(zone
		(layers "In3.Cu" "In5.Cu" "In12.Cu" "In14.Cu")
		(hatch none 0.5)
		(connect_pads
			(clearance 0)
		)
		(min_thickness 0.25)
		(keepout
			(tracks not_allowed)
			(vias allowed)
			(pads allowed)
			(copperpour not_allowed)
			(footprints allowed)
		)
		(placement
			(enabled no)
			(sheetname "")
		)
		(fill yes
			(thermal_gap 0.5)
			(thermal_bridge_width 0.5)
			(island_removal_mode 0)
		)
		(polygon
			(pts
				(arc
					(start 222.5167 -405.011382)
					(mid 220.7387 -405.011382)
					(end 222.5167 -405.011382)
				)
			)
		)
	)
	(zone
		(layers "In3.Cu" "In5.Cu" "In12.Cu" "In14.Cu")
		(hatch none 0.5)
		(connect_pads
			(clearance 0)
		)
		(min_thickness 0.25)
		(keepout
			(tracks not_allowed)
			(vias allowed)
			(pads allowed)
			(copperpour not_allowed)
			(footprints allowed)
		)
		(placement
			(enabled no)
			(sheetname "")
		)
		(fill yes
			(thermal_gap 0.5)
			(thermal_bridge_width 0.5)
			(island_removal_mode 0)
		)
		(polygon
			(pts
				(arc
					(start 188.56452 -400.616674)
					(mid 186.78652 -400.616674)
					(end 188.56452 -400.616674)
				)
			)
		)
	)
	(zone
		(layers "In3.Cu" "In5.Cu" "In12.Cu" "In14.Cu")
		(hatch none 0.5)
		(connect_pads
			(clearance 0)
		)
		(min_thickness 0.25)
		(keepout
			(tracks not_allowed)
			(vias allowed)
			(pads allowed)
			(copperpour not_allowed)
			(footprints allowed)
		)
		(placement
			(enabled no)
			(sheetname "")
		)
		(fill yes
			(thermal_gap 0.5)
			(thermal_bridge_width 0.5)
			(island_removal_mode 0)
		)
		(polygon
			(pts
				(arc
					(start 224.0407 -407.297382)
					(mid 222.2627 -407.297382)
					(end 224.0407 -407.297382)
				)
			)
		)
	)
	(zone
		(layers "In3.Cu" "In5.Cu" "In12.Cu" "In14.Cu")
		(hatch none 0.5)
		(connect_pads
			(clearance 0)
		)
		(min_thickness 0.25)
		(keepout
			(tracks not_allowed)
			(vias allowed)
			(pads allowed)
			(copperpour not_allowed)
			(footprints allowed)
		)
		(placement
			(enabled no)
			(sheetname "")
		)
		(fill yes
			(thermal_gap 0.5)
			(thermal_bridge_width 0.5)
			(island_removal_mode 0)
		)
		(polygon
			(pts
				(arc
					(start 188.56452 -401.919694)
					(mid 186.78652 -401.919694)
					(end 188.56452 -401.919694)
				)
			)
		)
	)
	(zone
		(layers "In3.Cu" "In5.Cu" "In12.Cu" "In14.Cu")
		(hatch none 0.5)
		(connect_pads
			(clearance 0)
		)
		(min_thickness 0.25)
		(keepout
			(tracks not_allowed)
			(vias allowed)
			(pads allowed)
			(copperpour not_allowed)
			(footprints allowed)
		)
		(placement
			(enabled no)
			(sheetname "")
		)
		(fill yes
			(thermal_gap 0.5)
			(thermal_bridge_width 0.5)
			(island_removal_mode 0)
		)
		(polygon
			(pts
				(arc
					(start 209.5627 -406.535382)
					(mid 207.7847 -406.535382)
					(end 209.5627 -406.535382)
				)
			)
		)
	)
	(zone
		(layers "In3.Cu" "In5.Cu" "In12.Cu" "In14.Cu")
		(hatch none 0.5)
		(connect_pads
			(clearance 0)
		)
		(min_thickness 0.25)
		(keepout
			(tracks not_allowed)
			(vias allowed)
			(pads allowed)
			(copperpour not_allowed)
			(footprints allowed)
		)
		(placement
			(enabled no)
			(sheetname "")
		)
		(fill yes
			(thermal_gap 0.5)
			(thermal_bridge_width 0.5)
			(island_removal_mode 0)
		)
		(polygon
			(pts
				(arc
					(start 187.16752 -403.222714)
					(mid 185.38952 -403.222714)
					(end 187.16752 -403.222714)
				)
			)
		)
	)
	(zone
		(layers "In3.Cu" "In5.Cu" "In12.Cu" "In14.Cu")
		(hatch none 0.5)
		(connect_pads
			(clearance 0)
		)
		(min_thickness 0.25)
		(keepout
			(tracks not_allowed)
			(vias allowed)
			(pads allowed)
			(copperpour not_allowed)
			(footprints allowed)
		)
		(placement
			(enabled no)
			(sheetname "")
		)
		(fill yes
			(thermal_gap 0.5)
			(thermal_bridge_width 0.5)
			(island_removal_mode 0)
		)
		(polygon
			(pts
				(arc
					(start 230.8987 -405.011382)
					(mid 229.1207 -405.011382)
					(end 230.8987 -405.011382)
				)
			)
		)
	)
	(zone
		(layers "In3.Cu" "In5.Cu" "In12.Cu" "In14.Cu")
		(hatch none 0.5)
		(connect_pads
			(clearance 0)
		)
		(min_thickness 0.25)
		(keepout
			(tracks not_allowed)
			(vias allowed)
			(pads allowed)
			(copperpour not_allowed)
			(footprints allowed)
		)
		(placement
			(enabled no)
			(sheetname "")
		)
		(fill yes
			(thermal_gap 0.5)
			(thermal_bridge_width 0.5)
			(island_removal_mode 0)
		)
		(polygon
			(pts
				(arc
					(start 190.372492 -404.993602)
					(mid 188.594492 -404.993602)
					(end 190.372492 -404.993602)
				)
			)
		)
	)
	(zone
		(layers "In3.Cu" "In5.Cu" "In12.Cu" "In14.Cu")
		(hatch none 0.5)
		(connect_pads
			(clearance 0)
		)
		(min_thickness 0.25)
		(keepout
			(tracks not_allowed)
			(vias allowed)
			(pads allowed)
			(copperpour not_allowed)
			(footprints allowed)
		)
		(placement
			(enabled no)
			(sheetname "")
		)
		(fill yes
			(thermal_gap 0.5)
			(thermal_bridge_width 0.5)
			(island_removal_mode 0)
		)
		(polygon
			(pts
				(arc
					(start 221.7547 -408.059382)
					(mid 219.9767 -408.059382)
					(end 221.7547 -408.059382)
				)
			)
		)
	)
	(zone
		(layers "In3.Cu" "In5.Cu" "In12.Cu" "In14.Cu")
		(hatch none 0.5)
		(connect_pads
			(clearance 0)
		)
		(min_thickness 0.25)
		(keepout
			(tracks not_allowed)
			(vias allowed)
			(pads allowed)
			(copperpour not_allowed)
			(footprints allowed)
		)
		(placement
			(enabled no)
			(sheetname "")
		)
		(fill yes
			(thermal_gap 0.5)
			(thermal_bridge_width 0.5)
			(island_removal_mode 0)
		)
		(polygon
			(pts
				(arc
					(start 233.826558 -403.223222)
					(mid 232.048558 -403.223222)
					(end 233.826558 -403.223222)
				)
			)
		)
	)
	(zone
		(layers "In3.Cu" "In5.Cu" "In12.Cu" "In14.Cu")
		(hatch none 0.5)
		(connect_pads
			(clearance 0)
		)
		(min_thickness 0.25)
		(keepout
			(tracks not_allowed)
			(vias allowed)
			(pads allowed)
			(copperpour not_allowed)
			(footprints allowed)
		)
		(placement
			(enabled no)
			(sheetname "")
		)
		(fill yes
			(thermal_gap 0.5)
			(thermal_bridge_width 0.5)
			(island_removal_mode 0)
		)
		(polygon
			(pts
				(arc
					(start 200.4187 -407.297382)
					(mid 198.6407 -407.297382)
					(end 200.4187 -407.297382)
				)
			)
		)
	)
	(zone
		(layers "In3.Cu" "In5.Cu" "In12.Cu" "In14.Cu")
		(hatch none 0.5)
		(connect_pads
			(clearance 0)
		)
		(min_thickness 0.25)
		(keepout
			(tracks not_allowed)
			(vias allowed)
			(pads allowed)
			(copperpour not_allowed)
			(footprints allowed)
		)
		(placement
			(enabled no)
			(sheetname "")
		)
		(fill yes
			(thermal_gap 0.5)
			(thermal_bridge_width 0.5)
			(island_removal_mode 0)
		)
		(polygon
			(pts
				(arc
					(start 199.6567 -408.059382)
					(mid 197.8787 -408.059382)
					(end 199.6567 -408.059382)
				)
			)
		)
	)
	(zone
		(layers "In3.Cu" "In5.Cu" "In12.Cu" "In14.Cu")
		(hatch none 0.5)
		(connect_pads
			(clearance 0)
		)
		(min_thickness 0.25)
		(keepout
			(tracks not_allowed)
			(vias allowed)
			(pads allowed)
			(copperpour not_allowed)
			(footprints allowed)
		)
		(placement
			(enabled no)
			(sheetname "")
		)
		(fill yes
			(thermal_gap 0.5)
			(thermal_bridge_width 0.5)
			(island_removal_mode 0)
		)
		(polygon
			(pts
				(arc
					(start 189.610492 -405.755602)
					(mid 187.832492 -405.755602)
					(end 189.610492 -405.755602)
				)
			)
		)
	)
	(zone
		(layers "In3.Cu" "In5.Cu" "In12.Cu" "In14.Cu")
		(hatch none 0.5)
		(connect_pads
			(clearance 0)
		)
		(min_thickness 0.25)
		(keepout
			(tracks not_allowed)
			(vias allowed)
			(pads allowed)
			(copperpour not_allowed)
			(footprints allowed)
		)
		(placement
			(enabled no)
			(sheetname "")
		)
		(fill yes
			(thermal_gap 0.5)
			(thermal_bridge_width 0.5)
			(island_removal_mode 0)
		)
		(polygon
			(pts
				(arc
					(start 198.1327 -408.059382)
					(mid 196.3547 -408.059382)
					(end 198.1327 -408.059382)
				)
			)
		)
	)
	(zone
		(layers "In3.Cu" "In5.Cu" "In12.Cu" "In14.Cu")
		(hatch none 0.5)
		(connect_pads
			(clearance 0)
		)
		(min_thickness 0.25)
		(keepout
			(tracks not_allowed)
			(vias allowed)
			(pads allowed)
			(copperpour not_allowed)
			(footprints allowed)
		)
		(placement
			(enabled no)
			(sheetname "")
		)
		(fill yes
			(thermal_gap 0.5)
			(thermal_bridge_width 0.5)
			(island_removal_mode 0)
		)
		(polygon
			(pts
				(arc
					(start 201.822558 -401.920202)
					(mid 200.044558 -401.920202)
					(end 201.822558 -401.920202)
				)
			)
		)
	)
	(zone
		(layers "In3.Cu" "In5.Cu" "In12.Cu" "In14.Cu")
		(hatch none 0.5)
		(connect_pads
			(clearance 0)
		)
		(min_thickness 0.25)
		(keepout
			(tracks not_allowed)
			(vias allowed)
			(pads allowed)
			(copperpour not_allowed)
			(footprints allowed)
		)
		(placement
			(enabled no)
			(sheetname "")
		)
		(fill yes
			(thermal_gap 0.5)
			(thermal_bridge_width 0.5)
			(island_removal_mode 0)
		)
		(polygon
			(pts
				(arc
					(start 211.0867 -405.773382)
					(mid 209.3087 -405.773382)
					(end 211.0867 -405.773382)
				)
			)
		)
	)
	(zone
		(layers "In3.Cu" "In5.Cu" "In12.Cu" "In14.Cu")
		(hatch none 0.5)
		(connect_pads
			(clearance 0)
		)
		(min_thickness 0.25)
		(keepout
			(tracks not_allowed)
			(vias allowed)
			(pads allowed)
			(copperpour not_allowed)
			(footprints allowed)
		)
		(placement
			(enabled no)
			(sheetname "")
		)
		(fill yes
			(thermal_gap 0.5)
			(thermal_bridge_width 0.5)
			(island_removal_mode 0)
		)
		(polygon
			(pts
				(arc
					(start 208.8007 -407.297382)
					(mid 207.0227 -407.297382)
					(end 208.8007 -407.297382)
				)
			)
		)
	)
	(zone
		(layers "In3.Cu" "In5.Cu" "In12.Cu" "In14.Cu")
		(hatch none 0.5)
		(connect_pads
			(clearance 0)
		)
		(min_thickness 0.25)
		(keepout
			(tracks not_allowed)
			(vias allowed)
			(pads allowed)
			(copperpour not_allowed)
			(footprints allowed)
		)
		(placement
			(enabled no)
			(sheetname "")
		)
		(fill yes
			(thermal_gap 0.5)
			(thermal_bridge_width 0.5)
			(island_removal_mode 0)
		)
		(polygon
			(pts
				(arc
					(start 211.0867 -405.011382)
					(mid 209.3087 -405.011382)
					(end 211.0867 -405.011382)
				)
			)
		)
	)
	(zone
		(layers "In3.Cu" "In5.Cu" "In12.Cu" "In14.Cu")
		(hatch none 0.5)
		(connect_pads
			(clearance 0)
		)
		(min_thickness 0.25)
		(keepout
			(tracks not_allowed)
			(vias allowed)
			(pads allowed)
			(copperpour not_allowed)
			(footprints allowed)
		)
		(placement
			(enabled no)
			(sheetname "")
		)
		(fill yes
			(thermal_gap 0.5)
			(thermal_bridge_width 0.5)
			(island_removal_mode 0)
		)
		(polygon
			(pts
				(arc
					(start 220.339158 -403.223222)
					(mid 218.561158 -403.223222)
					(end 220.339158 -403.223222)
				)
			)
		)
	)
	(zone
		(layers "In3.Cu" "In5.Cu" "In12.Cu" "In14.Cu")
		(hatch none 0.5)
		(connect_pads
			(clearance 0)
		)
		(min_thickness 0.25)
		(keepout
			(tracks not_allowed)
			(vias allowed)
			(pads allowed)
			(copperpour not_allowed)
			(footprints allowed)
		)
		(placement
			(enabled no)
			(sheetname "")
		)
		(fill yes
			(thermal_gap 0.5)
			(thermal_bridge_width 0.5)
			(island_removal_mode 0)
		)
		(polygon
			(pts
				(arc
					(start 211.0867 -407.297382)
					(mid 209.3087 -407.297382)
					(end 211.0867 -407.297382)
				)
			)
		)
	)
	(zone
		(layers "In3.Cu" "In5.Cu" "In12.Cu" "In14.Cu")
		(hatch none 0.5)
		(connect_pads
			(clearance 0)
		)
		(min_thickness 0.25)
		(keepout
			(tracks not_allowed)
			(vias allowed)
			(pads allowed)
			(copperpour not_allowed)
			(footprints allowed)
		)
		(placement
			(enabled no)
			(sheetname "")
		)
		(fill yes
			(thermal_gap 0.5)
			(thermal_bridge_width 0.5)
			(island_removal_mode 0)
		)
		(polygon
			(pts
				(arc
					(start 220.9927 -407.297382)
					(mid 219.2147 -407.297382)
					(end 220.9927 -407.297382)
				)
			)
		)
	)
	(zone
		(layers "In3.Cu" "In5.Cu" "In12.Cu" "In14.Cu")
		(hatch none 0.5)
		(connect_pads
			(clearance 0)
		)
		(min_thickness 0.25)
		(keepout
			(tracks not_allowed)
			(vias allowed)
			(pads allowed)
			(copperpour not_allowed)
			(footprints allowed)
		)
		(placement
			(enabled no)
			(sheetname "")
		)
		(fill yes
			(thermal_gap 0.5)
			(thermal_bridge_width 0.5)
			(island_removal_mode 0)
		)
		(polygon
			(pts
				(arc
					(start 231.007158 -401.920202)
					(mid 229.229158 -401.920202)
					(end 231.007158 -401.920202)
				)
			)
		)
	)
	(zone
		(layers "In3.Cu" "In5.Cu" "In12.Cu" "In14.Cu")
		(hatch none 0.5)
		(connect_pads
			(clearance 0)
		)
		(min_thickness 0.25)
		(keepout
			(tracks not_allowed)
			(vias allowed)
			(pads allowed)
			(copperpour not_allowed)
			(footprints allowed)
		)
		(placement
			(enabled no)
			(sheetname "")
		)
		(fill yes
			(thermal_gap 0.5)
			(thermal_bridge_width 0.5)
			(island_removal_mode 0)
		)
		(polygon
			(pts
				(arc
					(start 210.3247 -405.011382)
					(mid 208.5467 -405.011382)
					(end 210.3247 -405.011382)
				)
			)
		)
	)
	(zone
		(layers "In3.Cu" "In5.Cu" "In12.Cu" "In14.Cu")
		(hatch none 0.5)
		(connect_pads
			(clearance 0)
		)
		(min_thickness 0.25)
		(keepout
			(tracks not_allowed)
			(vias allowed)
			(pads allowed)
			(copperpour not_allowed)
			(footprints allowed)
		)
		(placement
			(enabled no)
			(sheetname "")
		)
		(fill yes
			(thermal_gap 0.5)
			(thermal_bridge_width 0.5)
			(island_removal_mode 0)
		)
		(polygon
			(pts
				(arc
					(start 211.093558 -400.617182)
					(mid 209.315558 -400.617182)
					(end 211.093558 -400.617182)
				)
			)
		)
	)
	(zone
		(layers "In3.Cu" "In5.Cu" "In12.Cu" "In14.Cu")
		(hatch none 0.5)
		(connect_pads
			(clearance 0)
		)
		(min_thickness 0.25)
		(keepout
			(tracks not_allowed)
			(vias allowed)
			(pads allowed)
			(copperpour not_allowed)
			(footprints allowed)
		)
		(placement
			(enabled no)
			(sheetname "")
		)
		(fill yes
			(thermal_gap 0.5)
			(thermal_bridge_width 0.5)
			(island_removal_mode 0)
		)
		(polygon
			(pts
				(arc
					(start 199.6567 -405.011382)
					(mid 197.8787 -405.011382)
					(end 199.6567 -405.011382)
				)
			)
		)
	)
	(zone
		(layers "In3.Cu" "In5.Cu" "In12.Cu" "In14.Cu")
		(hatch none 0.5)
		(connect_pads
			(clearance 0)
		)
		(min_thickness 0.25)
		(keepout
			(tracks not_allowed)
			(vias allowed)
			(pads allowed)
			(copperpour not_allowed)
			(footprints allowed)
		)
		(placement
			(enabled no)
			(sheetname "")
		)
		(fill yes
			(thermal_gap 0.5)
			(thermal_bridge_width 0.5)
			(island_removal_mode 0)
		)
		(polygon
			(pts
				(arc
					(start 199.003158 -403.223222)
					(mid 197.225158 -403.223222)
					(end 199.003158 -403.223222)
				)
			)
		)
	)
	(zone
		(layers "In3.Cu" "In5.Cu" "In12.Cu" "In14.Cu")
		(hatch none 0.5)
		(connect_pads
			(clearance 0)
		)
		(min_thickness 0.25)
		(keepout
			(tracks not_allowed)
			(vias allowed)
			(pads allowed)
			(copperpour not_allowed)
			(footprints allowed)
		)
		(placement
			(enabled no)
			(sheetname "")
		)
		(fill yes
			(thermal_gap 0.5)
			(thermal_bridge_width 0.5)
			(island_removal_mode 0)
		)
		(polygon
			(pts
				(arc
					(start 188.086492 -407.330402)
					(mid 186.308492 -407.330402)
					(end 188.086492 -407.330402)
				)
			)
		)
	)
	(zone
		(layers "In3.Cu" "In5.Cu" "In12.Cu" "In14.Cu")
		(hatch none 0.5)
		(connect_pads
			(clearance 0)
		)
		(min_thickness 0.25)
		(keepout
			(tracks not_allowed)
			(vias allowed)
			(pads allowed)
			(copperpour not_allowed)
			(footprints allowed)
		)
		(placement
			(enabled no)
			(sheetname "")
		)
		(fill yes
			(thermal_gap 0.5)
			(thermal_bridge_width 0.5)
			(island_removal_mode 0)
		)
		(polygon
			(pts
				(arc
					(start 210.3247 -406.535382)
					(mid 208.5467 -406.535382)
					(end 210.3247 -406.535382)
				)
			)
		)
	)
	(zone
		(layers "In3.Cu" "In5.Cu" "In12.Cu" "In14.Cu")
		(hatch none 0.5)
		(connect_pads
			(clearance 0)
		)
		(min_thickness 0.25)
		(keepout
			(tracks not_allowed)
			(vias allowed)
			(pads allowed)
			(copperpour not_allowed)
			(footprints allowed)
		)
		(placement
			(enabled no)
			(sheetname "")
		)
		(fill yes
			(thermal_gap 0.5)
			(thermal_bridge_width 0.5)
			(island_removal_mode 0)
		)
		(polygon
			(pts
				(arc
					(start 201.822558 -403.223222)
					(mid 200.044558 -403.223222)
					(end 201.822558 -403.223222)
				)
			)
		)
	)
	(zone
		(layers "In3.Cu" "In5.Cu" "In12.Cu" "In14.Cu")
		(hatch none 0.5)
		(connect_pads
			(clearance 0)
		)
		(min_thickness 0.25)
		(keepout
			(tracks not_allowed)
			(vias allowed)
			(pads allowed)
			(copperpour not_allowed)
			(footprints allowed)
		)
		(placement
			(enabled no)
			(sheetname "")
		)
		(fill yes
			(thermal_gap 0.5)
			(thermal_bridge_width 0.5)
			(island_removal_mode 0)
		)
		(polygon
			(pts
				(arc
					(start 231.007158 -403.223222)
					(mid 229.229158 -403.223222)
					(end 231.007158 -403.223222)
				)
			)
		)
	)
	(zone
		(layers "In3.Cu" "In5.Cu" "In12.Cu" "In14.Cu")
		(hatch none 0.5)
		(connect_pads
			(clearance 0)
		)
		(min_thickness 0.25)
		(keepout
			(tracks not_allowed)
			(vias allowed)
			(pads allowed)
			(copperpour not_allowed)
			(footprints allowed)
		)
		(placement
			(enabled no)
			(sheetname "")
		)
		(fill yes
			(thermal_gap 0.5)
			(thermal_bridge_width 0.5)
			(island_removal_mode 0)
		)
		(polygon
			(pts
				(arc
					(start 230.8987 -408.059382)
					(mid 229.1207 -408.059382)
					(end 230.8987 -408.059382)
				)
			)
		)
	)
	(zone
		(layers "In3.Cu" "In5.Cu" "In12.Cu" "In14.Cu")
		(hatch none 0.5)
		(connect_pads
			(clearance 0)
		)
		(min_thickness 0.25)
		(keepout
			(tracks not_allowed)
			(vias allowed)
			(pads allowed)
			(copperpour not_allowed)
			(footprints allowed)
		)
		(placement
			(enabled no)
			(sheetname "")
		)
		(fill yes
			(thermal_gap 0.5)
			(thermal_bridge_width 0.5)
			(island_removal_mode 0)
		)
		(polygon
			(pts
				(arc
					(start 220.2307 -406.535382)
					(mid 218.4527 -406.535382)
					(end 220.2307 -406.535382)
				)
			)
		)
	)
	(zone
		(layers "In3.Cu" "In5.Cu" "In12.Cu" "In14.Cu")
		(hatch none 0.5)
		(connect_pads
			(clearance 0)
		)
		(min_thickness 0.25)
		(keepout
			(tracks not_allowed)
			(vias allowed)
			(pads allowed)
			(copperpour not_allowed)
			(footprints allowed)
		)
		(placement
			(enabled no)
			(sheetname "")
		)
		(fill yes
			(thermal_gap 0.5)
			(thermal_bridge_width 0.5)
			(island_removal_mode 0)
		)
		(polygon
			(pts
				(arc
					(start 231.6607 -408.059382)
					(mid 229.8827 -408.059382)
					(end 231.6607 -408.059382)
				)
			)
		)
	)
	(zone
		(layers "In3.Cu" "In5.Cu" "In12.Cu" "In14.Cu")
		(hatch none 0.5)
		(connect_pads
			(clearance 0)
		)
		(min_thickness 0.25)
		(keepout
			(tracks not_allowed)
			(vias allowed)
			(pads allowed)
			(copperpour not_allowed)
			(footprints allowed)
		)
		(placement
			(enabled no)
			(sheetname "")
		)
		(fill yes
			(thermal_gap 0.5)
			(thermal_bridge_width 0.5)
			(island_removal_mode 0)
		)
		(polygon
			(pts
				(arc
					(start 223.158558 -401.920202)
					(mid 221.380558 -401.920202)
					(end 223.158558 -401.920202)
				)
			)
		)
	)
	(zone
		(layers "In3.Cu" "In5.Cu" "In12.Cu" "In14.Cu")
		(hatch none 0.5)
		(connect_pads
			(clearance 0)
		)
		(min_thickness 0.25)
		(keepout
			(tracks not_allowed)
			(vias allowed)
			(pads allowed)
			(copperpour not_allowed)
			(footprints allowed)
		)
		(placement
			(enabled no)
			(sheetname "")
		)
		(fill yes
			(thermal_gap 0.5)
			(thermal_bridge_width 0.5)
			(island_removal_mode 0)
		)
		(polygon
			(pts
				(arc
					(start 185.74512 -401.919694)
					(mid 183.96712 -401.919694)
					(end 185.74512 -401.919694)
				)
			)
		)
	)
	(zone
		(layers "In3.Cu" "In5.Cu" "In12.Cu" "In14.Cu")
		(hatch none 0.5)
		(connect_pads
			(clearance 0)
		)
		(min_thickness 0.25)
		(keepout
			(tracks not_allowed)
			(vias allowed)
			(pads allowed)
			(copperpour not_allowed)
			(footprints allowed)
		)
		(placement
			(enabled no)
			(sheetname "")
		)
		(fill yes
			(thermal_gap 0.5)
			(thermal_bridge_width 0.5)
			(island_removal_mode 0)
		)
		(polygon
			(pts
				(arc
					(start 201.1807 -407.297382)
					(mid 199.4027 -407.297382)
					(end 201.1807 -407.297382)
				)
			)
		)
	)
	(zone
		(layers "In3.Cu" "In5.Cu" "In12.Cu" "In14.Cu")
		(hatch none 0.5)
		(connect_pads
			(clearance 0)
		)
		(min_thickness 0.25)
		(keepout
			(tracks not_allowed)
			(vias allowed)
			(pads allowed)
			(copperpour not_allowed)
			(footprints allowed)
		)
		(placement
			(enabled no)
			(sheetname "")
		)
		(fill yes
			(thermal_gap 0.5)
			(thermal_bridge_width 0.5)
			(island_removal_mode 0)
		)
		(polygon
			(pts
				(arc
					(start 229.3747 -408.059382)
					(mid 227.5967 -408.059382)
					(end 229.3747 -408.059382)
				)
			)
		)
	)
	(zone
		(layers "In3.Cu" "In5.Cu" "In12.Cu" "In14.Cu")
		(hatch none 0.5)
		(connect_pads
			(clearance 0)
		)
		(min_thickness 0.25)
		(keepout
			(tracks not_allowed)
			(vias allowed)
			(pads allowed)
			(copperpour not_allowed)
			(footprints allowed)
		)
		(placement
			(enabled no)
			(sheetname "")
		)
		(fill yes
			(thermal_gap 0.5)
			(thermal_bridge_width 0.5)
			(island_removal_mode 0)
		)
		(polygon
			(pts
				(arc
					(start 233.9467 -407.297382)
					(mid 232.1687 -407.297382)
					(end 233.9467 -407.297382)
				)
			)
		)
	)
	(zone
		(layers "In3.Cu" "In5.Cu" "In12.Cu" "In14.Cu")
		(hatch none 0.5)
		(connect_pads
			(clearance 0)
		)
		(min_thickness 0.25)
		(keepout
			(tracks not_allowed)
			(vias allowed)
			(pads allowed)
			(copperpour not_allowed)
			(footprints allowed)
		)
		(placement
			(enabled no)
			(sheetname "")
		)
		(fill yes
			(thermal_gap 0.5)
			(thermal_bridge_width 0.5)
			(island_removal_mode 0)
		)
		(polygon
			(pts
				(arc
					(start 231.6607 -407.297382)
					(mid 229.8827 -407.297382)
					(end 231.6607 -407.297382)
				)
			)
		)
	)
	(zone
		(layers "In3.Cu" "In5.Cu" "In12.Cu" "In14.Cu")
		(hatch none 0.5)
		(connect_pads
			(clearance 0)
		)
		(min_thickness 0.25)
		(keepout
			(tracks not_allowed)
			(vias allowed)
			(pads allowed)
			(copperpour not_allowed)
			(footprints allowed)
		)
		(placement
			(enabled no)
			(sheetname "")
		)
		(fill yes
			(thermal_gap 0.5)
			(thermal_bridge_width 0.5)
			(island_removal_mode 0)
		)
		(polygon
			(pts
				(arc
					(start 222.5167 -408.059382)
					(mid 220.7387 -408.059382)
					(end 222.5167 -408.059382)
				)
			)
		)
	)
	(zone
		(layers "In3.Cu" "In5.Cu" "In12.Cu" "In14.Cu")
		(hatch none 0.5)
		(connect_pads
			(clearance 0)
		)
		(min_thickness 0.25)
		(keepout
			(tracks not_allowed)
			(vias allowed)
			(pads allowed)
			(copperpour not_allowed)
			(footprints allowed)
		)
		(placement
			(enabled no)
			(sheetname "")
		)
		(fill yes
			(thermal_gap 0.5)
			(thermal_bridge_width 0.5)
			(island_removal_mode 0)
		)
		(polygon
			(pts
				(arc
					(start 221.7547 -407.297382)
					(mid 219.9767 -407.297382)
					(end 221.7547 -407.297382)
				)
			)
		)
	)
	(zone
		(layers "In3.Cu" "In5.Cu" "In12.Cu" "In14.Cu")
		(hatch none 0.5)
		(connect_pads
			(clearance 0)
		)
		(min_thickness 0.25)
		(keepout
			(tracks not_allowed)
			(vias allowed)
			(pads allowed)
			(copperpour not_allowed)
			(footprints allowed)
		)
		(placement
			(enabled no)
			(sheetname "")
		)
		(fill yes
			(thermal_gap 0.5)
			(thermal_bridge_width 0.5)
			(island_removal_mode 0)
		)
		(polygon
			(pts
				(arc
					(start 221.7547 -406.535382)
					(mid 219.9767 -406.535382)
					(end 221.7547 -406.535382)
				)
			)
		)
	)
	(zone
		(layers "In3.Cu" "In5.Cu" "In12.Cu" "In14.Cu")
		(hatch none 0.5)
		(connect_pads
			(clearance 0)
		)
		(min_thickness 0.25)
		(keepout
			(tracks not_allowed)
			(vias allowed)
			(pads allowed)
			(copperpour not_allowed)
			(footprints allowed)
		)
		(placement
			(enabled no)
			(sheetname "")
		)
		(fill yes
			(thermal_gap 0.5)
			(thermal_bridge_width 0.5)
			(island_removal_mode 0)
		)
		(polygon
			(pts
				(arc
					(start 190.372492 -407.330402)
					(mid 188.594492 -407.330402)
					(end 190.372492 -407.330402)
				)
			)
		)
	)
	(zone
		(layers "In3.Cu" "In5.Cu" "In12.Cu" "In14.Cu")
		(hatch none 0.5)
		(connect_pads
			(clearance 0)
		)
		(min_thickness 0.25)
		(keepout
			(tracks not_allowed)
			(vias allowed)
			(pads allowed)
			(copperpour not_allowed)
			(footprints allowed)
		)
		(placement
			(enabled no)
			(sheetname "")
		)
		(fill yes
			(thermal_gap 0.5)
			(thermal_bridge_width 0.5)
			(island_removal_mode 0)
		)
		(polygon
			(pts
				(arc
					(start 201.9427 -405.773382)
					(mid 200.1647 -405.773382)
					(end 201.9427 -405.773382)
				)
			)
		)
	)
	(zone
		(layers "In3.Cu" "In5.Cu" "In12.Cu" "In14.Cu")
		(hatch none 0.5)
		(connect_pads
			(clearance 0)
		)
		(min_thickness 0.25)
		(keepout
			(tracks not_allowed)
			(vias allowed)
			(pads allowed)
			(copperpour not_allowed)
			(footprints allowed)
		)
		(placement
			(enabled no)
			(sheetname "")
		)
		(fill yes
			(thermal_gap 0.5)
			(thermal_bridge_width 0.5)
			(island_removal_mode 0)
		)
		(polygon
			(pts
				(arc
					(start 211.8487 -405.011382)
					(mid 210.0707 -405.011382)
					(end 211.8487 -405.011382)
				)
			)
		)
	)
	(zone
		(layers "In3.Cu" "In5.Cu" "In12.Cu" "In14.Cu")
		(hatch none 0.5)
		(connect_pads
			(clearance 0)
		)
		(min_thickness 0.25)
		(keepout
			(tracks not_allowed)
			(vias allowed)
			(pads allowed)
			(copperpour not_allowed)
			(footprints allowed)
		)
		(placement
			(enabled no)
			(sheetname "")
		)
		(fill yes
			(thermal_gap 0.5)
			(thermal_bridge_width 0.5)
			(island_removal_mode 0)
		)
		(polygon
			(pts
				(arc
					(start 220.9927 -405.773382)
					(mid 219.2147 -405.773382)
					(end 220.9927 -405.773382)
				)
			)
		)
	)
	(zone
		(layers "In3.Cu" "In5.Cu" "In12.Cu" "In14.Cu")
		(hatch none 0.5)
		(connect_pads
			(clearance 0)
		)
		(min_thickness 0.25)
		(keepout
			(tracks not_allowed)
			(vias allowed)
			(pads allowed)
			(copperpour not_allowed)
			(footprints allowed)
		)
		(placement
			(enabled no)
			(sheetname "")
		)
		(fill yes
			(thermal_gap 0.5)
			(thermal_bridge_width 0.5)
			(island_removal_mode 0)
		)
		(polygon
			(pts
				(arc
					(start 222.5167 -407.297382)
					(mid 220.7387 -407.297382)
					(end 222.5167 -407.297382)
				)
			)
		)
	)
	(zone
		(layers "In3.Cu" "In5.Cu" "In12.Cu" "In14.Cu")
		(hatch none 0.5)
		(connect_pads
			(clearance 0)
		)
		(min_thickness 0.25)
		(keepout
			(tracks not_allowed)
			(vias allowed)
			(pads allowed)
			(copperpour not_allowed)
			(footprints allowed)
		)
		(placement
			(enabled no)
			(sheetname "")
		)
		(fill yes
			(thermal_gap 0.5)
			(thermal_bridge_width 0.5)
			(island_removal_mode 0)
		)
		(polygon
			(pts
				(arc
					(start 198.1327 -405.011382)
					(mid 196.3547 -405.011382)
					(end 198.1327 -405.011382)
				)
			)
		)
	)
	(zone
		(layers "In3.Cu" "In5.Cu" "In12.Cu" "In14.Cu")
		(hatch none 0.5)
		(connect_pads
			(clearance 0)
		)
		(min_thickness 0.25)
		(keepout
			(tracks not_allowed)
			(vias allowed)
			(pads allowed)
			(copperpour not_allowed)
			(footprints allowed)
		)
		(placement
			(enabled no)
			(sheetname "")
		)
		(fill yes
			(thermal_gap 0.5)
			(thermal_bridge_width 0.5)
			(island_removal_mode 0)
		)
		(polygon
			(pts
				(arc
					(start 209.671158 -403.223222)
					(mid 207.893158 -403.223222)
					(end 209.671158 -403.223222)
				)
			)
		)
	)
	(zone
		(layers "In3.Cu" "In5.Cu" "In12.Cu" "In14.Cu")
		(hatch none 0.5)
		(connect_pads
			(clearance 0)
		)
		(min_thickness 0.25)
		(keepout
			(tracks not_allowed)
			(vias allowed)
			(pads allowed)
			(copperpour not_allowed)
			(footprints allowed)
		)
		(placement
			(enabled no)
			(sheetname "")
		)
		(fill yes
			(thermal_gap 0.5)
			(thermal_bridge_width 0.5)
			(island_removal_mode 0)
		)
		(polygon
			(pts
				(arc
					(start 212.490558 -401.920202)
					(mid 210.712558 -401.920202)
					(end 212.490558 -401.920202)
				)
			)
		)
	)
	(zone
		(layers "In3.Cu" "In5.Cu" "In12.Cu" "In14.Cu")
		(hatch none 0.5)
		(connect_pads
			(clearance 0)
		)
		(min_thickness 0.25)
		(keepout
			(tracks not_allowed)
			(vias allowed)
			(pads allowed)
			(copperpour not_allowed)
			(footprints allowed)
		)
		(placement
			(enabled no)
			(sheetname "")
		)
		(fill yes
			(thermal_gap 0.5)
			(thermal_bridge_width 0.5)
			(island_removal_mode 0)
		)
		(polygon
			(pts
				(arc
					(start 221.7547 -405.011382)
					(mid 219.9767 -405.011382)
					(end 221.7547 -405.011382)
				)
			)
		)
	)
	(zone
		(layers "In3.Cu" "In5.Cu" "In12.Cu" "In14.Cu")
		(hatch none 0.5)
		(connect_pads
			(clearance 0)
		)
		(min_thickness 0.25)
		(keepout
			(tracks not_allowed)
			(vias allowed)
			(pads allowed)
			(copperpour not_allowed)
			(footprints allowed)
		)
		(placement
			(enabled no)
			(sheetname "")
		)
		(fill yes
			(thermal_gap 0.5)
			(thermal_bridge_width 0.5)
			(island_removal_mode 0)
		)
		(polygon
			(pts
				(arc
					(start 223.2787 -405.011382)
					(mid 221.5007 -405.011382)
					(end 223.2787 -405.011382)
				)
			)
		)
	)
	(zone
		(layers "In3.Cu" "In5.Cu" "In12.Cu" "In14.Cu")
		(hatch none 0.5)
		(connect_pads
			(clearance 0)
		)
		(min_thickness 0.25)
		(keepout
			(tracks not_allowed)
			(vias allowed)
			(pads allowed)
			(copperpour not_allowed)
			(footprints allowed)
		)
		(placement
			(enabled no)
			(sheetname "")
		)
		(fill yes
			(thermal_gap 0.5)
			(thermal_bridge_width 0.5)
			(island_removal_mode 0)
		)
		(polygon
			(pts
				(arc
					(start 230.8987 -405.773382)
					(mid 229.1207 -405.773382)
					(end 230.8987 -405.773382)
				)
			)
		)
	)
	(zone
		(layers "In3.Cu" "In5.Cu" "In12.Cu" "In14.Cu")
		(hatch none 0.5)
		(connect_pads
			(clearance 0)
		)
		(min_thickness 0.25)
		(keepout
			(tracks not_allowed)
			(vias allowed)
			(pads allowed)
			(copperpour not_allowed)
			(footprints allowed)
		)
		(placement
			(enabled no)
			(sheetname "")
		)
		(fill yes
			(thermal_gap 0.5)
			(thermal_bridge_width 0.5)
			(island_removal_mode 0)
		)
		(polygon
			(pts
				(arc
					(start 186.562492 -406.517602)
					(mid 184.784492 -406.517602)
					(end 186.562492 -406.517602)
				)
			)
		)
	)
	(zone
		(layers "In3.Cu" "In5.Cu" "In12.Cu" "In14.Cu")
		(hatch none 0.5)
		(connect_pads
			(clearance 0)
		)
		(min_thickness 0.25)
		(keepout
			(tracks not_allowed)
			(vias allowed)
			(pads allowed)
			(copperpour not_allowed)
			(footprints allowed)
		)
		(placement
			(enabled no)
			(sheetname "")
		)
		(fill yes
			(thermal_gap 0.5)
			(thermal_bridge_width 0.5)
			(island_removal_mode 0)
		)
		(polygon
			(pts
				(arc
					(start 223.2787 -407.297382)
					(mid 221.5007 -407.297382)
					(end 223.2787 -407.297382)
				)
			)
		)
	)
	(zone
		(layers "In3.Cu" "In5.Cu" "In12.Cu" "In14.Cu")
		(hatch none 0.5)
		(connect_pads
			(clearance 0)
		)
		(min_thickness 0.25)
		(keepout
			(tracks not_allowed)
			(vias allowed)
			(pads allowed)
			(copperpour not_allowed)
			(footprints allowed)
		)
		(placement
			(enabled no)
			(sheetname "")
		)
		(fill yes
			(thermal_gap 0.5)
			(thermal_bridge_width 0.5)
			(island_removal_mode 0)
		)
		(polygon
			(pts
				(arc
					(start 230.8987 -407.297382)
					(mid 229.1207 -407.297382)
					(end 230.8987 -407.297382)
				)
			)
		)
	)
	(zone
		(layers "In3.Cu" "In5.Cu" "In12.Cu" "In14.Cu")
		(hatch none 0.5)
		(connect_pads
			(clearance 0)
		)
		(min_thickness 0.25)
		(keepout
			(tracks not_allowed)
			(vias allowed)
			(pads allowed)
			(copperpour not_allowed)
			(footprints allowed)
		)
		(placement
			(enabled no)
			(sheetname "")
		)
		(fill yes
			(thermal_gap 0.5)
			(thermal_bridge_width 0.5)
			(island_removal_mode 0)
		)
		(polygon
			(pts
				(arc
					(start 230.8987 -406.535382)
					(mid 229.1207 -406.535382)
					(end 230.8987 -406.535382)
				)
			)
		)
	)
	(zone
		(layers "In3.Cu" "In5.Cu" "In12.Cu" "In14.Cu")
		(hatch none 0.5)
		(connect_pads
			(clearance 0)
		)
		(min_thickness 0.25)
		(keepout
			(tracks not_allowed)
			(vias allowed)
			(pads allowed)
			(copperpour not_allowed)
			(footprints allowed)
		)
		(placement
			(enabled no)
			(sheetname "")
		)
		(fill yes
			(thermal_gap 0.5)
			(thermal_bridge_width 0.5)
			(island_removal_mode 0)
		)
		(polygon
			(pts
				(arc
					(start 199.6567 -405.773382)
					(mid 197.8787 -405.773382)
					(end 199.6567 -405.773382)
				)
			)
		)
	)
	(zone
		(layers "In3.Cu" "In5.Cu" "In12.Cu" "In14.Cu")
		(hatch none 0.5)
		(connect_pads
			(clearance 0)
		)
		(min_thickness 0.25)
		(keepout
			(tracks not_allowed)
			(vias allowed)
			(pads allowed)
			(copperpour not_allowed)
			(footprints allowed)
		)
		(placement
			(enabled no)
			(sheetname "")
		)
		(fill yes
			(thermal_gap 0.5)
			(thermal_bridge_width 0.5)
			(island_removal_mode 0)
		)
		(polygon
			(pts
				(arc
					(start 232.4227 -408.059382)
					(mid 230.6447 -408.059382)
					(end 232.4227 -408.059382)
				)
			)
		)
	)
	(zone
		(layers "In3.Cu" "In5.Cu" "In12.Cu" "In14.Cu")
		(hatch none 0.5)
		(connect_pads
			(clearance 0)
		)
		(min_thickness 0.25)
		(keepout
			(tracks not_allowed)
			(vias allowed)
			(pads allowed)
			(copperpour not_allowed)
			(footprints allowed)
		)
		(placement
			(enabled no)
			(sheetname "")
		)
		(fill yes
			(thermal_gap 0.5)
			(thermal_bridge_width 0.5)
			(island_removal_mode 0)
		)
		(polygon
			(pts
				(arc
					(start 212.490558 -403.223222)
					(mid 210.712558 -403.223222)
					(end 212.490558 -403.223222)
				)
			)
		)
	)
	(zone
		(layers "In3.Cu" "In5.Cu" "In12.Cu" "In14.Cu")
		(hatch none 0.5)
		(connect_pads
			(clearance 0)
		)
		(min_thickness 0.25)
		(keepout
			(tracks not_allowed)
			(vias allowed)
			(pads allowed)
			(copperpour not_allowed)
			(footprints allowed)
		)
		(placement
			(enabled no)
			(sheetname "")
		)
		(fill yes
			(thermal_gap 0.5)
			(thermal_bridge_width 0.5)
			(island_removal_mode 0)
		)
		(polygon
			(pts
				(arc
					(start 221.7547 -405.773382)
					(mid 219.9767 -405.773382)
					(end 221.7547 -405.773382)
				)
			)
		)
	)
	(zone
		(layers "In3.Cu" "In5.Cu" "In12.Cu" "In14.Cu")
		(hatch none 0.5)
		(connect_pads
			(clearance 0)
		)
		(min_thickness 0.25)
		(keepout
			(tracks not_allowed)
			(vias allowed)
			(pads allowed)
			(copperpour not_allowed)
			(footprints allowed)
		)
		(placement
			(enabled no)
			(sheetname "")
		)
		(fill yes
			(thermal_gap 0.5)
			(thermal_bridge_width 0.5)
			(island_removal_mode 0)
		)
		(polygon
			(pts
				(arc
					(start 218.7067 -408.059382)
					(mid 216.9287 -408.059382)
					(end 218.7067 -408.059382)
				)
			)
		)
	)
	(zone
		(layers "In3.Cu" "In5.Cu" "In12.Cu" "In14.Cu")
		(hatch none 0.5)
		(connect_pads
			(clearance 0)
		)
		(min_thickness 0.25)
		(keepout
			(tracks not_allowed)
			(vias allowed)
			(pads allowed)
			(copperpour not_allowed)
			(footprints allowed)
		)
		(placement
			(enabled no)
			(sheetname "")
		)
		(fill yes
			(thermal_gap 0.5)
			(thermal_bridge_width 0.5)
			(island_removal_mode 0)
		)
		(polygon
			(pts
				(arc
					(start 212.6107 -407.297382)
					(mid 210.8327 -407.297382)
					(end 212.6107 -407.297382)
				)
			)
		)
	)
	(zone
		(layers "In3.Cu" "In5.Cu" "In12.Cu" "In14.Cu")
		(hatch none 0.5)
		(connect_pads
			(clearance 0)
		)
		(min_thickness 0.25)
		(keepout
			(tracks not_allowed)
			(vias allowed)
			(pads allowed)
			(copperpour not_allowed)
			(footprints allowed)
		)
		(placement
			(enabled no)
			(sheetname "")
		)
		(fill yes
			(thermal_gap 0.5)
			(thermal_bridge_width 0.5)
			(island_removal_mode 0)
		)
		(polygon
			(pts
				(arc
					(start 200.4187 -405.773382)
					(mid 198.6407 -405.773382)
					(end 200.4187 -405.773382)
				)
			)
		)
	)
	(zone
		(layers "In3.Cu" "In5.Cu" "In12.Cu" "In14.Cu")
		(hatch none 0.5)
		(connect_pads
			(clearance 0)
		)
		(min_thickness 0.25)
		(keepout
			(tracks not_allowed)
			(vias allowed)
			(pads allowed)
			(copperpour not_allowed)
			(footprints allowed)
		)
		(placement
			(enabled no)
			(sheetname "")
		)
		(fill yes
			(thermal_gap 0.5)
			(thermal_bridge_width 0.5)
			(island_removal_mode 0)
		)
		(polygon
			(pts
				(arc
					(start 208.8007 -408.059382)
					(mid 207.0227 -408.059382)
					(end 208.8007 -408.059382)
				)
			)
		)
	)
	(zone
		(layers "In3.Cu" "In7.Cu")
		(hatch none 0.5)
		(connect_pads
			(clearance 0)
		)
		(min_thickness 0.25)
		(keepout
			(tracks not_allowed)
			(vias allowed)
			(pads allowed)
			(copperpour not_allowed)
			(footprints allowed)
		)
		(placement
			(enabled no)
			(sheetname "")
		)
		(fill yes
			(thermal_gap 0.5)
			(thermal_bridge_width 0.5)
			(island_removal_mode 0)
		)
		(polygon
			(pts
				(arc
					(start 383.241804 -439.76036)
					(mid 383.264122 -439.814242)
					(end 383.318004 -439.83656)
				)
				(arc
					(start 384.257804 -439.83656)
					(mid 384.311686 -439.814242)
					(end 384.334004 -439.76036)
				)
				(arc
					(start 384.334004 -437.218836)
					(mid 384.311686 -437.164954)
					(end 384.257804 -437.142636)
				)
				(arc
					(start 383.318004 -437.142636)
					(mid 383.264122 -437.164954)
					(end 383.241804 -437.218836)
				)
			)
		)
	)
	(zone
		(layers "In3.Cu" "In7.Cu")
		(hatch none 0.5)
		(connect_pads
			(clearance 0)
		)
		(min_thickness 0.25)
		(keepout
			(tracks not_allowed)
			(vias allowed)
			(pads allowed)
			(copperpour not_allowed)
			(footprints allowed)
		)
		(placement
			(enabled no)
			(sheetname "")
		)
		(fill yes
			(thermal_gap 0.5)
			(thermal_bridge_width 0.5)
			(island_removal_mode 0)
		)
		(polygon
			(pts
				(arc
					(start 389.241792 -438.760362)
					(mid 389.26411 -438.814244)
					(end 389.317992 -438.836562)
				)
				(arc
					(start 390.257792 -438.836562)
					(mid 390.311674 -438.814244)
					(end 390.333992 -438.760362)
				)
				(arc
					(start 390.333992 -436.218838)
					(mid 390.311674 -436.164956)
					(end 390.257792 -436.142638)
				)
				(arc
					(start 389.317992 -436.142638)
					(mid 389.26411 -436.164956)
					(end 389.241792 -436.218838)
				)
			)
		)
	)
	(zone
		(layers "In3.Cu" "In7.Cu")
		(hatch none 0.5)
		(connect_pads
			(clearance 0)
		)
		(min_thickness 0.25)
		(keepout
			(tracks not_allowed)
			(vias allowed)
			(pads allowed)
			(copperpour not_allowed)
			(footprints allowed)
		)
		(placement
			(enabled no)
			(sheetname "")
		)
		(fill yes
			(thermal_gap 0.5)
			(thermal_bridge_width 0.5)
			(island_removal_mode 0)
		)
		(polygon
			(pts
				(arc
					(start 391.241788 -439.76036)
					(mid 391.264106 -439.814242)
					(end 391.317988 -439.83656)
				)
				(arc
					(start 392.257788 -439.83656)
					(mid 392.31167 -439.814242)
					(end 392.333988 -439.76036)
				)
				(arc
					(start 392.333988 -437.218836)
					(mid 392.31167 -437.164954)
					(end 392.257788 -437.142636)
				)
				(arc
					(start 391.317988 -437.142636)
					(mid 391.264106 -437.164954)
					(end 391.241788 -437.218836)
				)
			)
		)
	)
	(zone
		(layers "In3.Cu" "In7.Cu")
		(hatch none 0.5)
		(connect_pads
			(clearance 0)
		)
		(min_thickness 0.25)
		(keepout
			(tracks not_allowed)
			(vias allowed)
			(pads allowed)
			(copperpour not_allowed)
			(footprints allowed)
		)
		(placement
			(enabled no)
			(sheetname "")
		)
		(fill yes
			(thermal_gap 0.5)
			(thermal_bridge_width 0.5)
			(island_removal_mode 0)
		)
		(polygon
			(pts
				(arc
					(start 381.241808 -438.760362)
					(mid 381.264126 -438.814244)
					(end 381.318008 -438.836562)
				)
				(arc
					(start 382.257808 -438.836562)
					(mid 382.31169 -438.814244)
					(end 382.334008 -438.760362)
				)
				(arc
					(start 382.334008 -436.218838)
					(mid 382.31169 -436.164956)
					(end 382.257808 -436.142638)
				)
				(arc
					(start 381.318008 -436.142638)
					(mid 381.264126 -436.164956)
					(end 381.241808 -436.218838)
				)
			)
		)
	)
	(zone
		(layers "In3.Cu" "In7.Cu")
		(hatch none 0.5)
		(connect_pads
			(clearance 0)
		)
		(min_thickness 0.25)
		(keepout
			(tracks not_allowed)
			(vias allowed)
			(pads allowed)
			(copperpour not_allowed)
			(footprints allowed)
		)
		(placement
			(enabled no)
			(sheetname "")
		)
		(fill yes
			(thermal_gap 0.5)
			(thermal_bridge_width 0.5)
			(island_removal_mode 0)
		)
		(polygon
			(pts
				(arc
					(start 400.24177 -439.76036)
					(mid 400.264088 -439.814242)
					(end 400.31797 -439.83656)
				)
				(arc
					(start 401.25777 -439.83656)
					(mid 401.311652 -439.814242)
					(end 401.33397 -439.76036)
				)
				(arc
					(start 401.33397 -437.218836)
					(mid 401.311652 -437.164954)
					(end 401.25777 -437.142636)
				)
				(arc
					(start 400.31797 -437.142636)
					(mid 400.264088 -437.164954)
					(end 400.24177 -437.218836)
				)
			)
		)
	)
	(zone
		(layers "In3.Cu" "In7.Cu")
		(hatch none 0.5)
		(connect_pads
			(clearance 0)
		)
		(min_thickness 0.25)
		(keepout
			(tracks not_allowed)
			(vias allowed)
			(pads allowed)
			(copperpour not_allowed)
			(footprints allowed)
		)
		(placement
			(enabled no)
			(sheetname "")
		)
		(fill yes
			(thermal_gap 0.5)
			(thermal_bridge_width 0.5)
			(island_removal_mode 0)
		)
		(polygon
			(pts
				(arc
					(start 387.241796 -439.76036)
					(mid 387.264114 -439.814242)
					(end 387.317996 -439.83656)
				)
				(arc
					(start 388.257796 -439.83656)
					(mid 388.311678 -439.814242)
					(end 388.333996 -439.76036)
				)
				(arc
					(start 388.333996 -437.218836)
					(mid 388.311678 -437.164954)
					(end 388.257796 -437.142636)
				)
				(arc
					(start 387.317996 -437.142636)
					(mid 387.264114 -437.164954)
					(end 387.241796 -437.218836)
				)
			)
		)
	)
	(zone
		(layers "In3.Cu" "In7.Cu")
		(hatch none 0.5)
		(connect_pads
			(clearance 0)
		)
		(min_thickness 0.25)
		(keepout
			(tracks not_allowed)
			(vias allowed)
			(pads allowed)
			(copperpour not_allowed)
			(footprints allowed)
		)
		(placement
			(enabled no)
			(sheetname "")
		)
		(fill yes
			(thermal_gap 0.5)
			(thermal_bridge_width 0.5)
			(island_removal_mode 0)
		)
		(polygon
			(pts
				(arc
					(start 385.2418 -438.760362)
					(mid 385.264118 -438.814244)
					(end 385.318 -438.836562)
				)
				(arc
					(start 386.2578 -438.836562)
					(mid 386.311682 -438.814244)
					(end 386.334 -438.760362)
				)
				(arc
					(start 386.334 -436.218838)
					(mid 386.311682 -436.164956)
					(end 386.2578 -436.142638)
				)
				(arc
					(start 385.318 -436.142638)
					(mid 385.264118 -436.164956)
					(end 385.2418 -436.218838)
				)
			)
		)
	)
	(zone
		(layers "In3.Cu" "In7.Cu")
		(hatch none 0.5)
		(connect_pads
			(clearance 0)
		)
		(min_thickness 0.25)
		(keepout
			(tracks not_allowed)
			(vias allowed)
			(pads allowed)
			(copperpour not_allowed)
			(footprints allowed)
		)
		(placement
			(enabled no)
			(sheetname "")
		)
		(fill yes
			(thermal_gap 0.5)
			(thermal_bridge_width 0.5)
			(island_removal_mode 0)
		)
		(polygon
			(pts
				(arc
					(start 393.241784 -438.760362)
					(mid 393.264102 -438.814244)
					(end 393.317984 -438.836562)
				)
				(arc
					(start 394.257784 -438.836562)
					(mid 394.311666 -438.814244)
					(end 394.333984 -438.760362)
				)
				(arc
					(start 394.333984 -436.218838)
					(mid 394.311666 -436.164956)
					(end 394.257784 -436.142638)
				)
				(arc
					(start 393.317984 -436.142638)
					(mid 393.264102 -436.164956)
					(end 393.241784 -436.218838)
				)
			)
		)
	)
	(zone
		(layers "In3.Cu" "In7.Cu")
		(hatch none 0.5)
		(connect_pads
			(clearance 0)
		)
		(min_thickness 0.25)
		(keepout
			(tracks not_allowed)
			(vias allowed)
			(pads allowed)
			(copperpour not_allowed)
			(footprints allowed)
		)
		(placement
			(enabled no)
			(sheetname "")
		)
		(fill yes
			(thermal_gap 0.5)
			(thermal_bridge_width 0.5)
			(island_removal_mode 0)
		)
		(polygon
			(pts
				(arc
					(start 402.241766 -438.760362)
					(mid 402.264084 -438.814244)
					(end 402.317966 -438.836562)
				)
				(arc
					(start 403.257766 -438.836562)
					(mid 403.311648 -438.814244)
					(end 403.333966 -438.760362)
				)
				(arc
					(start 403.333966 -436.218838)
					(mid 403.311648 -436.164956)
					(end 403.257766 -436.142638)
				)
				(arc
					(start 402.317966 -436.142638)
					(mid 402.264084 -436.164956)
					(end 402.241766 -436.218838)
				)
			)
		)
	)
	(zone
		(layers "In3.Cu" "In7.Cu")
		(hatch none 0.5)
		(connect_pads
			(clearance 0)
		)
		(min_thickness 0.25)
		(keepout
			(tracks not_allowed)
			(vias allowed)
			(pads allowed)
			(copperpour not_allowed)
			(footprints allowed)
		)
		(placement
			(enabled no)
			(sheetname "")
		)
		(fill yes
			(thermal_gap 0.5)
			(thermal_bridge_width 0.5)
			(island_removal_mode 0)
		)
		(polygon
			(pts
				(arc
					(start 410.24175 -438.760362)
					(mid 410.264068 -438.814244)
					(end 410.31795 -438.836562)
				)
				(arc
					(start 411.25775 -438.836562)
					(mid 411.311632 -438.814244)
					(end 411.33395 -438.760362)
				)
				(arc
					(start 411.33395 -436.218838)
					(mid 411.311632 -436.164956)
					(end 411.25775 -436.142638)
				)
				(arc
					(start 410.31795 -436.142638)
					(mid 410.264068 -436.164956)
					(end 410.24175 -436.218838)
				)
			)
		)
	)
	(zone
		(layers "In3.Cu" "In7.Cu")
		(hatch none 0.5)
		(connect_pads
			(clearance 0)
		)
		(min_thickness 0.25)
		(keepout
			(tracks not_allowed)
			(vias allowed)
			(pads allowed)
			(copperpour not_allowed)
			(footprints allowed)
		)
		(placement
			(enabled no)
			(sheetname "")
		)
		(fill yes
			(thermal_gap 0.5)
			(thermal_bridge_width 0.5)
			(island_removal_mode 0)
		)
		(polygon
			(pts
				(arc
					(start 395.24178 -439.76036)
					(mid 395.264098 -439.814242)
					(end 395.31798 -439.83656)
				)
				(arc
					(start 396.25778 -439.83656)
					(mid 396.311662 -439.814242)
					(end 396.33398 -439.76036)
				)
				(arc
					(start 396.33398 -437.218836)
					(mid 396.311662 -437.164954)
					(end 396.25778 -437.142636)
				)
				(arc
					(start 395.31798 -437.142636)
					(mid 395.264098 -437.164954)
					(end 395.24178 -437.218836)
				)
			)
		)
	)
	(zone
		(layers "In3.Cu" "In7.Cu")
		(hatch none 0.5)
		(connect_pads
			(clearance 0)
		)
		(min_thickness 0.25)
		(keepout
			(tracks not_allowed)
			(vias allowed)
			(pads allowed)
			(copperpour not_allowed)
			(footprints allowed)
		)
		(placement
			(enabled no)
			(sheetname "")
		)
		(fill yes
			(thermal_gap 0.5)
			(thermal_bridge_width 0.5)
			(island_removal_mode 0)
		)
		(polygon
			(pts
				(arc
					(start 406.241758 -438.760362)
					(mid 406.264076 -438.814244)
					(end 406.317958 -438.836562)
				)
				(arc
					(start 407.257758 -438.836562)
					(mid 407.31164 -438.814244)
					(end 407.333958 -438.760362)
				)
				(arc
					(start 407.333958 -436.218838)
					(mid 407.31164 -436.164956)
					(end 407.257758 -436.142638)
				)
				(arc
					(start 406.317958 -436.142638)
					(mid 406.264076 -436.164956)
					(end 406.241758 -436.218838)
				)
			)
		)
	)
	(zone
		(layers "In3.Cu" "In7.Cu")
		(hatch none 0.5)
		(connect_pads
			(clearance 0)
		)
		(min_thickness 0.25)
		(keepout
			(tracks not_allowed)
			(vias allowed)
			(pads allowed)
			(copperpour not_allowed)
			(footprints allowed)
		)
		(placement
			(enabled no)
			(sheetname "")
		)
		(fill yes
			(thermal_gap 0.5)
			(thermal_bridge_width 0.5)
			(island_removal_mode 0)
		)
		(polygon
			(pts
				(arc
					(start 408.241754 -439.76036)
					(mid 408.264072 -439.814242)
					(end 408.317954 -439.83656)
				)
				(arc
					(start 409.257754 -439.83656)
					(mid 409.311636 -439.814242)
					(end 409.333954 -439.76036)
				)
				(arc
					(start 409.333954 -437.218836)
					(mid 409.311636 -437.164954)
					(end 409.257754 -437.142636)
				)
				(arc
					(start 408.317954 -437.142636)
					(mid 408.264072 -437.164954)
					(end 408.241754 -437.218836)
				)
			)
		)
	)
	(zone
		(layers "In3.Cu" "In7.Cu")
		(hatch none 0.5)
		(connect_pads
			(clearance 0)
		)
		(min_thickness 0.25)
		(keepout
			(tracks not_allowed)
			(vias allowed)
			(pads allowed)
			(copperpour not_allowed)
			(footprints allowed)
		)
		(placement
			(enabled no)
			(sheetname "")
		)
		(fill yes
			(thermal_gap 0.5)
			(thermal_bridge_width 0.5)
			(island_removal_mode 0)
		)
		(polygon
			(pts
				(arc
					(start 404.241762 -439.76036)
					(mid 404.26408 -439.814242)
					(end 404.317962 -439.83656)
				)
				(arc
					(start 405.257762 -439.83656)
					(mid 405.311644 -439.814242)
					(end 405.333962 -439.76036)
				)
				(arc
					(start 405.333962 -437.218836)
					(mid 405.311644 -437.164954)
					(end 405.257762 -437.142636)
				)
				(arc
					(start 404.317962 -437.142636)
					(mid 404.26408 -437.164954)
					(end 404.241762 -437.218836)
				)
			)
		)
	)
	(zone
		(layers "In3.Cu" "In7.Cu")
		(hatch none 0.5)
		(connect_pads
			(clearance 0)
		)
		(min_thickness 0.25)
		(keepout
			(tracks not_allowed)
			(vias allowed)
			(pads allowed)
			(copperpour not_allowed)
			(footprints allowed)
		)
		(placement
			(enabled no)
			(sheetname "")
		)
		(fill yes
			(thermal_gap 0.5)
			(thermal_bridge_width 0.5)
			(island_removal_mode 0)
		)
		(polygon
			(pts
				(arc
					(start 398.241774 -438.760362)
					(mid 398.264092 -438.814244)
					(end 398.317974 -438.836562)
				)
				(arc
					(start 399.257774 -438.836562)
					(mid 399.311656 -438.814244)
					(end 399.333974 -438.760362)
				)
				(arc
					(start 399.333974 -436.218838)
					(mid 399.311656 -436.164956)
					(end 399.257774 -436.142638)
				)
				(arc
					(start 398.317974 -436.142638)
					(mid 398.264092 -436.164956)
					(end 398.241774 -436.218838)
				)
			)
		)
	)
	(zone
		(layers "In3.Cu" "In7.Cu")
		(hatch none 0.5)
		(connect_pads
			(clearance 0)
		)
		(min_thickness 0.25)
		(keepout
			(tracks not_allowed)
			(vias allowed)
			(pads allowed)
			(copperpour not_allowed)
			(footprints allowed)
		)
		(placement
			(enabled no)
			(sheetname "")
		)
		(fill yes
			(thermal_gap 0.5)
			(thermal_bridge_width 0.5)
			(island_removal_mode 0)
		)
		(polygon
			(pts
				(arc
					(start 412.241746 -439.76036)
					(mid 412.264064 -439.814242)
					(end 412.317946 -439.83656)
				)
				(arc
					(start 413.257746 -439.83656)
					(mid 413.311628 -439.814242)
					(end 413.333946 -439.76036)
				)
				(arc
					(start 413.333946 -437.218836)
					(mid 413.311628 -437.164954)
					(end 413.257746 -437.142636)
				)
				(arc
					(start 412.317946 -437.142636)
					(mid 412.264064 -437.164954)
					(end 412.241746 -437.218836)
				)
			)
		)
	)
	(zone
		(layer "In4.Cu")
		(hatch none 0.5)
		(connect_pads
			(clearance 0)
		)
		(min_thickness 0.25)
		(keepout
			(tracks allowed)
			(vias allowed)
			(pads allowed)
			(copperpour allowed)
			(footprints allowed)
		)
		(placement
			(enabled no)
			(sheetname "")
		)
		(fill
			(thermal_gap 0.5)
			(thermal_bridge_width 0.5)
			(island_removal_mode 0)
		)
		(polygon
			(pts
				(xy 59.95035 -350.283272) (xy 59.57443 -350.283272) (xy 59.15279 -350.704912) (xy 59.15279 -352.046032)
				(xy 58.52033 -352.678492) (xy 53.94579 -352.678492) (xy 52.61991 -354.004372) (xy 52.61991 -356.219252)
				(xy 52.83835 -356.437692) (xy 52.89169 -356.437692) (xy 53.53177 -355.797612) (xy 53.53177 -354.212652)
				(xy 54.27599 -353.468432) (xy 58.82259 -353.468432) (xy 59.94527 -352.345752) (xy 59.94527 -351.560892)
				(xy 60.18149 -351.324672) (xy 60.18149 -350.514412)
			)
		)
	)
	(zone
		(layer "In4.Cu")
		(hatch none 0.5)
		(connect_pads
			(clearance 0)
		)
		(min_thickness 0.25)
		(keepout
			(tracks not_allowed)
			(vias allowed)
			(pads allowed)
			(copperpour not_allowed)
			(footprints allowed)
		)
		(placement
			(enabled no)
			(sheetname "")
		)
		(fill
			(thermal_gap 0.5)
			(thermal_bridge_width 0.5)
			(island_removal_mode 0)
		)
		(polygon
			(pts
				(xy 242.68176 -314.031884) (xy 242.68176 -313.246008) (xy 244.761766 -313.246008) (xy 244.761766 -314.031884)
			)
		)
	)
	(zone
		(layer "In4.Cu")
		(hatch none 0.5)
		(connect_pads
			(clearance 0)
		)
		(min_thickness 0.25)
		(keepout
			(tracks not_allowed)
			(vias allowed)
			(pads allowed)
			(copperpour not_allowed)
			(footprints allowed)
		)
		(placement
			(enabled no)
			(sheetname "")
		)
		(fill
			(thermal_gap 0.5)
			(thermal_bridge_width 0.5)
			(island_removal_mode 0)
		)
		(polygon
			(pts
				(arc
					(start 181.597808 -376.489976)
					(mid 173.402244 -376.489976)
					(end 181.597808 -376.489976)
				)
			)
		)
	)
	(zone
		(layer "In4.Cu")
		(hatch none 0.5)
		(connect_pads
			(clearance 0)
		)
		(min_thickness 0.25)
		(keepout
			(tracks allowed)
			(vias allowed)
			(pads allowed)
			(copperpour allowed)
			(footprints allowed)
		)
		(placement
			(enabled no)
			(sheetname "")
		)
		(fill
			(thermal_gap 0.5)
			(thermal_bridge_width 0.5)
			(island_removal_mode 0)
		)
		(polygon
			(pts
				(xy 117.973094 -168.129712) (xy 118.455694 -167.647112) (xy 118.455694 -166.427912) (xy 113.350294 -161.322512)
				(xy 108.270294 -161.322512) (xy 99.913694 -152.965912) (xy 99.913694 -152.330912) (xy 99.710494 -152.127712)
				(xy 99.050094 -152.127712) (xy 98.923094 -152.254712) (xy 98.923094 -153.194512) (xy 107.838494 -162.109912)
				(xy 112.969294 -162.109912) (xy 117.566694 -166.707312) (xy 117.566694 -167.139112) (xy 117.388894 -167.316912)
				(xy 117.388894 -168.231312) (xy 117.541294 -168.383712) (xy 117.719094 -168.383712)
			)
		)
	)
	(zone
		(layer "In4.Cu")
		(hatch none 0.5)
		(connect_pads
			(clearance 0)
		)
		(min_thickness 0.25)
		(keepout
			(tracks allowed)
			(vias allowed)
			(pads allowed)
			(copperpour allowed)
			(footprints allowed)
		)
		(placement
			(enabled no)
			(sheetname "")
		)
		(fill
			(thermal_gap 0.5)
			(thermal_bridge_width 0.5)
			(island_removal_mode 0)
		)
		(polygon
			(pts
				(xy 179.722526 -385.673092) (xy 179.722526 -385.105656) (xy 180.241702 -385.105656) (xy 180.241702 -385.673092)
			)
		)
	)
	(zone
		(layer "In4.Cu")
		(hatch none 0.5)
		(connect_pads
			(clearance 0)
		)
		(min_thickness 0.25)
		(keepout
			(tracks allowed)
			(vias allowed)
			(pads allowed)
			(copperpour allowed)
			(footprints allowed)
		)
		(placement
			(enabled no)
			(sheetname "")
		)
		(fill
			(thermal_gap 0.5)
			(thermal_bridge_width 0.5)
			(island_removal_mode 0)
		)
		(polygon
			(pts
				(xy 75.169014 -335.933796) (xy 75.169014 -336.700876) (xy 75.024234 -336.700876) (xy 75.024234 -335.933796)
			)
		)
	)
	(zone
		(layer "In4.Cu")
		(hatch none 0.5)
		(connect_pads
			(clearance 0)
		)
		(min_thickness 0.25)
		(keepout
			(tracks allowed)
			(vias allowed)
			(pads allowed)
			(copperpour allowed)
			(footprints allowed)
		)
		(placement
			(enabled no)
			(sheetname "")
		)
		(fill
			(thermal_gap 0.5)
			(thermal_bridge_width 0.5)
			(island_removal_mode 0)
		)
		(polygon
			(pts
				(xy 197.009258 -405.25954) (xy 197.009258 -403.525482) (xy 200.085452 -403.525482) (xy 201.298302 -403.525482)
				(xy 201.298302 -405.25954) (xy 200.085452 -405.25954)
			)
		)
	)
	(zone
		(layer "In4.Cu")
		(hatch none 0.5)
		(connect_pads
			(clearance 0)
		)
		(min_thickness 0.25)
		(keepout
			(tracks allowed)
			(vias allowed)
			(pads allowed)
			(copperpour allowed)
			(footprints allowed)
		)
		(placement
			(enabled no)
			(sheetname "")
		)
		(fill
			(thermal_gap 0.5)
			(thermal_bridge_width 0.5)
			(island_removal_mode 0)
		)
		(polygon
			(pts
				(xy 430.013618 -355.543612) (xy 429.200818 -355.543612) (xy 429.023018 -355.721412) (xy 429.023018 -356.762812)
				(xy 427.600618 -358.185212) (xy 419.345618 -358.185212) (xy 418.990018 -358.540812) (xy 418.990018 -359.048812)
				(xy 419.167818 -359.226612) (xy 419.396418 -359.226612) (xy 419.675818 -358.947212) (xy 427.930818 -358.947212)
				(xy 429.759618 -357.118412) (xy 429.759618 -356.178612) (xy 430.140618 -355.797612) (xy 430.140618 -355.670612)
			)
		)
	)
	(zone
		(layer "In4.Cu")
		(hatch none 0.5)
		(connect_pads
			(clearance 0)
		)
		(min_thickness 0.25)
		(keepout
			(tracks allowed)
			(vias allowed)
			(pads allowed)
			(copperpour allowed)
			(footprints allowed)
		)
		(placement
			(enabled no)
			(sheetname "")
		)
		(fill
			(thermal_gap 0.5)
			(thermal_bridge_width 0.5)
			(island_removal_mode 0)
		)
		(polygon
			(pts
				(xy 91.785694 -149.130512) (xy 91.023694 -149.130512) (xy 88.356694 -151.797512) (xy 84.597494 -151.797512)
				(xy 80.381094 -156.013912) (xy 80.381094 -173.743112) (xy 84.191094 -177.553112) (xy 84.191094 -177.908712)
				(xy 83.962494 -178.137312) (xy 83.962494 -179.051712) (xy 84.140294 -179.229512) (xy 84.368894 -179.229512)
				(xy 85.054694 -178.543712) (xy 85.054694 -177.222912) (xy 81.193894 -173.362112) (xy 81.193894 -156.394912)
				(xy 84.978494 -152.610312) (xy 88.712294 -152.610312) (xy 91.201494 -150.121112) (xy 91.684094 -150.121112)
				(xy 91.938094 -149.867112) (xy 91.938094 -149.282912)
			)
		)
	)
	(zone
		(layer "In4.Cu")
		(hatch none 0.5)
		(connect_pads
			(clearance 0)
		)
		(min_thickness 0.25)
		(keepout
			(tracks allowed)
			(vias allowed)
			(pads allowed)
			(copperpour allowed)
			(footprints allowed)
		)
		(placement
			(enabled no)
			(sheetname "")
		)
		(fill
			(thermal_gap 0.5)
			(thermal_bridge_width 0.5)
			(island_removal_mode 0)
		)
		(polygon
			(pts
				(xy 58.23585 -347.611192) (xy 58.23585 -348.520512) (xy 58.07837 -348.520512) (xy 58.07837 -347.611192)
			)
		)
	)
	(zone
		(layer "In4.Cu")
		(hatch none 0.5)
		(connect_pads
			(clearance 0)
		)
		(min_thickness 0.25)
		(keepout
			(tracks allowed)
			(vias allowed)
			(pads allowed)
			(copperpour allowed)
			(footprints allowed)
		)
		(placement
			(enabled no)
			(sheetname "")
		)
		(fill
			(thermal_gap 0.5)
			(thermal_bridge_width 0.5)
			(island_removal_mode 0)
		)
		(polygon
			(pts
				(xy 167.834056 -118.670578) (xy 167.834056 -116.917216) (xy 168.638728 -116.917216) (xy 168.638728 -118.670578)
			)
		)
	)
	(zone
		(layer "In4.Cu")
		(hatch none 0.5)
		(connect_pads
			(clearance 0)
		)
		(min_thickness 0.25)
		(keepout
			(tracks allowed)
			(vias allowed)
			(pads allowed)
			(copperpour allowed)
			(footprints allowed)
		)
		(placement
			(enabled no)
			(sheetname "")
		)
		(fill
			(thermal_gap 0.5)
			(thermal_bridge_width 0.5)
			(island_removal_mode 0)
		)
		(polygon
			(pts
				(xy 301.704756 -367.062512) (xy 301.704756 -366.467898) (xy 302.23333 -366.467898) (xy 302.23333 -367.062512)
			)
		)
	)
	(zone
		(layer "In4.Cu")
		(hatch none 0.5)
		(connect_pads
			(clearance 0)
		)
		(min_thickness 0.25)
		(keepout
			(tracks allowed)
			(vias allowed)
			(pads allowed)
			(copperpour allowed)
			(footprints allowed)
		)
		(placement
			(enabled no)
			(sheetname "")
		)
		(fill
			(thermal_gap 0.5)
			(thermal_bridge_width 0.5)
			(island_removal_mode 0)
		)
		(polygon
			(pts
				(xy 392.751818 -175.864012) (xy 391.253218 -177.362612) (xy 391.253218 -179.039012) (xy 391.405618 -179.191412)
				(xy 391.583418 -179.191412) (xy 392.142218 -178.632612) (xy 392.142218 -177.515012) (xy 393.488418 -176.168812)
				(xy 393.488418 -155.061412) (xy 388.967218 -150.540212) (xy 383.861818 -150.540212) (xy 383.176018 -149.854412)
				(xy 382.820418 -149.854412) (xy 382.490218 -150.184612) (xy 382.490218 -150.311612) (xy 383.506218 -151.327612)
				(xy 388.713218 -151.327612) (xy 392.751818 -155.366212)
			)
		)
	)
	(zone
		(layer "In4.Cu")
		(hatch none 0.5)
		(connect_pads
			(clearance 0)
		)
		(min_thickness 0.25)
		(keepout
			(tracks allowed)
			(vias allowed)
			(pads allowed)
			(copperpour allowed)
			(footprints allowed)
		)
		(placement
			(enabled no)
			(sheetname "")
		)
		(fill
			(thermal_gap 0.5)
			(thermal_bridge_width 0.5)
			(island_removal_mode 0)
		)
		(polygon
			(pts
				(xy 421.352218 -354.908612) (xy 420.844218 -355.416612) (xy 420.844218 -356.661212) (xy 420.615618 -356.889812)
				(xy 418.355018 -356.889812) (xy 417.974018 -357.270812) (xy 417.974018 -358.032812) (xy 418.126418 -358.185212)
				(xy 418.329618 -358.185212) (xy 418.863018 -357.651812) (xy 421.022018 -357.651812) (xy 421.631618 -357.042212)
				(xy 421.631618 -356.127812) (xy 421.961818 -355.797612) (xy 421.961818 -355.061012) (xy 421.809418 -354.908612)
			)
		)
	)
	(zone
		(layer "In4.Cu")
		(hatch none 0.5)
		(connect_pads
			(clearance 0)
		)
		(min_thickness 0.25)
		(keepout
			(tracks allowed)
			(vias allowed)
			(pads allowed)
			(copperpour allowed)
			(footprints allowed)
		)
		(placement
			(enabled no)
			(sheetname "")
		)
		(fill
			(thermal_gap 0.5)
			(thermal_bridge_width 0.5)
			(island_removal_mode 0)
		)
		(polygon
			(pts
				(xy 25.00503 -347.661992) (xy 25.00503 -348.429072) (xy 24.86025 -348.429072) (xy 24.86025 -347.661992)
			)
		)
	)
	(zone
		(layer "In4.Cu")
		(hatch none 0.5)
		(connect_pads
			(clearance 0)
		)
		(min_thickness 0.25)
		(keepout
			(tracks allowed)
			(vias allowed)
			(pads allowed)
			(copperpour allowed)
			(footprints allowed)
		)
		(placement
			(enabled no)
			(sheetname "")
		)
		(fill
			(thermal_gap 0.5)
			(thermal_bridge_width 0.5)
			(island_removal_mode 0)
		)
		(polygon
			(pts
				(xy 229.533196 -404.925276) (xy 229.533196 -403.191218) (xy 232.60939 -403.191218) (xy 233.82224 -403.191218)
				(xy 233.82224 -404.925276) (xy 232.60939 -404.925276)
			)
		)
	)
	(zone
		(layer "In4.Cu")
		(hatch none 0.5)
		(connect_pads
			(clearance 0)
		)
		(min_thickness 0.25)
		(keepout
			(tracks allowed)
			(vias allowed)
			(pads allowed)
			(copperpour allowed)
			(footprints allowed)
		)
		(placement
			(enabled no)
			(sheetname "")
		)
		(fill
			(thermal_gap 0.5)
			(thermal_bridge_width 0.5)
			(island_removal_mode 0)
		)
		(polygon
			(pts
				(xy 183.48325 -94.125288) (xy 183.48325 -93.356684) (xy 185.152538 -93.356684) (xy 185.152538 -94.125288)
			)
		)
	)
	(zone
		(layer "In4.Cu")
		(hatch none 0.5)
		(connect_pads
			(clearance 0)
		)
		(min_thickness 0.25)
		(keepout
			(tracks allowed)
			(vias allowed)
			(pads allowed)
			(copperpour allowed)
			(footprints allowed)
		)
		(placement
			(enabled no)
			(sheetname "")
		)
		(fill
			(thermal_gap 0.5)
			(thermal_bridge_width 0.5)
			(island_removal_mode 0)
		)
		(polygon
			(pts
				(xy 135.270494 -152.486614) (xy 134.776718 -152.98039) (xy 134.765796 -152.991312) (xy 134.254494 -152.991312)
				(xy 134.051294 -152.788112) (xy 134.051294 -151.949912) (xy 134.328916 -151.67229) (xy 134.328916 -151.57069)
				(xy 133.86689 -151.108664) (xy 128.310386 -151.108664) (xy 125.262386 -154.156664) (xy 104.67975 -154.156664)
				(xy 101.044248 -150.521162) (xy 101.044248 -149.936708) (xy 101.81209 -149.936708) (xy 105.095294 -153.219912)
				(xy 125.008894 -153.219912) (xy 128.056894 -150.171912) (xy 134.229094 -150.171912) (xy 135.270494 -151.213312)
			)
		)
	)
	(zone
		(layer "In4.Cu")
		(hatch none 0.5)
		(connect_pads
			(clearance 0)
		)
		(min_thickness 0.25)
		(keepout
			(tracks allowed)
			(vias allowed)
			(pads allowed)
			(copperpour allowed)
			(footprints allowed)
		)
		(placement
			(enabled no)
			(sheetname "")
		)
		(fill
			(thermal_gap 0.5)
			(thermal_bridge_width 0.5)
			(island_removal_mode 0)
		)
		(polygon
			(pts
				(xy 208.588864 -399.048478) (xy 211.331048 -399.048478) (xy 212.543898 -399.048478) (xy 212.543898 -400.782536)
				(xy 211.331048 -400.782536) (xy 208.254854 -400.782536) (xy 207.244442 -401.792948) (xy 205.93939 -401.792948)
				(xy 205.381606 -401.235164) (xy 205.381606 -399.058638) (xy 205.84414 -398.596104) (xy 208.13649 -398.596104)
			)
		)
	)
	(zone
		(layer "In4.Cu")
		(hatch none 0.5)
		(connect_pads
			(clearance 0)
		)
		(min_thickness 0.25)
		(keepout
			(tracks allowed)
			(vias allowed)
			(pads allowed)
			(copperpour allowed)
			(footprints allowed)
		)
		(placement
			(enabled no)
			(sheetname "")
		)
		(fill
			(thermal_gap 0.5)
			(thermal_bridge_width 0.5)
			(island_removal_mode 0)
		)
		(polygon
			(pts
				(xy 49.94783 -347.661992) (xy 49.94783 -348.429072) (xy 49.80305 -348.429072) (xy 49.80305 -347.661992)
			)
		)
	)
	(zone
		(layer "In4.Cu")
		(hatch none 0.5)
		(connect_pads
			(clearance 0)
		)
		(min_thickness 0.25)
		(keepout
			(tracks allowed)
			(vias allowed)
			(pads allowed)
			(copperpour allowed)
			(footprints allowed)
		)
		(placement
			(enabled no)
			(sheetname "")
		)
		(fill
			(thermal_gap 0.5)
			(thermal_bridge_width 0.5)
			(island_removal_mode 0)
		)
		(polygon
			(pts
				(xy 41.59123 -347.661992) (xy 41.59123 -348.429072) (xy 41.44645 -348.429072) (xy 41.44645 -347.661992)
			)
		)
	)
	(zone
		(layer "In4.Cu")
		(hatch none 0.5)
		(connect_pads
			(clearance 0)
		)
		(min_thickness 0.25)
		(keepout
			(tracks allowed)
			(vias allowed)
			(pads allowed)
			(copperpour allowed)
			(footprints allowed)
		)
		(placement
			(enabled no)
			(sheetname "")
		)
		(fill
			(thermal_gap 0.5)
			(thermal_bridge_width 0.5)
			(island_removal_mode 0)
		)
		(polygon
			(pts
				(xy 93.57487 -338.703412) (xy 93.57487 -339.600032) (xy 93.39199 -339.600032) (xy 93.39199 -338.703412)
			)
		)
	)
	(zone
		(layer "In4.Cu")
		(hatch none 0.5)
		(connect_pads
			(clearance 0)
		)
		(min_thickness 0.25)
		(keepout
			(tracks allowed)
			(vias allowed)
			(pads allowed)
			(copperpour allowed)
			(footprints allowed)
		)
		(placement
			(enabled no)
			(sheetname "")
		)
		(fill
			(thermal_gap 0.5)
			(thermal_bridge_width 0.5)
			(island_removal_mode 0)
		)
		(polygon
			(pts
				(xy 184.110122 -99.601528) (xy 184.110122 -96.98355) (xy 186.848496 -96.98355) (xy 186.848496 -99.601528)
			)
		)
	)
	(zone
		(layer "In4.Cu")
		(hatch none 0.5)
		(connect_pads
			(clearance 0)
		)
		(min_thickness 0.25)
		(keepout
			(tracks allowed)
			(vias allowed)
			(pads allowed)
			(copperpour allowed)
			(footprints allowed)
		)
		(placement
			(enabled no)
			(sheetname "")
		)
		(fill
			(thermal_gap 0.5)
			(thermal_bridge_width 0.5)
			(island_removal_mode 0)
		)
		(polygon
			(pts
				(xy 51.64201 -350.255332) (xy 51.34737 -350.255332) (xy 50.85207 -350.750632) (xy 50.85207 -353.343972)
				(xy 49.46523 -354.730812) (xy 49.46523 -355.810312) (xy 49.61763 -355.962712) (xy 50.25263 -355.962712)
				(xy 50.46853 -355.746812) (xy 50.46853 -354.855272) (xy 51.58359 -353.740212) (xy 51.58359 -351.588832)
				(xy 51.81473 -351.357692) (xy 51.81473 -350.428052)
			)
		)
	)
	(zone
		(layer "In4.Cu")
		(hatch none 0.5)
		(connect_pads
			(clearance 0)
		)
		(min_thickness 0.25)
		(keepout
			(tracks allowed)
			(vias allowed)
			(pads allowed)
			(copperpour allowed)
			(footprints allowed)
		)
		(placement
			(enabled no)
			(sheetname "")
		)
		(fill
			(thermal_gap 0.5)
			(thermal_bridge_width 0.5)
			(island_removal_mode 0)
		)
		(polygon
			(pts
				(xy 178.414934 -95.42526) (xy 178.414934 -94.764606) (xy 180.024278 -94.764606) (xy 180.024278 -95.42526)
			)
		)
	)
	(zone
		(layer "In4.Cu")
		(hatch none 0.5)
		(connect_pads
			(clearance 0)
		)
		(min_thickness 0.25)
		(keepout
			(tracks allowed)
			(vias allowed)
			(pads allowed)
			(copperpour allowed)
			(footprints allowed)
		)
		(placement
			(enabled no)
			(sheetname "")
		)
		(fill
			(thermal_gap 0.5)
			(thermal_bridge_width 0.5)
			(island_removal_mode 0)
		)
		(polygon
			(pts
				(xy 26.72969 -350.268032) (xy 26.22169 -350.268032) (xy 25.82545 -350.664272) (xy 25.82545 -351.543112)
				(xy 30.56255 -356.280212) (xy 30.56255 -361.085892) (xy 36.06419 -366.587532) (xy 46.51629 -366.587532)
				(xy 47.29607 -365.807752) (xy 46.68901 -365.200692) (xy 46.22673 -365.200692) (xy 45.71111 -365.716312)
				(xy 36.39693 -365.716312) (xy 31.35503 -360.674412) (xy 31.35503 -355.899212) (xy 26.95829 -351.502472)
				(xy 26.95829 -350.496632)
			)
		)
	)
	(zone
		(layer "In4.Cu")
		(hatch none 0.5)
		(connect_pads
			(clearance 0)
		)
		(min_thickness 0.25)
		(keepout
			(tracks allowed)
			(vias allowed)
			(pads allowed)
			(copperpour allowed)
			(footprints allowed)
		)
		(placement
			(enabled no)
			(sheetname "")
		)
		(fill
			(thermal_gap 0.5)
			(thermal_bridge_width 0.5)
			(island_removal_mode 0)
		)
		(polygon
			(pts
				(xy 68.55587 -338.754212) (xy 68.55587 -339.600032) (xy 68.32981 -339.600032) (xy 68.32981 -338.754212)
			)
		)
	)
	(zone
		(layer "In4.Cu")
		(hatch none 0.5)
		(connect_pads
			(clearance 0)
		)
		(min_thickness 0.25)
		(keepout
			(tracks allowed)
			(vias allowed)
			(pads allowed)
			(copperpour allowed)
			(footprints allowed)
		)
		(placement
			(enabled no)
			(sheetname "")
		)
		(fill
			(thermal_gap 0.5)
			(thermal_bridge_width 0.5)
			(island_removal_mode 0)
		)
		(polygon
			(pts
				(xy 181.267608 -385.322826) (xy 181.267608 -384.73126) (xy 181.895496 -384.73126) (xy 181.895496 -385.322826)
			)
		)
	)
	(zone
		(layer "In4.Cu")
		(hatch none 0.5)
		(connect_pads
			(clearance 0)
		)
		(min_thickness 0.25)
		(keepout
			(tracks allowed)
			(vias allowed)
			(pads allowed)
			(copperpour allowed)
			(footprints allowed)
		)
		(placement
			(enabled no)
			(sheetname "")
		)
		(fill
			(thermal_gap 0.5)
			(thermal_bridge_width 0.5)
			(island_removal_mode 0)
		)
		(polygon
			(pts
				(xy 385.157218 -144.850612) (xy 381.677418 -144.850612) (xy 381.575818 -144.952212) (xy 381.575818 -145.384012)
				(xy 381.804418 -145.612612) (xy 385.004818 -145.612612) (xy 385.970018 -146.577812) (xy 391.126218 -146.577812)
				(xy 407.839418 -163.291012) (xy 407.839418 -164.764212) (xy 408.093418 -165.018212) (xy 408.245818 -165.018212)
				(xy 408.880818 -164.383212) (xy 408.880818 -163.265612) (xy 391.405618 -145.790412) (xy 386.249418 -145.790412)
				(xy 385.817618 -145.358612) (xy 385.309618 -144.850612)
			)
		)
	)
	(zone
		(layer "In4.Cu")
		(hatch none 0.5)
		(connect_pads
			(clearance 0)
		)
		(min_thickness 0.25)
		(keepout
			(tracks allowed)
			(vias allowed)
			(pads allowed)
			(copperpour allowed)
			(footprints allowed)
		)
		(placement
			(enabled no)
			(sheetname "")
		)
		(fill
			(thermal_gap 0.5)
			(thermal_bridge_width 0.5)
			(island_removal_mode 0)
		)
		(polygon
			(pts
				(xy 229.970076 -399.02765) (xy 232.71226 -399.02765) (xy 233.92511 -399.02765) (xy 233.92511 -400.761708)
				(xy 232.71226 -400.761708) (xy 229.636066 -400.761708) (xy 228.625654 -401.77212) (xy 227.320602 -401.77212)
				(xy 226.762818 -401.214336) (xy 226.762818 -399.03781) (xy 227.225352 -398.575276) (xy 229.517702 -398.575276)
			)
		)
	)
	(zone
		(layer "In4.Cu")
		(hatch none 0.5)
		(connect_pads
			(clearance 0)
		)
		(min_thickness 0.25)
		(keepout
			(tracks allowed)
			(vias allowed)
			(pads allowed)
			(copperpour allowed)
			(footprints allowed)
		)
		(placement
			(enabled no)
			(sheetname "")
		)
		(fill
			(thermal_gap 0.5)
			(thermal_bridge_width 0.5)
			(island_removal_mode 0)
		)
		(polygon
			(pts
				(xy 304.311304 -366.443768) (xy 304.311304 -365.885222) (xy 304.881788 -365.885222) (xy 304.881788 -366.443768)
			)
		)
	)
	(zone
		(layer "In4.Cu")
		(hatch none 0.5)
		(connect_pads
			(clearance 0)
		)
		(min_thickness 0.25)
		(keepout
			(tracks allowed)
			(vias allowed)
			(pads allowed)
			(copperpour allowed)
			(footprints allowed)
		)
		(placement
			(enabled no)
			(sheetname "")
		)
		(fill
			(thermal_gap 0.5)
			(thermal_bridge_width 0.5)
			(island_removal_mode 0)
		)
		(polygon
			(pts
				(xy 176.265332 -99.601782) (xy 176.265332 -96.839532) (xy 179.186078 -96.839532) (xy 179.186078 -99.601782)
			)
		)
	)
	(zone
		(layer "In4.Cu")
		(hatch none 0.5)
		(connect_pads
			(clearance 0)
		)
		(min_thickness 0.25)
		(keepout
			(tracks allowed)
			(vias allowed)
			(pads allowed)
			(copperpour allowed)
			(footprints allowed)
		)
		(placement
			(enabled no)
			(sheetname "")
		)
		(fill
			(thermal_gap 0.5)
			(thermal_bridge_width 0.5)
			(island_removal_mode 0)
		)
		(polygon
			(pts
				(xy 302.161448 -366.381538) (xy 302.161448 -365.8108) (xy 302.756062 -365.8108) (xy 302.756062 -366.381538)
			)
		)
	)
	(zone
		(layer "In4.Cu")
		(hatch none 0.5)
		(connect_pads
			(clearance 0)
		)
		(min_thickness 0.25)
		(keepout
			(tracks allowed)
			(vias allowed)
			(pads allowed)
			(copperpour allowed)
			(footprints allowed)
		)
		(placement
			(enabled no)
			(sheetname "")
		)
		(fill
			(thermal_gap 0.5)
			(thermal_bridge_width 0.5)
			(island_removal_mode 0)
		)
		(polygon
			(pts
				(xy 302.226218 -359.277412) (xy 301.616618 -359.277412) (xy 301.489618 -359.150412) (xy 301.489618 -356.204012)
				(xy 300.168818 -354.883212) (xy 290.999418 -354.883212) (xy 288.256218 -352.140012) (xy 288.256218 -351.022412)
				(xy 288.484818 -350.793812) (xy 288.865818 -350.793812) (xy 288.865818 -351.276412) (xy 289.094418 -351.505012)
				(xy 289.094418 -351.886012) (xy 291.151818 -353.943412) (xy 300.524418 -353.943412) (xy 302.378618 -355.797612)
				(xy 302.378618 -359.125012)
			)
		)
	)
	(zone
		(layer "In4.Cu")
		(hatch none 0.5)
		(connect_pads
			(clearance 0)
		)
		(min_thickness 0.25)
		(keepout
			(tracks allowed)
			(vias allowed)
			(pads allowed)
			(copperpour allowed)
			(footprints allowed)
		)
		(placement
			(enabled no)
			(sheetname "")
		)
		(fill
			(thermal_gap 0.5)
			(thermal_bridge_width 0.5)
			(island_removal_mode 0)
		)
		(polygon
			(pts
				(xy 377.181618 -149.498812) (xy 376.521218 -149.498812) (xy 376.292618 -149.727412) (xy 376.292618 -158.338012)
				(xy 383.125218 -165.170612) (xy 383.125218 -177.896012) (xy 382.769618 -178.251612) (xy 382.769618 -179.013612)
				(xy 382.972818 -179.216812) (xy 383.277618 -179.216812) (xy 383.836418 -178.658012) (xy 383.836418 -164.815012)
				(xy 377.029218 -158.007812) (xy 377.029218 -149.930612) (xy 377.257818 -149.702012) (xy 377.257818 -149.575012)
			)
		)
	)
	(zone
		(layer "In4.Cu")
		(hatch none 0.5)
		(connect_pads
			(clearance 0)
		)
		(min_thickness 0.25)
		(keepout
			(tracks allowed)
			(vias allowed)
			(pads allowed)
			(copperpour allowed)
			(footprints allowed)
		)
		(placement
			(enabled no)
			(sheetname "")
		)
		(fill
			(thermal_gap 0.5)
			(thermal_bridge_width 0.5)
			(island_removal_mode 0)
		)
		(polygon
			(pts
				(xy 218.739974 -405.305514) (xy 218.739974 -403.571456) (xy 221.816168 -403.571456) (xy 223.029018 -403.571456)
				(xy 223.029018 -405.305514) (xy 221.816168 -405.305514)
			)
		)
	)
	(zone
		(layer "In4.Cu")
		(hatch none 0.5)
		(connect_pads
			(clearance 0)
		)
		(min_thickness 0.25)
		(keepout
			(tracks allowed)
			(vias allowed)
			(pads allowed)
			(copperpour allowed)
			(footprints allowed)
		)
		(placement
			(enabled no)
			(sheetname "")
		)
		(fill
			(thermal_gap 0.5)
			(thermal_bridge_width 0.5)
			(island_removal_mode 0)
		)
		(polygon
			(pts
				(xy 219.382086 -399.23339) (xy 222.12427 -399.23339) (xy 223.33712 -399.23339) (xy 223.33712 -400.967448)
				(xy 222.12427 -400.967448) (xy 219.048076 -400.967448) (xy 218.037664 -401.97786) (xy 216.732612 -401.97786)
				(xy 216.174828 -401.420076) (xy 216.174828 -399.24355) (xy 216.637362 -398.781016) (xy 218.929712 -398.781016)
			)
		)
	)
	(zone
		(layer "In4.Cu")
		(hatch none 0.5)
		(connect_pads
			(clearance 0)
		)
		(min_thickness 0.25)
		(keepout
			(tracks allowed)
			(vias allowed)
			(pads allowed)
			(copperpour allowed)
			(footprints allowed)
		)
		(placement
			(enabled no)
			(sheetname "")
		)
		(fill
			(thermal_gap 0.5)
			(thermal_bridge_width 0.5)
			(island_removal_mode 0)
		)
		(polygon
			(pts
				(xy 101.793294 -178.518312) (xy 101.793294 -177.248312) (xy 99.558094 -175.013112) (xy 99.558094 -158.680912)
				(xy 95.341694 -154.464512) (xy 95.341694 -152.711912) (xy 95.214694 -152.584912) (xy 94.605094 -152.584912)
				(xy 94.478094 -152.711912) (xy 94.478094 -152.915112) (xy 94.579694 -153.016712) (xy 94.579694 -154.896312)
				(xy 98.796094 -159.112712) (xy 98.796094 -175.292512) (xy 101.056694 -177.553112) (xy 101.056694 -177.857912)
				(xy 100.777294 -178.137312) (xy 100.777294 -179.000912) (xy 100.929694 -179.153312) (xy 101.158294 -179.153312)
			)
		)
	)
	(zone
		(layer "In4.Cu")
		(hatch none 0.5)
		(connect_pads
			(clearance 0)
		)
		(min_thickness 0.25)
		(keepout
			(tracks allowed)
			(vias allowed)
			(pads allowed)
			(copperpour allowed)
			(footprints allowed)
		)
		(placement
			(enabled no)
			(sheetname "")
		)
		(fill
			(thermal_gap 0.5)
			(thermal_bridge_width 0.5)
			(island_removal_mode 0)
		)
		(polygon
			(pts
				(xy 197.605396 -400.761962) (xy 197.605396 -399.027904) (xy 200.68159 -399.027904) (xy 201.89444 -399.027904)
				(xy 201.89444 -400.761962) (xy 200.68159 -400.761962)
			)
		)
	)
	(zone
		(layer "In4.Cu")
		(hatch none 0.5)
		(connect_pads
			(clearance 0)
		)
		(min_thickness 0.25)
		(keepout
			(tracks allowed)
			(vias allowed)
			(pads allowed)
			(copperpour allowed)
			(footprints allowed)
		)
		(placement
			(enabled no)
			(sheetname "")
		)
		(fill
			(thermal_gap 0.5)
			(thermal_bridge_width 0.5)
			(island_removal_mode 0)
		)
		(polygon
			(pts
				(xy 314.291218 -339.643212) (xy 313.529218 -339.643212) (xy 313.478418 -339.694012) (xy 313.478418 -340.506812)
				(xy 311.700418 -342.284812) (xy 311.700418 -347.441012) (xy 312.792618 -348.533212) (xy 312.792618 -350.920812)
				(xy 308.855618 -354.857812) (xy 308.855618 -359.328212) (xy 308.931818 -359.404412) (xy 309.541418 -359.404412)
				(xy 309.693818 -359.252012) (xy 309.693818 -355.035612) (xy 313.554618 -351.174812) (xy 313.554618 -348.228412)
				(xy 312.437018 -347.110812) (xy 312.437018 -342.767412) (xy 314.316618 -340.887812) (xy 314.316618 -339.668612)
			)
		)
	)
	(zone
		(layer "In4.Cu")
		(hatch none 0.5)
		(connect_pads
			(clearance 0)
		)
		(min_thickness 0.25)
		(keepout
			(tracks allowed)
			(vias allowed)
			(pads allowed)
			(copperpour allowed)
			(footprints allowed)
		)
		(placement
			(enabled no)
			(sheetname "")
		)
		(fill
			(thermal_gap 0.5)
			(thermal_bridge_width 0.5)
			(island_removal_mode 0)
		)
		(polygon
			(pts
				(xy 330.877418 -339.440012) (xy 330.344018 -339.440012) (xy 330.217018 -339.567012) (xy 330.217018 -340.481412)
				(xy 329.632818 -341.065612) (xy 325.340218 -341.065612) (xy 321.504818 -344.901012) (xy 321.504818 -351.454212)
				(xy 311.649618 -361.309412) (xy 311.649618 -362.300012) (xy 311.776618 -362.427012) (xy 312.030618 -362.427012)
				(xy 312.208418 -362.249212) (xy 312.208418 -361.842812) (xy 322.343018 -351.708212) (xy 322.343018 -345.307412)
				(xy 325.721218 -341.929212) (xy 329.912218 -341.929212) (xy 331.029818 -340.811612) (xy 331.029818 -339.592412)
			)
		)
	)
	(zone
		(layer "In4.Cu")
		(hatch none 0.5)
		(connect_pads
			(clearance 0)
		)
		(min_thickness 0.25)
		(keepout
			(tracks not_allowed)
			(vias allowed)
			(pads allowed)
			(copperpour not_allowed)
			(footprints allowed)
		)
		(placement
			(enabled no)
			(sheetname "")
		)
		(fill
			(thermal_gap 0.5)
			(thermal_bridge_width 0.5)
			(island_removal_mode 0)
		)
		(polygon
			(pts
				(arc
					(start 36.354766 -153.76652)
					(mid 23.55469 -153.76652)
					(end 36.354766 -153.76652)
				)
			)
		)
	)
	(zone
		(layer "In4.Cu")
		(hatch none 0.5)
		(connect_pads
			(clearance 0)
		)
		(min_thickness 0.25)
		(keepout
			(tracks allowed)
			(vias allowed)
			(pads allowed)
			(copperpour allowed)
			(footprints allowed)
		)
		(placement
			(enabled no)
			(sheetname "")
		)
		(fill
			(thermal_gap 0.5)
			(thermal_bridge_width 0.5)
			(island_removal_mode 0)
		)
		(polygon
			(pts
				(xy 299.559218 -362.960412) (xy 299.559218 -363.849412) (xy 299.432218 -363.976412) (xy 297.628818 -363.976412)
				(xy 296.206418 -365.398812) (xy 283.354018 -365.398812) (xy 279.772618 -361.817412) (xy 279.772618 -351.124012)
				(xy 280.534618 -350.362012) (xy 280.534618 -351.276412) (xy 280.788618 -351.530412) (xy 280.788618 -361.385612)
				(xy 283.989018 -364.586012) (xy 295.800018 -364.586012) (xy 297.501818 -362.884212) (xy 299.483018 -362.884212)
			)
		)
	)
	(zone
		(layer "In4.Cu")
		(hatch none 0.5)
		(connect_pads
			(clearance 0)
		)
		(min_thickness 0.25)
		(keepout
			(tracks allowed)
			(vias allowed)
			(pads allowed)
			(copperpour allowed)
			(footprints allowed)
		)
		(placement
			(enabled no)
			(sheetname "")
		)
		(fill
			(thermal_gap 0.5)
			(thermal_bridge_width 0.5)
			(island_removal_mode 0)
		)
		(polygon
			(pts
				(xy 375.403618 -147.263612) (xy 374.590818 -147.263612) (xy 373.727218 -148.127212) (xy 373.727218 -173.349412)
				(xy 374.616218 -174.238412) (xy 374.616218 -177.946812) (xy 374.438418 -178.124612) (xy 374.438418 -179.089812)
				(xy 374.565418 -179.216812) (xy 374.819418 -179.216812) (xy 375.479818 -178.556412) (xy 375.479818 -173.933612)
				(xy 374.438418 -172.892212) (xy 374.438418 -148.686012) (xy 375.479818 -147.644612) (xy 375.479818 -147.339812)
			)
		)
	)
	(zone
		(layer "In4.Cu")
		(hatch none 0.5)
		(connect_pads
			(clearance 0)
		)
		(min_thickness 0.25)
		(keepout
			(tracks allowed)
			(vias allowed)
			(pads allowed)
			(copperpour allowed)
			(footprints allowed)
		)
		(placement
			(enabled no)
			(sheetname "")
		)
		(fill
			(thermal_gap 0.5)
			(thermal_bridge_width 0.5)
			(island_removal_mode 0)
		)
		(polygon
			(pts
				(xy 310.532018 -359.201212) (xy 310.405018 -359.074212) (xy 310.405018 -356.559612) (xy 319.752218 -347.212412)
				(xy 319.752218 -343.199212) (xy 321.758818 -341.192612) (xy 321.758818 -339.440012) (xy 322.368418 -338.830412)
				(xy 322.546218 -339.008212) (xy 322.546218 -341.472012) (xy 320.488818 -343.529412) (xy 320.488818 -347.618812)
				(xy 311.395618 -356.712012) (xy 311.395618 -359.099612) (xy 311.395618 -359.480612) (xy 311.319418 -359.556812)
				(xy 310.887618 -359.556812)
			)
		)
	)
	(zone
		(layer "In4.Cu")
		(hatch none 0.5)
		(connect_pads
			(clearance 0)
		)
		(min_thickness 0.25)
		(keepout
			(tracks allowed)
			(vias allowed)
			(pads allowed)
			(copperpour allowed)
			(footprints allowed)
		)
		(placement
			(enabled no)
			(sheetname "")
		)
		(fill
			(thermal_gap 0.5)
			(thermal_bridge_width 0.5)
			(island_removal_mode 0)
		)
		(polygon
			(pts
				(xy 101.89591 -343.676732) (xy 101.89591 -344.502232) (xy 101.62667 -344.502232) (xy 101.62667 -343.676732)
			)
		)
	)
	(zone
		(layer "In4.Cu")
		(hatch none 0.5)
		(connect_pads
			(clearance 0)
		)
		(min_thickness 0.25)
		(keepout
			(tracks allowed)
			(vias allowed)
			(pads allowed)
			(copperpour allowed)
			(footprints allowed)
		)
		(placement
			(enabled no)
			(sheetname "")
		)
		(fill
			(thermal_gap 0.5)
			(thermal_bridge_width 0.5)
			(island_removal_mode 0)
		)
		(polygon
			(pts
				(xy 91.85783 -335.970118) (xy 91.85783 -336.737198) (xy 91.71305 -336.737198) (xy 91.71305 -335.970118)
			)
		)
	)
	(zone
		(layer "In4.Cu")
		(hatch none 0.5)
		(connect_pads
			(clearance 0)
		)
		(min_thickness 0.25)
		(keepout
			(tracks allowed)
			(vias allowed)
			(pads allowed)
			(copperpour allowed)
			(footprints allowed)
		)
		(placement
			(enabled no)
			(sheetname "")
		)
		(fill
			(thermal_gap 0.5)
			(thermal_bridge_width 0.5)
			(island_removal_mode 0)
		)
		(polygon
			(pts
				(xy 208.028286 -405.264366) (xy 208.028286 -403.530308) (xy 211.10448 -403.530308) (xy 212.31733 -403.530308)
				(xy 212.31733 -405.264366) (xy 211.10448 -405.264366)
			)
		)
	)
	(zone
		(layer "In4.Cu")
		(hatch none 0.5)
		(connect_pads
			(clearance 0)
		)
		(min_thickness 0.25)
		(keepout
			(tracks allowed)
			(vias allowed)
			(pads allowed)
			(copperpour allowed)
			(footprints allowed)
		)
		(placement
			(enabled no)
			(sheetname "")
		)
		(fill
			(thermal_gap 0.5)
			(thermal_bridge_width 0.5)
			(island_removal_mode 0)
		)
		(polygon
			(pts
				(xy 308.042818 -359.379012) (xy 307.331618 -359.379012) (xy 307.230018 -359.277412) (xy 307.230018 -355.543612)
				(xy 304.918618 -353.232212) (xy 304.918618 -351.047812) (xy 305.325018 -350.641412) (xy 305.604418 -350.920812)
				(xy 305.604418 -351.327212) (xy 305.782218 -351.505012) (xy 305.782218 -352.927412) (xy 308.068218 -355.213412)
				(xy 308.068218 -359.353612)
			)
		)
	)
	(zone
		(layer "In4.Cu")
		(hatch none 0.5)
		(connect_pads
			(clearance 0)
		)
		(min_thickness 0.25)
		(keepout
			(tracks allowed)
			(vias allowed)
			(pads allowed)
			(copperpour allowed)
			(footprints allowed)
		)
		(placement
			(enabled no)
			(sheetname "")
		)
		(fill
			(thermal_gap 0.5)
			(thermal_bridge_width 0.5)
			(island_removal_mode 0)
		)
		(polygon
			(pts
				(xy 126.228094 -161.525712) (xy 126.685294 -161.068512) (xy 126.685294 -159.773112) (xy 124.729494 -157.817312)
				(xy 107.787694 -157.817312) (xy 101.488494 -151.518112) (xy 100.675694 -151.518112) (xy 100.675694 -151.645112)
				(xy 107.533694 -158.503112) (xy 124.424694 -158.503112) (xy 125.847094 -159.925512) (xy 125.847094 -160.458912)
				(xy 125.745494 -160.560512) (xy 125.745494 -161.424112) (xy 125.847094 -161.525712)
			)
		)
	)
	(zone
		(layer "In4.Cu")
		(hatch none 0.5)
		(connect_pads
			(clearance 0)
		)
		(min_thickness 0.25)
		(keepout
			(tracks allowed)
			(vias allowed)
			(pads allowed)
			(copperpour allowed)
			(footprints allowed)
		)
		(placement
			(enabled no)
			(sheetname "")
		)
		(fill
			(thermal_gap 0.5)
			(thermal_bridge_width 0.5)
			(island_removal_mode 0)
		)
		(polygon
			(pts
				(xy 85.14969 -338.451952) (xy 84.89823 -338.451952) (xy 84.37753 -338.972652) (xy 84.37753 -340.293452)
				(xy 83.32343 -341.347552) (xy 81.73085 -341.347552) (xy 66.47561 -356.602792) (xy 63.12027 -356.602792)
				(xy 62.86119 -356.861872) (xy 62.86119 -357.362252) (xy 63.09233 -357.593392) (xy 63.24473 -357.593392)
				(xy 63.48857 -357.349552) (xy 66.82613 -357.349552) (xy 82.05597 -342.119712) (xy 83.63331 -342.119712)
				(xy 85.19033 -340.562692) (xy 85.19033 -339.787992) (xy 85.40623 -339.572092) (xy 85.40623 -338.708492)
			)
		)
	)
	(zone
		(layer "In4.Cu")
		(hatch none 0.5)
		(connect_pads
			(clearance 0)
		)
		(min_thickness 0.25)
		(keepout
			(tracks allowed)
			(vias allowed)
			(pads allowed)
			(copperpour allowed)
			(footprints allowed)
		)
		(placement
			(enabled no)
			(sheetname "")
		)
		(fill
			(thermal_gap 0.5)
			(thermal_bridge_width 0.5)
			(island_removal_mode 0)
		)
		(polygon
			(pts
				(xy 349.759778 -156.478732) (xy 349.592138 -156.478732) (xy 349.508318 -156.562552) (xy 349.508318 -157.522672)
				(xy 349.818198 -157.522672) (xy 349.863918 -157.476952) (xy 349.863918 -156.582872)
			)
		)
	)
	(zone
		(layer "In4.Cu")
		(hatch none 0.5)
		(connect_pads
			(clearance 0)
		)
		(min_thickness 0.25)
		(keepout
			(tracks allowed)
			(vias allowed)
			(pads allowed)
			(copperpour allowed)
			(footprints allowed)
		)
		(placement
			(enabled no)
			(sheetname "")
		)
		(fill
			(thermal_gap 0.5)
			(thermal_bridge_width 0.5)
			(island_removal_mode 0)
		)
		(polygon
			(pts
				(xy 185.316368 -405.233632) (xy 185.316368 -403.499574) (xy 188.392562 -403.499574) (xy 188.392562 -405.233632)
			)
		)
	)
	(zone
		(layer "In4.Cu")
		(hatch none 0.5)
		(connect_pads
			(clearance 0)
		)
		(min_thickness 0.25)
		(keepout
			(tracks allowed)
			(vias allowed)
			(pads allowed)
			(copperpour allowed)
			(footprints allowed)
		)
		(placement
			(enabled no)
			(sheetname "")
		)
		(fill
			(thermal_gap 0.5)
			(thermal_bridge_width 0.5)
			(island_removal_mode 0)
		)
		(polygon
			(pts
				(xy 100.13569 -340.933532) (xy 100.13569 -341.797132) (xy 99.92995 -341.797132) (xy 99.92995 -340.933532)
			)
		)
	)
	(zone
		(layer "In4.Cu")
		(hatch none 0.5)
		(connect_pads
			(clearance 0)
		)
		(min_thickness 0.25)
		(keepout
			(tracks allowed)
			(vias allowed)
			(pads allowed)
			(copperpour allowed)
			(footprints allowed)
		)
		(placement
			(enabled no)
			(sheetname "")
		)
		(fill
			(thermal_gap 0.5)
			(thermal_bridge_width 0.5)
			(island_removal_mode 0)
		)
		(polygon
			(pts
				(xy 299.762418 -365.221012) (xy 298.594018 -365.221012) (xy 297.298618 -366.516412) (xy 282.236418 -366.516412)
				(xy 273.930618 -358.210612) (xy 273.930618 -352.470212) (xy 272.762218 -351.301812) (xy 272.152618 -351.301812)
				(xy 271.873218 -351.581212) (xy 273.067018 -352.775012) (xy 273.067018 -358.591612) (xy 281.830018 -367.354612)
				(xy 297.552618 -367.354612) (xy 298.695618 -366.211612) (xy 299.838618 -366.211612) (xy 299.838618 -365.297212)
			)
		)
	)
	(zone
		(layer "In4.Cu")
		(hatch none 0.5)
		(connect_pads
			(clearance 0)
		)
		(min_thickness 0.25)
		(keepout
			(tracks allowed)
			(vias allowed)
			(pads allowed)
			(copperpour allowed)
			(footprints allowed)
		)
		(placement
			(enabled no)
			(sheetname "")
		)
		(fill
			(thermal_gap 0.5)
			(thermal_bridge_width 0.5)
			(island_removal_mode 0)
		)
		(polygon
			(pts
				(xy 358.126538 -164.908992) (xy 357.887778 -164.908992) (xy 357.811578 -164.985192) (xy 357.811578 -165.729412)
				(xy 357.920798 -165.838632) (xy 358.085898 -165.838632) (xy 358.164638 -165.759892) (xy 358.164638 -164.947092)
			)
		)
	)
	(zone
		(layer "In4.Cu")
		(hatch none 0.5)
		(connect_pads
			(clearance 0)
		)
		(min_thickness 0.25)
		(keepout
			(tracks allowed)
			(vias allowed)
			(pads allowed)
			(copperpour allowed)
			(footprints allowed)
		)
		(placement
			(enabled no)
			(sheetname "")
		)
		(fill
			(thermal_gap 0.5)
			(thermal_bridge_width 0.5)
			(island_removal_mode 0)
		)
		(polygon
			(pts
				(xy 103.036624 -146.592544) (xy 102.675182 -146.592544) (xy 102.10038 -147.167346) (xy 102.10038 -149.791674)
				(xy 104.210612 -151.901906) (xy 121.689876 -151.901906) (xy 132.381498 -141.210284) (xy 134.859522 -141.210284)
				(xy 136.437624 -142.788386) (xy 136.437624 -147.546568) (xy 138.42873 -149.537674) (xy 138.42873 -155.04541)
				(xy 136.310624 -157.163516) (xy 136.310624 -165.625018) (xy 138.732514 -168.046908) (xy 139.627102 -168.046908)
				(xy 139.943586 -167.730424) (xy 139.943586 -167.125904) (xy 139.689332 -166.87165) (xy 139.17295 -166.87165)
				(xy 139.172696 -166.871904) (xy 139.162536 -166.871904) (xy 137.454386 -165.163754) (xy 137.454386 -157.595062)
				(xy 139.572492 -155.476956) (xy 139.572492 -149.03196) (xy 137.581386 -147.040854) (xy 137.581386 -142.335758)
				(xy 135.24611 -140.000482) (xy 131.902708 -140.000482) (xy 121.145046 -150.758144) (xy 104.65689 -150.758144)
				(xy 103.256842 -149.358096) (xy 103.256842 -147.876768) (xy 103.307642 -147.825968) (xy 103.515922 -147.825968)
				(xy 103.897176 -147.444714) (xy 103.897176 -146.654266) (xy 103.525066 -146.282156) (xy 103.347012 -146.282156)
			)
		)
	)
	(zone
		(layer "In4.Cu")
		(hatch none 0.5)
		(connect_pads
			(clearance 0)
		)
		(min_thickness 0.25)
		(keepout
			(tracks allowed)
			(vias allowed)
			(pads allowed)
			(copperpour allowed)
			(footprints allowed)
		)
		(placement
			(enabled no)
			(sheetname "")
		)
		(fill
			(thermal_gap 0.5)
			(thermal_bridge_width 0.5)
			(island_removal_mode 0)
		)
		(polygon
			(pts
				(xy 168.920922 -113.596166) (xy 168.920922 -112.070896) (xy 170.590464 -112.070896) (xy 170.590464 -113.596166)
			)
		)
	)
	(zone
		(layer "In4.Cu")
		(hatch none 0.5)
		(connect_pads
			(clearance 0)
		)
		(min_thickness 0.25)
		(keepout
			(tracks allowed)
			(vias allowed)
			(pads allowed)
			(copperpour allowed)
			(footprints allowed)
		)
		(placement
			(enabled no)
			(sheetname "")
		)
		(fill
			(thermal_gap 0.5)
			(thermal_bridge_width 0.5)
			(island_removal_mode 0)
		)
		(polygon
			(pts
				(xy 43.25747 -350.262952) (xy 42.96029 -350.262952) (xy 42.48531 -350.737932) (xy 42.48531 -352.236532)
				(xy 44.55033 -354.301552) (xy 46.92015 -354.301552) (xy 47.35449 -354.735892) (xy 47.35449 -355.779832)
				(xy 47.61865 -356.043992) (xy 48.10633 -356.043992) (xy 48.29937 -355.850952) (xy 48.29937 -354.649532)
				(xy 47.18431 -353.534472) (xy 44.84751 -353.534472) (xy 43.37685 -352.063812) (xy 43.37685 -351.352612)
				(xy 43.47591 -351.253552) (xy 43.47591 -350.481392)
			)
		)
	)
	(zone
		(layer "In4.Cu")
		(hatch none 0.5)
		(connect_pads
			(clearance 0)
		)
		(min_thickness 0.25)
		(keepout
			(tracks allowed)
			(vias allowed)
			(pads allowed)
			(copperpour allowed)
			(footprints allowed)
		)
		(placement
			(enabled no)
			(sheetname "")
		)
		(fill
			(thermal_gap 0.5)
			(thermal_bridge_width 0.5)
			(island_removal_mode 0)
		)
		(polygon
			(pts
				(xy 93.919294 -152.381712) (xy 93.436694 -152.381712) (xy 93.208094 -152.610312) (xy 93.208094 -157.537912)
				(xy 96.103694 -160.433512) (xy 96.103694 -172.549312) (xy 92.395294 -176.257712) (xy 92.395294 -179.051712)
				(xy 92.598494 -179.254912) (xy 92.725494 -179.254912) (xy 93.487494 -178.492912) (xy 93.487494 -176.410112)
				(xy 96.891094 -173.006512) (xy 96.891094 -160.103312) (xy 93.970094 -157.182312) (xy 93.970094 -152.432512)
			)
		)
	)
	(zone
		(layer "In4.Cu")
		(hatch none 0.5)
		(connect_pads
			(clearance 0)
		)
		(min_thickness 0.25)
		(keepout
			(tracks allowed)
			(vias allowed)
			(pads allowed)
			(copperpour allowed)
			(footprints allowed)
		)
		(placement
			(enabled no)
			(sheetname "")
		)
		(fill
			(thermal_gap 0.5)
			(thermal_bridge_width 0.5)
			(island_removal_mode 0)
		)
		(polygon
			(pts
				(xy 35.002978 -350.464628) (xy 35.002978 -351.231708) (xy 34.858198 -351.231708) (xy 34.858198 -350.464628)
			)
		)
	)
	(zone
		(layer "In4.Cu")
		(hatch none 0.5)
		(connect_pads
			(clearance 0)
		)
		(min_thickness 0.25)
		(keepout
			(tracks allowed)
			(vias allowed)
			(pads allowed)
			(copperpour allowed)
			(footprints allowed)
		)
		(placement
			(enabled no)
			(sheetname "")
		)
		(fill
			(thermal_gap 0.5)
			(thermal_bridge_width 0.5)
			(island_removal_mode 0)
		)
		(polygon
			(pts
				(xy 179.683156 -400.052794) (xy 179.683156 -398.318736) (xy 182.75935 -398.318736) (xy 182.75935 -400.052794)
			)
		)
	)
	(zone
		(layer "In4.Cu")
		(hatch none 0.5)
		(connect_pads
			(clearance 0)
		)
		(min_thickness 0.25)
		(keepout
			(tracks allowed)
			(vias allowed)
			(pads allowed)
			(copperpour allowed)
			(footprints allowed)
		)
		(placement
			(enabled no)
			(sheetname "")
		)
		(fill
			(thermal_gap 0.5)
			(thermal_bridge_width 0.5)
			(island_removal_mode 0)
		)
		(polygon
			(pts
				(xy 303.877218 -359.099612) (xy 303.166018 -359.099612) (xy 303.089818 -359.023412) (xy 303.089818 -354.908612)
				(xy 301.489618 -353.308412) (xy 297.832018 -353.308412) (xy 296.638218 -352.114612) (xy 296.638218 -350.946212)
				(xy 297.324018 -350.260412) (xy 297.324018 -351.276412) (xy 297.527218 -351.479612) (xy 297.527218 -351.708212)
				(xy 298.238418 -352.419412) (xy 301.870618 -352.419412) (xy 304.055018 -354.603812) (xy 304.055018 -358.921812)
			)
		)
	)
	(zone
		(layer "In4.Cu")
		(hatch none 0.5)
		(connect_pads
			(clearance 0)
		)
		(min_thickness 0.25)
		(keepout
			(tracks allowed)
			(vias allowed)
			(pads allowed)
			(copperpour allowed)
			(footprints allowed)
		)
		(placement
			(enabled no)
			(sheetname "")
		)
		(fill
			(thermal_gap 0.5)
			(thermal_bridge_width 0.5)
			(island_removal_mode 0)
		)
		(polygon
			(pts
				(xy 66.81343 -335.940908) (xy 66.81343 -336.707988) (xy 66.66865 -336.707988) (xy 66.66865 -335.940908)
			)
		)
	)
	(zone
		(layer "In4.Cu")
		(hatch none 0.5)
		(connect_pads
			(clearance 0)
		)
		(min_thickness 0.25)
		(keepout
			(tracks allowed)
			(vias allowed)
			(pads allowed)
			(copperpour allowed)
			(footprints allowed)
		)
		(placement
			(enabled no)
			(sheetname "")
		)
		(fill
			(thermal_gap 0.5)
			(thermal_bridge_width 0.5)
			(island_removal_mode 0)
		)
		(polygon
			(pts
				(xy 197.627494 -368.243612) (xy 196.382894 -368.243612) (xy 195.620894 -367.481612) (xy 187.442094 -367.481612)
				(xy 186.121294 -366.160812) (xy 180.380894 -366.160812) (xy 178.806094 -364.586012) (xy 178.806094 -357.905812)
				(xy 180.711094 -356.000812) (xy 180.711094 -355.162612) (xy 180.406294 -354.857812) (xy 177.815494 -357.448612)
				(xy 177.815494 -365.144812) (xy 179.796694 -367.126012) (xy 185.765694 -367.126012) (xy 187.137294 -368.497612)
				(xy 195.443094 -368.497612) (xy 196.230494 -369.285012) (xy 197.475094 -369.285012) (xy 197.754494 -369.005612)
				(xy 197.754494 -368.370612)
			)
		)
	)
	(zone
		(layer "In4.Cu")
		(hatch none 0.5)
		(connect_pads
			(clearance 0)
		)
		(min_thickness 0.25)
		(keepout
			(tracks allowed)
			(vias allowed)
			(pads allowed)
			(copperpour allowed)
			(footprints allowed)
		)
		(placement
			(enabled no)
			(sheetname "")
		)
		(fill
			(thermal_gap 0.5)
			(thermal_bridge_width 0.5)
			(island_removal_mode 0)
		)
		(polygon
			(pts
				(xy 83.52663 -335.919318) (xy 83.52663 -336.686398) (xy 83.38185 -336.686398) (xy 83.38185 -335.919318)
			)
		)
	)
	(zone
		(layer "In4.Cu")
		(hatch none 0.5)
		(connect_pads
			(clearance 0)
		)
		(min_thickness 0.25)
		(keepout
			(tracks allowed)
			(vias allowed)
			(pads allowed)
			(copperpour allowed)
			(footprints allowed)
		)
		(placement
			(enabled no)
			(sheetname "")
		)
		(fill
			(thermal_gap 0.5)
			(thermal_bridge_width 0.5)
			(island_removal_mode 0)
		)
		(polygon
			(pts
				(xy 384.039618 -146.019012) (xy 383.658618 -146.019012) (xy 383.582418 -146.095212) (xy 383.582418 -146.806412)
				(xy 383.684018 -146.908012) (xy 383.912618 -146.908012) (xy 385.157218 -148.152612) (xy 389.526018 -148.152612)
				(xy 399.305018 -157.931612) (xy 399.305018 -171.774612) (xy 399.686018 -172.155612) (xy 399.686018 -172.435012)
				(xy 399.559018 -172.562012) (xy 399.559018 -173.425612) (xy 399.736818 -173.603412) (xy 399.889218 -173.603412)
				(xy 400.549618 -172.943012) (xy 400.549618 -171.927012) (xy 400.041618 -171.419012) (xy 400.041618 -157.601412)
				(xy 399.609818 -157.169612) (xy 399.533618 -157.169612) (xy 389.703818 -147.339812) (xy 385.360418 -147.339812)
			)
		)
	)
	(zone
		(layer "In4.Cu")
		(hatch none 0.5)
		(connect_pads
			(clearance 0)
		)
		(min_thickness 0.25)
		(keepout
			(tracks allowed)
			(vias allowed)
			(pads allowed)
			(copperpour allowed)
			(footprints allowed)
		)
		(placement
			(enabled no)
			(sheetname "")
		)
		(fill
			(thermal_gap 0.5)
			(thermal_bridge_width 0.5)
			(island_removal_mode 0)
		)
		(polygon
			(pts
				(xy 76.81595 -338.551012) (xy 76.55179 -338.551012) (xy 76.05141 -339.051392) (xy 76.05141 -344.448892)
				(xy 66.49085 -354.009452) (xy 56.37657 -354.009452) (xy 55.51805 -354.867972) (xy 55.51805 -356.069392)
				(xy 55.71617 -356.267512) (xy 56.00573 -356.267512) (xy 56.48071 -355.792532) (xy 56.48071 -355.040692)
				(xy 56.73217 -354.789232) (xy 66.87947 -354.789232) (xy 76.81595 -344.852752) (xy 76.81595 -339.704172)
				(xy 77.03947 -339.480652) (xy 77.03947 -338.774532)
			)
		)
	)
	(zone
		(layer "In4.Cu")
		(hatch none 0.5)
		(connect_pads
			(clearance 0)
		)
		(min_thickness 0.25)
		(keepout
			(tracks allowed)
			(vias allowed)
			(pads allowed)
			(copperpour allowed)
			(footprints allowed)
		)
		(placement
			(enabled no)
			(sheetname "")
		)
		(fill
			(thermal_gap 0.5)
			(thermal_bridge_width 0.5)
			(island_removal_mode 0)
		)
		(polygon
			(pts
				(xy 189.245494 -355.975412) (xy 189.143894 -355.975412) (xy 189.042294 -355.873812) (xy 189.042294 -355.162612)
				(xy 188.940694 -355.061012) (xy 188.839094 -355.061012) (xy 188.483494 -355.416612) (xy 188.483494 -356.077012)
				(xy 188.483494 -365.881412) (xy 189.423294 -366.821212) (xy 197.195694 -366.821212) (xy 198.059294 -366.821212)
				(xy 198.186294 -366.694212) (xy 198.186294 -366.160812) (xy 197.983094 -365.957612) (xy 197.170294 -365.957612)
				(xy 197.157594 -365.970312) (xy 189.689994 -365.970312) (xy 189.245494 -365.525812)
			)
		)
	)
	(zone
		(layer "In4.Cu")
		(hatch none 0.5)
		(connect_pads
			(clearance 0)
		)
		(min_thickness 0.25)
		(keepout
			(tracks allowed)
			(vias allowed)
			(pads allowed)
			(copperpour allowed)
			(footprints allowed)
		)
		(placement
			(enabled no)
			(sheetname "")
		)
		(fill
			(thermal_gap 0.5)
			(thermal_bridge_width 0.5)
			(island_removal_mode 0)
		)
		(polygon
			(pts
				(xy 420.676578 -156.148532) (xy 420.676578 -157.057852) (xy 418.664898 -157.057852) (xy 418.664898 -156.148532)
			)
		)
	)
	(zone
		(layer "In4.Cu")
		(hatch none 0.5)
		(connect_pads
			(clearance 0)
		)
		(min_thickness 0.25)
		(keepout
			(tracks allowed)
			(vias allowed)
			(pads allowed)
			(copperpour allowed)
			(footprints allowed)
		)
		(placement
			(enabled no)
			(sheetname "")
		)
		(fill
			(thermal_gap 0.5)
			(thermal_bridge_width 0.5)
			(island_removal_mode 0)
		)
		(polygon
			(pts
				(xy 33.28543 -347.661992) (xy 33.28543 -348.429072) (xy 33.14065 -348.429072) (xy 33.14065 -347.661992)
			)
		)
	)
	(zone
		(layer "In4.Cu")
		(hatch none 0.5)
		(connect_pads
			(clearance 0)
		)
		(min_thickness 0.25)
		(keepout
			(tracks not_allowed)
			(vias allowed)
			(pads allowed)
			(copperpour not_allowed)
			(footprints allowed)
		)
		(placement
			(enabled no)
			(sheetname "")
		)
		(fill
			(thermal_gap 0.5)
			(thermal_bridge_width 0.5)
			(island_removal_mode 0)
		)
		(polygon
			(pts
				(xy 286.254952 -363.37621) (xy 286.254952 -362.37545) (xy 289.533076 -362.37545) (xy 289.533076 -363.37621)
			)
		)
	)
	(zone
		(layer "In4.Cu")
		(hatch none 0.5)
		(connect_pads
			(clearance 0)
		)
		(min_thickness 0.25)
		(keepout
			(tracks allowed)
			(vias allowed)
			(pads allowed)
			(copperpour allowed)
			(footprints allowed)
		)
		(placement
			(enabled no)
			(sheetname "")
		)
		(fill
			(thermal_gap 0.5)
			(thermal_bridge_width 0.5)
			(island_removal_mode 0)
		)
		(polygon
			(pts
				(xy 174.367698 -97.532952) (xy 174.367698 -96.512126) (xy 175.98898 -96.512126) (xy 175.98898 -97.532952)
			)
		)
	)
	(zone
		(layer "In4.Cu")
		(hatch none 0.5)
		(connect_pads
			(clearance 0)
		)
		(min_thickness 0.25)
		(keepout
			(tracks allowed)
			(vias allowed)
			(pads allowed)
			(copperpour allowed)
			(footprints allowed)
		)
		(placement
			(enabled no)
			(sheetname "")
		)
		(fill
			(thermal_gap 0.5)
			(thermal_bridge_width 0.5)
			(island_removal_mode 0)
		)
		(polygon
			(pts
				(xy 109.311694 -174.606712) (xy 109.159294 -174.454312) (xy 109.159294 -173.641512) (xy 109.489494 -173.311312)
				(xy 109.489494 -173.133512) (xy 108.778294 -172.422312) (xy 104.358694 -172.422312) (xy 101.361494 -169.425112)
				(xy 101.361494 -159.011112) (xy 95.595694 -153.245312) (xy 95.595694 -152.838912) (xy 95.773494 -152.661112)
				(xy 96.230694 -152.661112) (xy 102.072694 -158.503112) (xy 102.072694 -169.044112) (xy 104.714294 -171.685712)
				(xy 109.210094 -171.685712) (xy 110.226094 -172.701712) (xy 110.226094 -173.997112) (xy 109.616494 -174.606712)
			)
		)
	)
	(zone
		(layer "In4.Cu")
		(hatch none 0.5)
		(connect_pads
			(clearance 0)
		)
		(min_thickness 0.25)
		(keepout
			(tracks allowed)
			(vias allowed)
			(pads allowed)
			(copperpour allowed)
			(footprints allowed)
		)
		(placement
			(enabled no)
			(sheetname "")
		)
		(fill
			(thermal_gap 0.5)
			(thermal_bridge_width 0.5)
			(island_removal_mode 0)
		)
		(polygon
			(pts
				(xy 167.91813 -116.508784) (xy 167.91813 -114.040666) (xy 170.608498 -114.040666) (xy 170.608498 -116.508784)
			)
		)
	)
	(zone
		(layer "In4.Cu")
		(hatch none 0.5)
		(connect_pads
			(clearance 0)
		)
		(min_thickness 0.25)
		(keepout
			(tracks not_allowed)
			(vias allowed)
			(pads allowed)
			(copperpour not_allowed)
			(footprints allowed)
		)
		(placement
			(enabled no)
			(sheetname "")
		)
		(fill
			(thermal_gap 0.5)
			(thermal_bridge_width 0.5)
			(island_removal_mode 0)
		)
		(polygon
			(pts
				(arc
					(start 448.29476 -153.77541)
					(mid 435.494684 -153.77541)
					(end 448.29476 -153.77541)
				)
			)
		)
	)
	(zone
		(layers "In4.Cu" "In6.Cu" "In11.Cu")
		(hatch none 0.5)
		(connect_pads
			(clearance 0)
		)
		(min_thickness 0.25)
		(keepout
			(tracks not_allowed)
			(vias allowed)
			(pads allowed)
			(copperpour not_allowed)
			(footprints allowed)
		)
		(placement
			(enabled no)
			(sheetname "")
		)
		(fill yes
			(thermal_gap 0.5)
			(thermal_bridge_width 0.5)
			(island_removal_mode 0)
		)
		(polygon
			(pts
				(arc
					(start 432.77536 -364.327948)
					(mid 431.25136 -364.327948)
					(end 432.77536 -364.327948)
				)
			)
		)
	)
	(zone
		(layers "In4.Cu" "In11.Cu" "In13.Cu" "In15.Cu")
		(hatch none 0.5)
		(connect_pads
			(clearance 0)
		)
		(min_thickness 0.25)
		(keepout
			(tracks not_allowed)
			(vias allowed)
			(pads allowed)
			(copperpour not_allowed)
			(footprints allowed)
		)
		(placement
			(enabled no)
			(sheetname "")
		)
		(fill yes
			(thermal_gap 0.5)
			(thermal_bridge_width 0.5)
			(island_removal_mode 0)
		)
		(polygon
			(pts
				(arc
					(start 192.44183 -364.93069)
					(mid 190.91783 -364.93069)
					(end 192.44183 -364.93069)
				)
			)
		)
	)
	(zone
		(layer "In5.Cu")
		(hatch none 0.5)
		(connect_pads
			(clearance 0)
		)
		(min_thickness 0.25)
		(keepout
			(tracks not_allowed)
			(vias allowed)
			(pads allowed)
			(copperpour not_allowed)
			(footprints allowed)
		)
		(placement
			(enabled no)
			(sheetname "")
		)
		(fill
			(thermal_gap 0.5)
			(thermal_bridge_width 0.5)
			(island_removal_mode 0)
		)
		(polygon
			(pts
				(arc
					(start 333.141828 -428.960534)
					(mid 333.164146 -429.014416)
					(end 333.218028 -429.036734)
				)
				(arc
					(start 334.157828 -429.036734)
					(mid 334.21171 -429.014416)
					(end 334.234028 -428.960534)
				)
				(arc
					(start 334.234028 -426.41901)
					(mid 334.21171 -426.365128)
					(end 334.157828 -426.34281)
				)
				(arc
					(start 333.218028 -426.34281)
					(mid 333.164146 -426.365128)
					(end 333.141828 -426.41901)
				)
				(arc
					(start 333.141828 -427.146466)
					(mid 333.143827 -427.163807)
					(end 333.149702 -427.180248)
				)
				(arc
					(start 333.383128 -427.656498)
					(mid 333.390911 -427.690026)
					(end 333.383128 -427.723554)
				)
				(arc
					(start 333.149702 -428.199804)
					(mid 333.143807 -428.21624)
					(end 333.141828 -428.233586)
				)
			)
		)
	)
	(zone
		(layer "In5.Cu")
		(hatch none 0.5)
		(connect_pads
			(clearance 0)
		)
		(min_thickness 0.25)
		(keepout
			(tracks not_allowed)
			(vias allowed)
			(pads allowed)
			(copperpour not_allowed)
			(footprints allowed)
		)
		(placement
			(enabled no)
			(sheetname "")
		)
		(fill
			(thermal_gap 0.5)
			(thermal_bridge_width 0.5)
			(island_removal_mode 0)
		)
		(polygon
			(pts
				(arc
					(start 387.24205 -428.960534)
					(mid 387.264368 -429.014416)
					(end 387.31825 -429.036734)
				)
				(arc
					(start 388.25805 -429.036734)
					(mid 388.311932 -429.014416)
					(end 388.33425 -428.960534)
				)
				(arc
					(start 388.33425 -426.41901)
					(mid 388.311932 -426.365128)
					(end 388.25805 -426.34281)
				)
				(arc
					(start 387.31825 -426.34281)
					(mid 387.264368 -426.365128)
					(end 387.24205 -426.41901)
				)
				(arc
					(start 387.24205 -427.146466)
					(mid 387.244049 -427.163807)
					(end 387.249924 -427.180248)
				)
				(arc
					(start 387.48335 -427.656498)
					(mid 387.491133 -427.690026)
					(end 387.48335 -427.723554)
				)
				(arc
					(start 387.249924 -428.199804)
					(mid 387.244029 -428.21624)
					(end 387.24205 -428.233586)
				)
			)
		)
	)
	(zone
		(layer "In5.Cu")
		(hatch none 0.5)
		(connect_pads
			(clearance 0)
		)
		(min_thickness 0.25)
		(keepout
			(tracks not_allowed)
			(vias allowed)
			(pads allowed)
			(copperpour not_allowed)
			(footprints allowed)
		)
		(placement
			(enabled no)
			(sheetname "")
		)
		(fill
			(thermal_gap 0.5)
			(thermal_bridge_width 0.5)
			(island_removal_mode 0)
		)
		(polygon
			(pts
				(arc
					(start 400.242024 -439.760614)
					(mid 400.264342 -439.814496)
					(end 400.318224 -439.836814)
				)
				(arc
					(start 401.258024 -439.836814)
					(mid 401.311906 -439.814496)
					(end 401.334224 -439.760614)
				)
				(arc
					(start 401.334224 -437.21909)
					(mid 401.311906 -437.165208)
					(end 401.258024 -437.14289)
				)
				(arc
					(start 400.318224 -437.14289)
					(mid 400.264342 -437.165208)
					(end 400.242024 -437.21909)
				)
			)
		)
	)
	(zone
		(layer "In5.Cu")
		(hatch none 0.5)
		(connect_pads
			(clearance 0)
		)
		(min_thickness 0.25)
		(keepout
			(tracks not_allowed)
			(vias allowed)
			(pads allowed)
			(copperpour not_allowed)
			(footprints allowed)
		)
		(placement
			(enabled no)
			(sheetname "")
		)
		(fill
			(thermal_gap 0.5)
			(thermal_bridge_width 0.5)
			(island_removal_mode 0)
		)
		(polygon
			(pts
				(arc
					(start 381.242062 -438.760616)
					(mid 381.26438 -438.814498)
					(end 381.318262 -438.836816)
				)
				(arc
					(start 382.258062 -438.836816)
					(mid 382.311944 -438.814498)
					(end 382.334262 -438.760616)
				)
				(arc
					(start 382.334262 -436.219092)
					(mid 382.311944 -436.16521)
					(end 382.258062 -436.142892)
				)
				(arc
					(start 381.318262 -436.142892)
					(mid 381.26438 -436.16521)
					(end 381.242062 -436.219092)
				)
			)
		)
	)
	(zone
		(layer "In5.Cu")
		(hatch none 0.5)
		(connect_pads
			(clearance 0)
		)
		(min_thickness 0.25)
		(keepout
			(tracks not_allowed)
			(vias allowed)
			(pads allowed)
			(copperpour not_allowed)
			(footprints allowed)
		)
		(placement
			(enabled no)
			(sheetname "")
		)
		(fill
			(thermal_gap 0.5)
			(thermal_bridge_width 0.5)
			(island_removal_mode 0)
		)
		(polygon
			(pts
				(arc
					(start 398.242282 -431.560732)
					(mid 398.2646 -431.614614)
					(end 398.318482 -431.636932)
				)
				(arc
					(start 399.258282 -431.636932)
					(mid 399.312164 -431.614614)
					(end 399.334482 -431.560732)
				)
				(arc
					(start 399.334482 -429.019208)
					(mid 399.312164 -428.965326)
					(end 399.258282 -428.943008)
				)
				(arc
					(start 398.318482 -428.943008)
					(mid 398.2646 -428.965326)
					(end 398.242282 -429.019208)
				)
			)
		)
	)
	(zone
		(layer "In5.Cu")
		(hatch none 0.5)
		(connect_pads
			(clearance 0)
		)
		(min_thickness 0.25)
		(keepout
			(tracks not_allowed)
			(vias allowed)
			(pads allowed)
			(copperpour not_allowed)
			(footprints allowed)
		)
		(placement
			(enabled no)
			(sheetname "")
		)
		(fill
			(thermal_gap 0.5)
			(thermal_bridge_width 0.5)
			(island_removal_mode 0)
		)
		(polygon
			(pts
				(arc
					(start 412.242254 -432.56073)
					(mid 412.264572 -432.614612)
					(end 412.318454 -432.63693)
				)
				(arc
					(start 413.258254 -432.63693)
					(mid 413.312136 -432.614612)
					(end 413.334454 -432.56073)
				)
				(arc
					(start 413.334454 -430.019206)
					(mid 413.312136 -429.965324)
					(end 413.258254 -429.943006)
				)
				(arc
					(start 412.318454 -429.943006)
					(mid 412.264572 -429.965324)
					(end 412.242254 -430.019206)
				)
			)
		)
	)
	(zone
		(layer "In5.Cu")
		(hatch none 0.5)
		(connect_pads
			(clearance 0)
		)
		(min_thickness 0.25)
		(keepout
			(tracks not_allowed)
			(vias allowed)
			(pads allowed)
			(copperpour not_allowed)
			(footprints allowed)
		)
		(placement
			(enabled no)
			(sheetname "")
		)
		(fill
			(thermal_gap 0.5)
			(thermal_bridge_width 0.5)
			(island_removal_mode 0)
		)
		(polygon
			(pts
				(arc
					(start 383.242058 -439.760614)
					(mid 383.264376 -439.814496)
					(end 383.318258 -439.836814)
				)
				(arc
					(start 384.258058 -439.836814)
					(mid 384.31194 -439.814496)
					(end 384.334258 -439.760614)
				)
				(arc
					(start 384.334258 -437.21909)
					(mid 384.31194 -437.165208)
					(end 384.258058 -437.14289)
				)
				(arc
					(start 383.318258 -437.14289)
					(mid 383.264376 -437.165208)
					(end 383.242058 -437.21909)
				)
			)
		)
	)
	(zone
		(layer "In5.Cu")
		(hatch none 0.5)
		(connect_pads
			(clearance 0)
		)
		(min_thickness 0.25)
		(keepout
			(tracks not_allowed)
			(vias allowed)
			(pads allowed)
			(copperpour not_allowed)
			(footprints allowed)
		)
		(placement
			(enabled no)
			(sheetname "")
		)
		(fill
			(thermal_gap 0.5)
			(thermal_bridge_width 0.5)
			(island_removal_mode 0)
		)
		(polygon
			(pts
				(arc
					(start 400.242278 -432.56073)
					(mid 400.264596 -432.614612)
					(end 400.318478 -432.63693)
				)
				(arc
					(start 401.258278 -432.63693)
					(mid 401.31216 -432.614612)
					(end 401.334478 -432.56073)
				)
				(arc
					(start 401.334478 -430.019206)
					(mid 401.31216 -429.965324)
					(end 401.258278 -429.943006)
				)
				(arc
					(start 400.318478 -429.943006)
					(mid 400.264596 -429.965324)
					(end 400.242278 -430.019206)
				)
			)
		)
	)
	(zone
		(layer "In5.Cu")
		(hatch none 0.5)
		(connect_pads
			(clearance 0)
		)
		(min_thickness 0.25)
		(keepout
			(tracks not_allowed)
			(vias allowed)
			(pads allowed)
			(copperpour not_allowed)
			(footprints allowed)
		)
		(placement
			(enabled no)
			(sheetname "")
		)
		(fill
			(thermal_gap 0.5)
			(thermal_bridge_width 0.5)
			(island_removal_mode 0)
		)
		(polygon
			(pts
				(arc
					(start 387.24205 -439.760614)
					(mid 387.264368 -439.814496)
					(end 387.31825 -439.836814)
				)
				(arc
					(start 388.25805 -439.836814)
					(mid 388.311932 -439.814496)
					(end 388.33425 -439.760614)
				)
				(arc
					(start 388.33425 -437.21909)
					(mid 388.311932 -437.165208)
					(end 388.25805 -437.14289)
				)
				(arc
					(start 387.31825 -437.14289)
					(mid 387.264368 -437.165208)
					(end 387.24205 -437.21909)
				)
			)
		)
	)
	(zone
		(layer "In5.Cu")
		(hatch none 0.5)
		(connect_pads
			(clearance 0)
		)
		(min_thickness 0.25)
		(keepout
			(tracks not_allowed)
			(vias allowed)
			(pads allowed)
			(copperpour not_allowed)
			(footprints allowed)
		)
		(placement
			(enabled no)
			(sheetname "")
		)
		(fill
			(thermal_gap 0.5)
			(thermal_bridge_width 0.5)
			(island_removal_mode 0)
		)
		(polygon
			(pts
				(arc
					(start 381.242062 -431.560732)
					(mid 381.26438 -431.614614)
					(end 381.318262 -431.636932)
				)
				(arc
					(start 382.258062 -431.636932)
					(mid 382.311944 -431.614614)
					(end 382.334262 -431.560732)
				)
				(arc
					(start 382.334262 -429.019208)
					(mid 382.311944 -428.965326)
					(end 382.258062 -428.943008)
				)
				(arc
					(start 381.318262 -428.943008)
					(mid 381.26438 -428.965326)
					(end 381.242062 -429.019208)
				)
			)
		)
	)
	(zone
		(layer "In5.Cu")
		(hatch none 0.5)
		(connect_pads
			(clearance 0)
		)
		(min_thickness 0.25)
		(keepout
			(tracks not_allowed)
			(vias allowed)
			(pads allowed)
			(copperpour not_allowed)
			(footprints allowed)
		)
		(placement
			(enabled no)
			(sheetname "")
		)
		(fill
			(thermal_gap 0.5)
			(thermal_bridge_width 0.5)
			(island_removal_mode 0)
		)
		(polygon
			(pts
				(arc
					(start 316.141862 -428.960534)
					(mid 316.16418 -429.014416)
					(end 316.218062 -429.036734)
				)
				(arc
					(start 317.157862 -429.036734)
					(mid 317.211744 -429.014416)
					(end 317.234062 -428.960534)
				)
				(arc
					(start 317.234062 -426.41901)
					(mid 317.211744 -426.365128)
					(end 317.157862 -426.34281)
				)
				(arc
					(start 316.218062 -426.34281)
					(mid 316.16418 -426.365128)
					(end 316.141862 -426.41901)
				)
				(arc
					(start 316.141862 -427.146466)
					(mid 316.143861 -427.163807)
					(end 316.149736 -427.180248)
				)
				(arc
					(start 316.383162 -427.656498)
					(mid 316.390945 -427.690026)
					(end 316.383162 -427.723554)
				)
				(arc
					(start 316.149736 -428.199804)
					(mid 316.143841 -428.21624)
					(end 316.141862 -428.233586)
				)
			)
		)
	)
	(zone
		(layer "In5.Cu")
		(hatch none 0.5)
		(connect_pads
			(clearance 0)
		)
		(min_thickness 0.25)
		(keepout
			(tracks not_allowed)
			(vias allowed)
			(pads allowed)
			(copperpour not_allowed)
			(footprints allowed)
		)
		(placement
			(enabled no)
			(sheetname "")
		)
		(fill
			(thermal_gap 0.5)
			(thermal_bridge_width 0.5)
			(island_removal_mode 0)
		)
		(polygon
			(pts
				(arc
					(start 333.142082 -432.56073)
					(mid 333.1644 -432.614612)
					(end 333.218282 -432.63693)
				)
				(arc
					(start 334.158082 -432.63693)
					(mid 334.211964 -432.614612)
					(end 334.234282 -432.56073)
				)
				(arc
					(start 334.234282 -430.019206)
					(mid 334.211964 -429.965324)
					(end 334.158082 -429.943006)
				)
				(arc
					(start 333.218282 -429.943006)
					(mid 333.1644 -429.965324)
					(end 333.142082 -430.019206)
				)
			)
		)
	)
	(zone
		(layer "In5.Cu")
		(hatch none 0.5)
		(connect_pads
			(clearance 0)
		)
		(min_thickness 0.25)
		(keepout
			(tracks not_allowed)
			(vias allowed)
			(pads allowed)
			(copperpour not_allowed)
			(footprints allowed)
		)
		(placement
			(enabled no)
			(sheetname "")
		)
		(fill
			(thermal_gap 0.5)
			(thermal_bridge_width 0.5)
			(island_removal_mode 0)
		)
		(polygon
			(pts
				(arc
					(start 400.242024 -428.960534)
					(mid 400.264342 -429.014416)
					(end 400.318224 -429.036734)
				)
				(arc
					(start 401.258024 -429.036734)
					(mid 401.311906 -429.014416)
					(end 401.334224 -428.960534)
				)
				(arc
					(start 401.334224 -426.41901)
					(mid 401.311906 -426.365128)
					(end 401.258024 -426.34281)
				)
				(arc
					(start 400.318224 -426.34281)
					(mid 400.264342 -426.365128)
					(end 400.242024 -426.41901)
				)
				(arc
					(start 400.242024 -427.146466)
					(mid 400.244023 -427.163807)
					(end 400.249898 -427.180248)
				)
				(arc
					(start 400.483324 -427.656498)
					(mid 400.491107 -427.690026)
					(end 400.483324 -427.723554)
				)
				(arc
					(start 400.249898 -428.199804)
					(mid 400.244003 -428.21624)
					(end 400.242024 -428.233586)
				)
			)
		)
	)
	(zone
		(layer "In5.Cu")
		(hatch none 0.5)
		(connect_pads
			(clearance 0)
		)
		(min_thickness 0.25)
		(keepout
			(tracks not_allowed)
			(vias allowed)
			(pads allowed)
			(copperpour not_allowed)
			(footprints allowed)
		)
		(placement
			(enabled no)
			(sheetname "")
		)
		(fill
			(thermal_gap 0.5)
			(thermal_bridge_width 0.5)
			(island_removal_mode 0)
		)
		(polygon
			(pts
				(arc
					(start 389.242046 -427.960536)
					(mid 389.264364 -428.014418)
					(end 389.318246 -428.036736)
				)
				(arc
					(start 390.258046 -428.036736)
					(mid 390.311928 -428.014418)
					(end 390.334246 -427.960536)
				)
				(arc
					(start 390.334246 -425.419012)
					(mid 390.311928 -425.36513)
					(end 390.258046 -425.342812)
				)
				(arc
					(start 389.318246 -425.342812)
					(mid 389.264364 -425.36513)
					(end 389.242046 -425.419012)
				)
				(arc
					(start 389.242046 -426.146468)
					(mid 389.244045 -426.163809)
					(end 389.24992 -426.18025)
				)
				(arc
					(start 389.483346 -426.6565)
					(mid 389.491129 -426.690028)
					(end 389.483346 -426.723556)
				)
				(arc
					(start 389.24992 -427.199806)
					(mid 389.244025 -427.216242)
					(end 389.242046 -427.233588)
				)
			)
		)
	)
	(zone
		(layer "In5.Cu")
		(hatch none 0.5)
		(connect_pads
			(clearance 0)
		)
		(min_thickness 0.25)
		(keepout
			(tracks not_allowed)
			(vias allowed)
			(pads allowed)
			(copperpour not_allowed)
			(footprints allowed)
		)
		(placement
			(enabled no)
			(sheetname "")
		)
		(fill
			(thermal_gap 0.5)
			(thermal_bridge_width 0.5)
			(island_removal_mode 0)
		)
		(polygon
			(pts
				(arc
					(start 410.242004 -435.160674)
					(mid 410.264322 -435.214556)
					(end 410.318204 -435.236874)
				)
				(arc
					(start 411.258004 -435.236874)
					(mid 411.311886 -435.214556)
					(end 411.334204 -435.160674)
				)
				(arc
					(start 411.334204 -432.61915)
					(mid 411.311886 -432.565268)
					(end 411.258004 -432.54295)
				)
				(arc
					(start 410.318204 -432.54295)
					(mid 410.264322 -432.565268)
					(end 410.242004 -432.61915)
				)
			)
		)
	)
	(zone
		(layer "In5.Cu")
		(hatch none 0.5)
		(connect_pads
			(clearance 0)
		)
		(min_thickness 0.25)
		(keepout
			(tracks not_allowed)
			(vias allowed)
			(pads allowed)
			(copperpour not_allowed)
			(footprints allowed)
		)
		(placement
			(enabled no)
			(sheetname "")
		)
		(fill
			(thermal_gap 0.5)
			(thermal_bridge_width 0.5)
			(island_removal_mode 0)
		)
		(polygon
			(pts
				(arc
					(start 391.242042 -439.760614)
					(mid 391.26436 -439.814496)
					(end 391.318242 -439.836814)
				)
				(arc
					(start 392.258042 -439.836814)
					(mid 392.311924 -439.814496)
					(end 392.334242 -439.760614)
				)
				(arc
					(start 392.334242 -437.21909)
					(mid 392.311924 -437.165208)
					(end 392.258042 -437.14289)
				)
				(arc
					(start 391.318242 -437.14289)
					(mid 391.26436 -437.165208)
					(end 391.242042 -437.21909)
				)
			)
		)
	)
	(zone
		(layer "In5.Cu")
		(hatch none 0.5)
		(connect_pads
			(clearance 0)
		)
		(min_thickness 0.25)
		(keepout
			(tracks not_allowed)
			(vias allowed)
			(pads allowed)
			(copperpour not_allowed)
			(footprints allowed)
		)
		(placement
			(enabled no)
			(sheetname "")
		)
		(fill
			(thermal_gap 0.5)
			(thermal_bridge_width 0.5)
			(island_removal_mode 0)
		)
		(polygon
			(pts
				(xy 230.70947 -402.70938) (xy 230.70947 -401.11934) (xy 232.375202 -401.11934) (xy 232.375202 -402.70938)
			)
		)
	)
	(zone
		(layer "In5.Cu")
		(hatch none 0.5)
		(connect_pads
			(clearance 0)
		)
		(min_thickness 0.25)
		(keepout
			(tracks not_allowed)
			(vias allowed)
			(pads allowed)
			(copperpour not_allowed)
			(footprints allowed)
		)
		(placement
			(enabled no)
			(sheetname "")
		)
		(fill
			(thermal_gap 0.5)
			(thermal_bridge_width 0.5)
			(island_removal_mode 0)
		)
		(polygon
			(pts
				(arc
					(start 320.141854 -428.960534)
					(mid 320.164172 -429.014416)
					(end 320.218054 -429.036734)
				)
				(arc
					(start 321.157854 -429.036734)
					(mid 321.211736 -429.014416)
					(end 321.234054 -428.960534)
				)
				(arc
					(start 321.234054 -426.41901)
					(mid 321.211736 -426.365128)
					(end 321.157854 -426.34281)
				)
				(arc
					(start 320.218054 -426.34281)
					(mid 320.164172 -426.365128)
					(end 320.141854 -426.41901)
				)
				(arc
					(start 320.141854 -427.146466)
					(mid 320.143853 -427.163807)
					(end 320.149728 -427.180248)
				)
				(arc
					(start 320.383154 -427.656498)
					(mid 320.390937 -427.690026)
					(end 320.383154 -427.723554)
				)
				(arc
					(start 320.149728 -428.199804)
					(mid 320.143833 -428.21624)
					(end 320.141854 -428.233586)
				)
			)
		)
	)
	(zone
		(layer "In5.Cu")
		(hatch none 0.5)
		(connect_pads
			(clearance 0)
		)
		(min_thickness 0.25)
		(keepout
			(tracks not_allowed)
			(vias allowed)
			(pads allowed)
			(copperpour not_allowed)
			(footprints allowed)
		)
		(placement
			(enabled no)
			(sheetname "")
		)
		(fill
			(thermal_gap 0.5)
			(thermal_bridge_width 0.5)
			(island_removal_mode 0)
		)
		(polygon
			(pts
				(xy 209.357976 -402.746972) (xy 209.357976 -401.09394) (xy 211.036408 -401.09394) (xy 211.036408 -402.746972)
			)
		)
	)
	(zone
		(layer "In5.Cu")
		(hatch none 0.5)
		(connect_pads
			(clearance 0)
		)
		(min_thickness 0.25)
		(keepout
			(tracks not_allowed)
			(vias allowed)
			(pads allowed)
			(copperpour not_allowed)
			(footprints allowed)
		)
		(placement
			(enabled no)
			(sheetname "")
		)
		(fill
			(thermal_gap 0.5)
			(thermal_bridge_width 0.5)
			(island_removal_mode 0)
		)
		(polygon
			(pts
				(arc
					(start 328.141838 -428.960534)
					(mid 328.164156 -429.014416)
					(end 328.218038 -429.036734)
				)
				(arc
					(start 329.157838 -429.036734)
					(mid 329.21172 -429.014416)
					(end 329.234038 -428.960534)
				)
				(arc
					(start 329.234038 -426.41901)
					(mid 329.21172 -426.365128)
					(end 329.157838 -426.34281)
				)
				(arc
					(start 328.218038 -426.34281)
					(mid 328.164156 -426.365128)
					(end 328.141838 -426.41901)
				)
				(arc
					(start 328.141838 -427.146466)
					(mid 328.143837 -427.163807)
					(end 328.149712 -427.180248)
				)
				(arc
					(start 328.383138 -427.656498)
					(mid 328.390921 -427.690026)
					(end 328.383138 -427.723554)
				)
				(arc
					(start 328.149712 -428.199804)
					(mid 328.143817 -428.21624)
					(end 328.141838 -428.233586)
				)
			)
		)
	)
	(zone
		(layer "In5.Cu")
		(hatch none 0.5)
		(connect_pads
			(clearance 0)
		)
		(min_thickness 0.25)
		(keepout
			(tracks not_allowed)
			(vias allowed)
			(pads allowed)
			(copperpour not_allowed)
			(footprints allowed)
		)
		(placement
			(enabled no)
			(sheetname "")
		)
		(fill
			(thermal_gap 0.5)
			(thermal_bridge_width 0.5)
			(island_removal_mode 0)
		)
		(polygon
			(pts
				(arc
					(start 383.242058 -428.960534)
					(mid 383.264376 -429.014416)
					(end 383.318258 -429.036734)
				)
				(arc
					(start 384.258058 -429.036734)
					(mid 384.31194 -429.014416)
					(end 384.334258 -428.960534)
				)
				(arc
					(start 384.334258 -426.41901)
					(mid 384.31194 -426.365128)
					(end 384.258058 -426.34281)
				)
				(arc
					(start 383.318258 -426.34281)
					(mid 383.264376 -426.365128)
					(end 383.242058 -426.41901)
				)
				(arc
					(start 383.242058 -427.146466)
					(mid 383.244057 -427.163807)
					(end 383.249932 -427.180248)
				)
				(arc
					(start 383.483358 -427.656498)
					(mid 383.491141 -427.690026)
					(end 383.483358 -427.723554)
				)
				(arc
					(start 383.249932 -428.199804)
					(mid 383.244037 -428.21624)
					(end 383.242058 -428.233586)
				)
			)
		)
	)
	(zone
		(layer "In5.Cu")
		(hatch none 0.5)
		(connect_pads
			(clearance 0)
		)
		(min_thickness 0.25)
		(keepout
			(tracks not_allowed)
			(vias allowed)
			(pads allowed)
			(copperpour not_allowed)
			(footprints allowed)
		)
		(placement
			(enabled no)
			(sheetname "")
		)
		(fill
			(thermal_gap 0.5)
			(thermal_bridge_width 0.5)
			(island_removal_mode 0)
		)
		(polygon
			(pts
				(arc
					(start 395.242034 -436.160672)
					(mid 395.264352 -436.214554)
					(end 395.318234 -436.236872)
				)
				(arc
					(start 396.258034 -436.236872)
					(mid 396.311916 -436.214554)
					(end 396.334234 -436.160672)
				)
				(arc
					(start 396.334234 -433.619148)
					(mid 396.311916 -433.565266)
					(end 396.258034 -433.542948)
				)
				(arc
					(start 395.318234 -433.542948)
					(mid 395.264352 -433.565266)
					(end 395.242034 -433.619148)
				)
			)
		)
	)
	(zone
		(layer "In5.Cu")
		(hatch none 0.5)
		(connect_pads
			(clearance 0)
		)
		(min_thickness 0.25)
		(keepout
			(tracks not_allowed)
			(vias allowed)
			(pads allowed)
			(copperpour not_allowed)
			(footprints allowed)
		)
		(placement
			(enabled no)
			(sheetname "")
		)
		(fill
			(thermal_gap 0.5)
			(thermal_bridge_width 0.5)
			(island_removal_mode 0)
		)
		(polygon
			(pts
				(arc
					(start 412.242 -439.760614)
					(mid 412.264318 -439.814496)
					(end 412.3182 -439.836814)
				)
				(arc
					(start 413.258 -439.836814)
					(mid 413.311882 -439.814496)
					(end 413.3342 -439.760614)
				)
				(arc
					(start 413.3342 -437.21909)
					(mid 413.311882 -437.165208)
					(end 413.258 -437.14289)
				)
				(arc
					(start 412.3182 -437.14289)
					(mid 412.264318 -437.165208)
					(end 412.242 -437.21909)
				)
			)
		)
	)
	(zone
		(layer "In5.Cu")
		(hatch none 0.5)
		(connect_pads
			(clearance 0)
		)
		(min_thickness 0.25)
		(keepout
			(tracks not_allowed)
			(vias allowed)
			(pads allowed)
			(copperpour not_allowed)
			(footprints allowed)
		)
		(placement
			(enabled no)
			(sheetname "")
		)
		(fill
			(thermal_gap 0.5)
			(thermal_bridge_width 0.5)
			(island_removal_mode 0)
		)
		(polygon
			(pts
				(arc
					(start 385.242054 -431.560732)
					(mid 385.264372 -431.614614)
					(end 385.318254 -431.636932)
				)
				(arc
					(start 386.258054 -431.636932)
					(mid 386.311936 -431.614614)
					(end 386.334254 -431.560732)
				)
				(arc
					(start 386.334254 -429.019208)
					(mid 386.311936 -428.965326)
					(end 386.258054 -428.943008)
				)
				(arc
					(start 385.318254 -428.943008)
					(mid 385.264372 -428.965326)
					(end 385.242054 -429.019208)
				)
			)
		)
	)
	(zone
		(layer "In5.Cu")
		(hatch none 0.5)
		(connect_pads
			(clearance 0)
		)
		(min_thickness 0.25)
		(keepout
			(tracks not_allowed)
			(vias allowed)
			(pads allowed)
			(copperpour not_allowed)
			(footprints allowed)
		)
		(placement
			(enabled no)
			(sheetname "")
		)
		(fill
			(thermal_gap 0.5)
			(thermal_bridge_width 0.5)
			(island_removal_mode 0)
		)
		(polygon
			(pts
				(arc
					(start 331.142086 -431.560732)
					(mid 331.164404 -431.614614)
					(end 331.218286 -431.636932)
				)
				(arc
					(start 332.158086 -431.636932)
					(mid 332.211968 -431.614614)
					(end 332.234286 -431.560732)
				)
				(arc
					(start 332.234286 -429.019208)
					(mid 332.211968 -428.965326)
					(end 332.158086 -428.943008)
				)
				(arc
					(start 331.218286 -428.943008)
					(mid 331.164404 -428.965326)
					(end 331.142086 -429.019208)
				)
			)
		)
	)
	(zone
		(layer "In5.Cu")
		(hatch none 0.5)
		(connect_pads
			(clearance 0)
		)
		(min_thickness 0.25)
		(keepout
			(tracks not_allowed)
			(vias allowed)
			(pads allowed)
			(copperpour not_allowed)
			(footprints allowed)
		)
		(placement
			(enabled no)
			(sheetname "")
		)
		(fill
			(thermal_gap 0.5)
			(thermal_bridge_width 0.5)
			(island_removal_mode 0)
		)
		(polygon
			(pts
				(arc
					(start 322.14185 -427.960536)
					(mid 322.164168 -428.014418)
					(end 322.21805 -428.036736)
				)
				(arc
					(start 323.15785 -428.036736)
					(mid 323.211732 -428.014418)
					(end 323.23405 -427.960536)
				)
				(arc
					(start 323.23405 -425.419012)
					(mid 323.211732 -425.36513)
					(end 323.15785 -425.342812)
				)
				(arc
					(start 322.21805 -425.342812)
					(mid 322.164168 -425.36513)
					(end 322.14185 -425.419012)
				)
				(arc
					(start 322.14185 -426.146468)
					(mid 322.143849 -426.163809)
					(end 322.149724 -426.18025)
				)
				(arc
					(start 322.38315 -426.6565)
					(mid 322.390933 -426.690028)
					(end 322.38315 -426.723556)
				)
				(arc
					(start 322.149724 -427.199806)
					(mid 322.143829 -427.216242)
					(end 322.14185 -427.233588)
				)
			)
		)
	)
	(zone
		(layer "In5.Cu")
		(hatch none 0.5)
		(connect_pads
			(clearance 0)
		)
		(min_thickness 0.25)
		(keepout
			(tracks not_allowed)
			(vias allowed)
			(pads allowed)
			(copperpour not_allowed)
			(footprints allowed)
		)
		(placement
			(enabled no)
			(sheetname "")
		)
		(fill
			(thermal_gap 0.5)
			(thermal_bridge_width 0.5)
			(island_removal_mode 0)
		)
		(polygon
			(pts
				(arc
					(start 408.242008 -436.160672)
					(mid 408.264326 -436.214554)
					(end 408.318208 -436.236872)
				)
				(arc
					(start 409.258008 -436.236872)
					(mid 409.31189 -436.214554)
					(end 409.334208 -436.160672)
				)
				(arc
					(start 409.334208 -433.619148)
					(mid 409.31189 -433.565266)
					(end 409.258008 -433.542948)
				)
				(arc
					(start 408.318208 -433.542948)
					(mid 408.264326 -433.565266)
					(end 408.242008 -433.619148)
				)
			)
		)
	)
	(zone
		(layer "In5.Cu")
		(hatch none 0.5)
		(connect_pads
			(clearance 0)
		)
		(min_thickness 0.25)
		(keepout
			(tracks not_allowed)
			(vias allowed)
			(pads allowed)
			(copperpour not_allowed)
			(footprints allowed)
		)
		(placement
			(enabled no)
			(sheetname "")
		)
		(fill
			(thermal_gap 0.5)
			(thermal_bridge_width 0.5)
			(island_removal_mode 0)
		)
		(polygon
			(pts
				(arc
					(start 389.242046 -431.560732)
					(mid 389.264364 -431.614614)
					(end 389.318246 -431.636932)
				)
				(arc
					(start 390.258046 -431.636932)
					(mid 390.311928 -431.614614)
					(end 390.334246 -431.560732)
				)
				(arc
					(start 390.334246 -429.019208)
					(mid 390.311928 -428.965326)
					(end 390.258046 -428.943008)
				)
				(arc
					(start 389.318246 -428.943008)
					(mid 389.264364 -428.965326)
					(end 389.242046 -429.019208)
				)
			)
		)
	)
	(zone
		(layer "In5.Cu")
		(hatch none 0.5)
		(connect_pads
			(clearance 0)
		)
		(min_thickness 0.25)
		(keepout
			(tracks not_allowed)
			(vias allowed)
			(pads allowed)
			(copperpour not_allowed)
			(footprints allowed)
		)
		(placement
			(enabled no)
			(sheetname "")
		)
		(fill
			(thermal_gap 0.5)
			(thermal_bridge_width 0.5)
			(island_removal_mode 0)
		)
		(polygon
			(pts
				(arc
					(start 404.242016 -436.160672)
					(mid 404.264334 -436.214554)
					(end 404.318216 -436.236872)
				)
				(arc
					(start 405.258016 -436.236872)
					(mid 405.311898 -436.214554)
					(end 405.334216 -436.160672)
				)
				(arc
					(start 405.334216 -433.619148)
					(mid 405.311898 -433.565266)
					(end 405.258016 -433.542948)
				)
				(arc
					(start 404.318216 -433.542948)
					(mid 404.264334 -433.565266)
					(end 404.242016 -433.619148)
				)
			)
		)
	)
	(zone
		(layer "In5.Cu")
		(hatch none 0.5)
		(connect_pads
			(clearance 0)
		)
		(min_thickness 0.25)
		(keepout
			(tracks not_allowed)
			(vias allowed)
			(pads allowed)
			(copperpour not_allowed)
			(footprints allowed)
		)
		(placement
			(enabled no)
			(sheetname "")
		)
		(fill
			(thermal_gap 0.5)
			(thermal_bridge_width 0.5)
			(island_removal_mode 0)
		)
		(polygon
			(pts
				(arc
					(start 395.242034 -432.56073)
					(mid 395.264352 -432.614612)
					(end 395.318234 -432.63693)
				)
				(arc
					(start 396.258034 -432.63693)
					(mid 396.311916 -432.614612)
					(end 396.334234 -432.56073)
				)
				(arc
					(start 396.334234 -430.019206)
					(mid 396.311916 -429.965324)
					(end 396.258034 -429.943006)
				)
				(arc
					(start 395.318234 -429.943006)
					(mid 395.264352 -429.965324)
					(end 395.242034 -430.019206)
				)
			)
		)
	)
	(zone
		(layer "In5.Cu")
		(hatch none 0.5)
		(connect_pads
			(clearance 0)
		)
		(min_thickness 0.25)
		(keepout
			(tracks not_allowed)
			(vias allowed)
			(pads allowed)
			(copperpour not_allowed)
			(footprints allowed)
		)
		(placement
			(enabled no)
			(sheetname "")
		)
		(fill
			(thermal_gap 0.5)
			(thermal_bridge_width 0.5)
			(island_removal_mode 0)
		)
		(polygon
			(pts
				(arc
					(start 404.242016 -439.760614)
					(mid 404.264334 -439.814496)
					(end 404.318216 -439.836814)
				)
				(arc
					(start 405.258016 -439.836814)
					(mid 405.311898 -439.814496)
					(end 405.334216 -439.760614)
				)
				(arc
					(start 405.334216 -437.21909)
					(mid 405.311898 -437.165208)
					(end 405.258016 -437.14289)
				)
				(arc
					(start 404.318216 -437.14289)
					(mid 404.264334 -437.165208)
					(end 404.242016 -437.21909)
				)
			)
		)
	)
	(zone
		(layer "In5.Cu")
		(hatch none 0.5)
		(connect_pads
			(clearance 0)
		)
		(min_thickness 0.25)
		(keepout
			(tracks not_allowed)
			(vias allowed)
			(pads allowed)
			(copperpour not_allowed)
			(footprints allowed)
		)
		(placement
			(enabled no)
			(sheetname "")
		)
		(fill
			(thermal_gap 0.5)
			(thermal_bridge_width 0.5)
			(island_removal_mode 0)
		)
		(polygon
			(pts
				(arc
					(start 385.242054 -427.960536)
					(mid 385.264372 -428.014418)
					(end 385.318254 -428.036736)
				)
				(arc
					(start 386.258054 -428.036736)
					(mid 386.311936 -428.014418)
					(end 386.334254 -427.960536)
				)
				(arc
					(start 386.334254 -425.419012)
					(mid 386.311936 -425.36513)
					(end 386.258054 -425.342812)
				)
				(arc
					(start 385.318254 -425.342812)
					(mid 385.264372 -425.36513)
					(end 385.242054 -425.419012)
				)
				(arc
					(start 385.242054 -426.146468)
					(mid 385.244053 -426.163809)
					(end 385.249928 -426.18025)
				)
				(arc
					(start 385.483354 -426.6565)
					(mid 385.491137 -426.690028)
					(end 385.483354 -426.723556)
				)
				(arc
					(start 385.249928 -427.199806)
					(mid 385.244033 -427.216242)
					(end 385.242054 -427.233588)
				)
			)
		)
	)
	(zone
		(layer "In5.Cu")
		(hatch none 0.5)
		(connect_pads
			(clearance 0)
		)
		(min_thickness 0.25)
		(keepout
			(tracks not_allowed)
			(vias allowed)
			(pads allowed)
			(copperpour not_allowed)
			(footprints allowed)
		)
		(placement
			(enabled no)
			(sheetname "")
		)
		(fill
			(thermal_gap 0.5)
			(thermal_bridge_width 0.5)
			(island_removal_mode 0)
		)
		(polygon
			(pts
				(arc
					(start 402.242274 -431.560732)
					(mid 402.264592 -431.614614)
					(end 402.318474 -431.636932)
				)
				(arc
					(start 403.258274 -431.636932)
					(mid 403.312156 -431.614614)
					(end 403.334474 -431.560732)
				)
				(arc
					(start 403.334474 -429.019208)
					(mid 403.312156 -428.965326)
					(end 403.258274 -428.943008)
				)
				(arc
					(start 402.318474 -428.943008)
					(mid 402.264592 -428.965326)
					(end 402.242274 -429.019208)
				)
			)
		)
	)
	(zone
		(layer "In5.Cu")
		(hatch none 0.5)
		(connect_pads
			(clearance 0)
		)
		(min_thickness 0.25)
		(keepout
			(tracks not_allowed)
			(vias allowed)
			(pads allowed)
			(copperpour not_allowed)
			(footprints allowed)
		)
		(placement
			(enabled no)
			(sheetname "")
		)
		(fill
			(thermal_gap 0.5)
			(thermal_bridge_width 0.5)
			(island_removal_mode 0)
		)
		(polygon
			(pts
				(arc
					(start 343.142062 -431.560732)
					(mid 343.16438 -431.614614)
					(end 343.218262 -431.636932)
				)
				(arc
					(start 344.158062 -431.636932)
					(mid 344.211944 -431.614614)
					(end 344.234262 -431.560732)
				)
				(arc
					(start 344.234262 -429.019208)
					(mid 344.211944 -428.965326)
					(end 344.158062 -428.943008)
				)
				(arc
					(start 343.218262 -428.943008)
					(mid 343.16438 -428.965326)
					(end 343.142062 -429.019208)
				)
			)
		)
	)
	(zone
		(layer "In5.Cu")
		(hatch none 0.5)
		(connect_pads
			(clearance 0)
		)
		(min_thickness 0.25)
		(keepout
			(tracks not_allowed)
			(vias allowed)
			(pads allowed)
			(copperpour not_allowed)
			(footprints allowed)
		)
		(placement
			(enabled no)
			(sheetname "")
		)
		(fill
			(thermal_gap 0.5)
			(thermal_bridge_width 0.5)
			(island_removal_mode 0)
		)
		(polygon
			(pts
				(arc
					(start 389.242046 -435.160674)
					(mid 389.264364 -435.214556)
					(end 389.318246 -435.236874)
				)
				(arc
					(start 390.258046 -435.236874)
					(mid 390.311928 -435.214556)
					(end 390.334246 -435.160674)
				)
				(arc
					(start 390.334246 -432.61915)
					(mid 390.311928 -432.565268)
					(end 390.258046 -432.54295)
				)
				(arc
					(start 389.318246 -432.54295)
					(mid 389.264364 -432.565268)
					(end 389.242046 -432.61915)
				)
			)
		)
	)
	(zone
		(layer "In5.Cu")
		(hatch none 0.5)
		(connect_pads
			(clearance 0)
		)
		(min_thickness 0.25)
		(keepout
			(tracks not_allowed)
			(vias allowed)
			(pads allowed)
			(copperpour not_allowed)
			(footprints allowed)
		)
		(placement
			(enabled no)
			(sheetname "")
		)
		(fill
			(thermal_gap 0.5)
			(thermal_bridge_width 0.5)
			(island_removal_mode 0)
		)
		(polygon
			(pts
				(arc
					(start 393.242038 -431.560732)
					(mid 393.264356 -431.614614)
					(end 393.318238 -431.636932)
				)
				(arc
					(start 394.258038 -431.636932)
					(mid 394.31192 -431.614614)
					(end 394.334238 -431.560732)
				)
				(arc
					(start 394.334238 -429.019208)
					(mid 394.31192 -428.965326)
					(end 394.258038 -428.943008)
				)
				(arc
					(start 393.318238 -428.943008)
					(mid 393.264356 -428.965326)
					(end 393.242038 -429.019208)
				)
			)
		)
	)
	(zone
		(layer "In5.Cu")
		(hatch none 0.5)
		(connect_pads
			(clearance 0)
		)
		(min_thickness 0.25)
		(keepout
			(tracks not_allowed)
			(vias allowed)
			(pads allowed)
			(copperpour not_allowed)
			(footprints allowed)
		)
		(placement
			(enabled no)
			(sheetname "")
		)
		(fill
			(thermal_gap 0.5)
			(thermal_bridge_width 0.5)
			(island_removal_mode 0)
		)
		(polygon
			(pts
				(arc
					(start 324.141846 -428.960534)
					(mid 324.164164 -429.014416)
					(end 324.218046 -429.036734)
				)
				(arc
					(start 325.157846 -429.036734)
					(mid 325.211728 -429.014416)
					(end 325.234046 -428.960534)
				)
				(arc
					(start 325.234046 -426.41901)
					(mid 325.211728 -426.365128)
					(end 325.157846 -426.34281)
				)
				(arc
					(start 324.218046 -426.34281)
					(mid 324.164164 -426.365128)
					(end 324.141846 -426.41901)
				)
				(arc
					(start 324.141846 -427.146466)
					(mid 324.143845 -427.163807)
					(end 324.14972 -427.180248)
				)
				(arc
					(start 324.383146 -427.656498)
					(mid 324.390929 -427.690026)
					(end 324.383146 -427.723554)
				)
				(arc
					(start 324.14972 -428.199804)
					(mid 324.143825 -428.21624)
					(end 324.141846 -428.233586)
				)
			)
		)
	)
	(zone
		(layer "In5.Cu")
		(hatch none 0.5)
		(connect_pads
			(clearance 0)
		)
		(min_thickness 0.25)
		(keepout
			(tracks not_allowed)
			(vias allowed)
			(pads allowed)
			(copperpour not_allowed)
			(footprints allowed)
		)
		(placement
			(enabled no)
			(sheetname "")
		)
		(fill
			(thermal_gap 0.5)
			(thermal_bridge_width 0.5)
			(island_removal_mode 0)
		)
		(polygon
			(pts
				(arc
					(start 412.242 -436.160672)
					(mid 412.264318 -436.214554)
					(end 412.3182 -436.236872)
				)
				(arc
					(start 413.258 -436.236872)
					(mid 413.311882 -436.214554)
					(end 413.3342 -436.160672)
				)
				(arc
					(start 413.3342 -433.619148)
					(mid 413.311882 -433.565266)
					(end 413.258 -433.542948)
				)
				(arc
					(start 412.3182 -433.542948)
					(mid 412.264318 -433.565266)
					(end 412.242 -433.619148)
				)
			)
		)
	)
	(zone
		(layer "In5.Cu")
		(hatch none 0.5)
		(connect_pads
			(clearance 0)
		)
		(min_thickness 0.25)
		(keepout
			(tracks not_allowed)
			(vias allowed)
			(pads allowed)
			(copperpour not_allowed)
			(footprints allowed)
		)
		(placement
			(enabled no)
			(sheetname "")
		)
		(fill
			(thermal_gap 0.5)
			(thermal_bridge_width 0.5)
			(island_removal_mode 0)
		)
		(polygon
			(pts
				(arc
					(start 383.242058 -432.56073)
					(mid 383.264376 -432.614612)
					(end 383.318258 -432.63693)
				)
				(arc
					(start 384.258058 -432.63693)
					(mid 384.31194 -432.614612)
					(end 384.334258 -432.56073)
				)
				(arc
					(start 384.334258 -430.019206)
					(mid 384.31194 -429.965324)
					(end 384.258058 -429.943006)
				)
				(arc
					(start 383.318258 -429.943006)
					(mid 383.264376 -429.965324)
					(end 383.242058 -430.019206)
				)
			)
		)
	)
	(zone
		(layer "In5.Cu")
		(hatch none 0.5)
		(connect_pads
			(clearance 0)
		)
		(min_thickness 0.25)
		(keepout
			(tracks not_allowed)
			(vias allowed)
			(pads allowed)
			(copperpour not_allowed)
			(footprints allowed)
		)
		(placement
			(enabled no)
			(sheetname "")
		)
		(fill
			(thermal_gap 0.5)
			(thermal_bridge_width 0.5)
			(island_removal_mode 0)
		)
		(polygon
			(pts
				(arc
					(start 387.24205 -432.56073)
					(mid 387.264368 -432.614612)
					(end 387.31825 -432.63693)
				)
				(arc
					(start 388.25805 -432.63693)
					(mid 388.311932 -432.614612)
					(end 388.33425 -432.56073)
				)
				(arc
					(start 388.33425 -430.019206)
					(mid 388.311932 -429.965324)
					(end 388.25805 -429.943006)
				)
				(arc
					(start 387.31825 -429.943006)
					(mid 387.264368 -429.965324)
					(end 387.24205 -430.019206)
				)
			)
		)
	)
	(zone
		(layer "In5.Cu")
		(hatch none 0.5)
		(connect_pads
			(clearance 0)
		)
		(min_thickness 0.25)
		(keepout
			(tracks not_allowed)
			(vias allowed)
			(pads allowed)
			(copperpour not_allowed)
			(footprints allowed)
		)
		(placement
			(enabled no)
			(sheetname "")
		)
		(fill
			(thermal_gap 0.5)
			(thermal_bridge_width 0.5)
			(island_removal_mode 0)
		)
		(polygon
			(pts
				(arc
					(start 326.141842 -427.960536)
					(mid 326.16416 -428.014418)
					(end 326.218042 -428.036736)
				)
				(arc
					(start 327.157842 -428.036736)
					(mid 327.211724 -428.014418)
					(end 327.234042 -427.960536)
				)
				(arc
					(start 327.234042 -425.419012)
					(mid 327.211724 -425.36513)
					(end 327.157842 -425.342812)
				)
				(arc
					(start 326.218042 -425.342812)
					(mid 326.16416 -425.36513)
					(end 326.141842 -425.419012)
				)
				(arc
					(start 326.141842 -426.146468)
					(mid 326.143841 -426.163809)
					(end 326.149716 -426.18025)
				)
				(arc
					(start 326.383142 -426.6565)
					(mid 326.390925 -426.690028)
					(end 326.383142 -426.723556)
				)
				(arc
					(start 326.149716 -427.199806)
					(mid 326.143821 -427.216242)
					(end 326.141842 -427.233588)
				)
			)
		)
	)
	(zone
		(layer "In5.Cu")
		(hatch none 0.5)
		(connect_pads
			(clearance 0)
		)
		(min_thickness 0.25)
		(keepout
			(tracks not_allowed)
			(vias allowed)
			(pads allowed)
			(copperpour not_allowed)
			(footprints allowed)
		)
		(placement
			(enabled no)
			(sheetname "")
		)
		(fill
			(thermal_gap 0.5)
			(thermal_bridge_width 0.5)
			(island_removal_mode 0)
		)
		(polygon
			(pts
				(arc
					(start 391.242042 -432.56073)
					(mid 391.26436 -432.614612)
					(end 391.318242 -432.63693)
				)
				(arc
					(start 392.258042 -432.63693)
					(mid 392.311924 -432.614612)
					(end 392.334242 -432.56073)
				)
				(arc
					(start 392.334242 -430.019206)
					(mid 392.311924 -429.965324)
					(end 392.258042 -429.943006)
				)
				(arc
					(start 391.318242 -429.943006)
					(mid 391.26436 -429.965324)
					(end 391.242042 -430.019206)
				)
			)
		)
	)
	(zone
		(layer "In5.Cu")
		(hatch none 0.5)
		(connect_pads
			(clearance 0)
		)
		(min_thickness 0.25)
		(keepout
			(tracks not_allowed)
			(vias allowed)
			(pads allowed)
			(copperpour not_allowed)
			(footprints allowed)
		)
		(placement
			(enabled no)
			(sheetname "")
		)
		(fill
			(thermal_gap 0.5)
			(thermal_bridge_width 0.5)
			(island_removal_mode 0)
		)
		(polygon
			(pts
				(arc
					(start 383.242058 -436.160672)
					(mid 383.264376 -436.214554)
					(end 383.318258 -436.236872)
				)
				(arc
					(start 384.258058 -436.236872)
					(mid 384.31194 -436.214554)
					(end 384.334258 -436.160672)
				)
				(arc
					(start 384.334258 -433.619148)
					(mid 384.31194 -433.565266)
					(end 384.258058 -433.542948)
				)
				(arc
					(start 383.318258 -433.542948)
					(mid 383.264376 -433.565266)
					(end 383.242058 -433.619148)
				)
			)
		)
	)
	(zone
		(layer "In5.Cu")
		(hatch none 0.5)
		(connect_pads
			(clearance 0)
		)
		(min_thickness 0.25)
		(keepout
			(tracks not_allowed)
			(vias allowed)
			(pads allowed)
			(copperpour not_allowed)
			(footprints allowed)
		)
		(placement
			(enabled no)
			(sheetname "")
		)
		(fill
			(thermal_gap 0.5)
			(thermal_bridge_width 0.5)
			(island_removal_mode 0)
		)
		(polygon
			(pts
				(arc
					(start 337.142074 -432.56073)
					(mid 337.164392 -432.614612)
					(end 337.218274 -432.63693)
				)
				(arc
					(start 338.158074 -432.63693)
					(mid 338.211956 -432.614612)
					(end 338.234274 -432.56073)
				)
				(arc
					(start 338.234274 -430.019206)
					(mid 338.211956 -429.965324)
					(end 338.158074 -429.943006)
				)
				(arc
					(start 337.218274 -429.943006)
					(mid 337.164392 -429.965324)
					(end 337.142074 -430.019206)
				)
			)
		)
	)
	(zone
		(layer "In5.Cu")
		(hatch none 0.5)
		(connect_pads
			(clearance 0)
		)
		(min_thickness 0.25)
		(keepout
			(tracks not_allowed)
			(vias allowed)
			(pads allowed)
			(copperpour not_allowed)
			(footprints allowed)
		)
		(placement
			(enabled no)
			(sheetname "")
		)
		(fill
			(thermal_gap 0.5)
			(thermal_bridge_width 0.5)
			(island_removal_mode 0)
		)
		(polygon
			(pts
				(arc
					(start 408.242262 -432.56073)
					(mid 408.26458 -432.614612)
					(end 408.318462 -432.63693)
				)
				(arc
					(start 409.258262 -432.63693)
					(mid 409.312144 -432.614612)
					(end 409.334462 -432.56073)
				)
				(arc
					(start 409.334462 -430.019206)
					(mid 409.312144 -429.965324)
					(end 409.258262 -429.943006)
				)
				(arc
					(start 408.318462 -429.943006)
					(mid 408.26458 -429.965324)
					(end 408.242262 -430.019206)
				)
			)
		)
	)
	(zone
		(layer "In5.Cu")
		(hatch none 0.5)
		(connect_pads
			(clearance 0)
		)
		(min_thickness 0.25)
		(keepout
			(tracks not_allowed)
			(vias allowed)
			(pads allowed)
			(copperpour not_allowed)
			(footprints allowed)
		)
		(placement
			(enabled no)
			(sheetname "")
		)
		(fill
			(thermal_gap 0.5)
			(thermal_bridge_width 0.5)
			(island_removal_mode 0)
		)
		(polygon
			(pts
				(xy 220.052392 -402.70938) (xy 220.052392 -401.11934) (xy 221.680278 -401.11934) (xy 221.680278 -402.70938)
			)
		)
	)
	(zone
		(layer "In5.Cu")
		(hatch none 0.5)
		(connect_pads
			(clearance 0)
		)
		(min_thickness 0.25)
		(keepout
			(tracks not_allowed)
			(vias allowed)
			(pads allowed)
			(copperpour not_allowed)
			(footprints allowed)
		)
		(placement
			(enabled no)
			(sheetname "")
		)
		(fill
			(thermal_gap 0.5)
			(thermal_bridge_width 0.5)
			(island_removal_mode 0)
		)
		(polygon
			(pts
				(arc
					(start 408.242008 -439.760614)
					(mid 408.264326 -439.814496)
					(end 408.318208 -439.836814)
				)
				(arc
					(start 409.258008 -439.836814)
					(mid 409.31189 -439.814496)
					(end 409.334208 -439.760614)
				)
				(arc
					(start 409.334208 -437.21909)
					(mid 409.31189 -437.165208)
					(end 409.258008 -437.14289)
				)
				(arc
					(start 408.318208 -437.14289)
					(mid 408.264326 -437.165208)
					(end 408.242008 -437.21909)
				)
			)
		)
	)
	(zone
		(layer "In5.Cu")
		(hatch none 0.5)
		(connect_pads
			(clearance 0)
		)
		(min_thickness 0.25)
		(keepout
			(tracks not_allowed)
			(vias allowed)
			(pads allowed)
			(copperpour not_allowed)
			(footprints allowed)
		)
		(placement
			(enabled no)
			(sheetname "")
		)
		(fill
			(thermal_gap 0.5)
			(thermal_bridge_width 0.5)
			(island_removal_mode 0)
		)
		(polygon
			(pts
				(arc
					(start 381.242062 -427.960536)
					(mid 381.26438 -428.014418)
					(end 381.318262 -428.036736)
				)
				(arc
					(start 382.258062 -428.036736)
					(mid 382.311944 -428.014418)
					(end 382.334262 -427.960536)
				)
				(arc
					(start 382.334262 -425.419012)
					(mid 382.311944 -425.36513)
					(end 382.258062 -425.342812)
				)
				(arc
					(start 381.318262 -425.342812)
					(mid 381.26438 -425.36513)
					(end 381.242062 -425.419012)
				)
				(arc
					(start 381.242062 -426.146468)
					(mid 381.244061 -426.163809)
					(end 381.249936 -426.18025)
				)
				(arc
					(start 381.483362 -426.6565)
					(mid 381.491145 -426.690028)
					(end 381.483362 -426.723556)
				)
				(arc
					(start 381.249936 -427.199806)
					(mid 381.244041 -427.216242)
					(end 381.242062 -427.233588)
				)
			)
		)
	)
	(zone
		(layer "In5.Cu")
		(hatch none 0.5)
		(connect_pads
			(clearance 0)
		)
		(min_thickness 0.25)
		(keepout
			(tracks not_allowed)
			(vias allowed)
			(pads allowed)
			(copperpour not_allowed)
			(footprints allowed)
		)
		(placement
			(enabled no)
			(sheetname "")
		)
		(fill
			(thermal_gap 0.5)
			(thermal_bridge_width 0.5)
			(island_removal_mode 0)
		)
		(polygon
			(pts
				(arc
					(start 412.242 -428.960534)
					(mid 412.264318 -429.014416)
					(end 412.3182 -429.036734)
				)
				(arc
					(start 413.258 -429.036734)
					(mid 413.311882 -429.014416)
					(end 413.3342 -428.960534)
				)
				(arc
					(start 413.3342 -426.41901)
					(mid 413.311882 -426.365128)
					(end 413.258 -426.34281)
				)
				(arc
					(start 412.3182 -426.34281)
					(mid 412.264318 -426.365128)
					(end 412.242 -426.41901)
				)
				(arc
					(start 412.242 -427.146466)
					(mid 412.243999 -427.163807)
					(end 412.249874 -427.180248)
				)
				(arc
					(start 412.4833 -427.656498)
					(mid 412.491083 -427.690026)
					(end 412.4833 -427.723554)
				)
				(arc
					(start 412.249874 -428.199804)
					(mid 412.243979 -428.21624)
					(end 412.242 -428.233586)
				)
			)
		)
	)
	(zone
		(layer "In5.Cu")
		(hatch none 0.5)
		(connect_pads
			(clearance 0)
		)
		(min_thickness 0.25)
		(keepout
			(tracks not_allowed)
			(vias allowed)
			(pads allowed)
			(copperpour not_allowed)
			(footprints allowed)
		)
		(placement
			(enabled no)
			(sheetname "")
		)
		(fill
			(thermal_gap 0.5)
			(thermal_bridge_width 0.5)
			(island_removal_mode 0)
		)
		(polygon
			(pts
				(arc
					(start 398.242028 -435.160674)
					(mid 398.264346 -435.214556)
					(end 398.318228 -435.236874)
				)
				(arc
					(start 399.258028 -435.236874)
					(mid 399.31191 -435.214556)
					(end 399.334228 -435.160674)
				)
				(arc
					(start 399.334228 -432.61915)
					(mid 399.31191 -432.565268)
					(end 399.258028 -432.54295)
				)
				(arc
					(start 398.318228 -432.54295)
					(mid 398.264346 -432.565268)
					(end 398.242028 -432.61915)
				)
			)
		)
	)
	(zone
		(layer "In5.Cu")
		(hatch none 0.5)
		(connect_pads
			(clearance 0)
		)
		(min_thickness 0.25)
		(keepout
			(tracks not_allowed)
			(vias allowed)
			(pads allowed)
			(copperpour not_allowed)
			(footprints allowed)
		)
		(placement
			(enabled no)
			(sheetname "")
		)
		(fill
			(thermal_gap 0.5)
			(thermal_bridge_width 0.5)
			(island_removal_mode 0)
		)
		(polygon
			(pts
				(arc
					(start 341.142066 -432.56073)
					(mid 341.164384 -432.614612)
					(end 341.218266 -432.63693)
				)
				(arc
					(start 342.158066 -432.63693)
					(mid 342.211948 -432.614612)
					(end 342.234266 -432.56073)
				)
				(arc
					(start 342.234266 -430.019206)
					(mid 342.211948 -429.965324)
					(end 342.158066 -429.943006)
				)
				(arc
					(start 341.218266 -429.943006)
					(mid 341.164384 -429.965324)
					(end 341.142066 -430.019206)
				)
			)
		)
	)
	(zone
		(layer "In5.Cu")
		(hatch none 0.5)
		(connect_pads
			(clearance 0)
		)
		(min_thickness 0.25)
		(keepout
			(tracks not_allowed)
			(vias allowed)
			(pads allowed)
			(copperpour not_allowed)
			(footprints allowed)
		)
		(placement
			(enabled no)
			(sheetname "")
		)
		(fill
			(thermal_gap 0.5)
			(thermal_bridge_width 0.5)
			(island_removal_mode 0)
		)
		(polygon
			(pts
				(arc
					(start 404.242016 -428.960534)
					(mid 404.264334 -429.014416)
					(end 404.318216 -429.036734)
				)
				(arc
					(start 405.258016 -429.036734)
					(mid 405.311898 -429.014416)
					(end 405.334216 -428.960534)
				)
				(arc
					(start 405.334216 -426.41901)
					(mid 405.311898 -426.365128)
					(end 405.258016 -426.34281)
				)
				(arc
					(start 404.318216 -426.34281)
					(mid 404.264334 -426.365128)
					(end 404.242016 -426.41901)
				)
				(arc
					(start 404.242016 -427.146466)
					(mid 404.244015 -427.163807)
					(end 404.24989 -427.180248)
				)
				(arc
					(start 404.483316 -427.656498)
					(mid 404.491099 -427.690026)
					(end 404.483316 -427.723554)
				)
				(arc
					(start 404.24989 -428.199804)
					(mid 404.243995 -428.21624)
					(end 404.242016 -428.233586)
				)
			)
		)
	)
	(zone
		(layer "In5.Cu")
		(hatch none 0.5)
		(connect_pads
			(clearance 0)
		)
		(min_thickness 0.25)
		(keepout
			(tracks not_allowed)
			(vias allowed)
			(pads allowed)
			(copperpour not_allowed)
			(footprints allowed)
		)
		(placement
			(enabled no)
			(sheetname "")
		)
		(fill
			(thermal_gap 0.5)
			(thermal_bridge_width 0.5)
			(island_removal_mode 0)
		)
		(polygon
			(pts
				(arc
					(start 385.242054 -438.760616)
					(mid 385.264372 -438.814498)
					(end 385.318254 -438.836816)
				)
				(arc
					(start 386.258054 -438.836816)
					(mid 386.311936 -438.814498)
					(end 386.334254 -438.760616)
				)
				(arc
					(start 386.334254 -436.219092)
					(mid 386.311936 -436.16521)
					(end 386.258054 -436.142892)
				)
				(arc
					(start 385.318254 -436.142892)
					(mid 385.264372 -436.16521)
					(end 385.242054 -436.219092)
				)
			)
		)
	)
	(zone
		(layer "In5.Cu")
		(hatch none 0.5)
		(connect_pads
			(clearance 0)
		)
		(min_thickness 0.25)
		(keepout
			(tracks not_allowed)
			(vias allowed)
			(pads allowed)
			(copperpour not_allowed)
			(footprints allowed)
		)
		(placement
			(enabled no)
			(sheetname "")
		)
		(fill
			(thermal_gap 0.5)
			(thermal_bridge_width 0.5)
			(island_removal_mode 0)
		)
		(polygon
			(pts
				(arc
					(start 387.24205 -436.160672)
					(mid 387.264368 -436.214554)
					(end 387.31825 -436.236872)
				)
				(arc
					(start 388.25805 -436.236872)
					(mid 388.311932 -436.214554)
					(end 388.33425 -436.160672)
				)
				(arc
					(start 388.33425 -433.619148)
					(mid 388.311932 -433.565266)
					(end 388.25805 -433.542948)
				)
				(arc
					(start 387.31825 -433.542948)
					(mid 387.264368 -433.565266)
					(end 387.24205 -433.619148)
				)
			)
		)
	)
	(zone
		(layer "In5.Cu")
		(hatch none 0.5)
		(connect_pads
			(clearance 0)
		)
		(min_thickness 0.25)
		(keepout
			(tracks not_allowed)
			(vias allowed)
			(pads allowed)
			(copperpour not_allowed)
			(footprints allowed)
		)
		(placement
			(enabled no)
			(sheetname "")
		)
		(fill
			(thermal_gap 0.5)
			(thermal_bridge_width 0.5)
			(island_removal_mode 0)
		)
		(polygon
			(pts
				(arc
					(start 393.242038 -438.760616)
					(mid 393.264356 -438.814498)
					(end 393.318238 -438.836816)
				)
				(arc
					(start 394.258038 -438.836816)
					(mid 394.31192 -438.814498)
					(end 394.334238 -438.760616)
				)
				(arc
					(start 394.334238 -436.219092)
					(mid 394.31192 -436.16521)
					(end 394.258038 -436.142892)
				)
				(arc
					(start 393.318238 -436.142892)
					(mid 393.264356 -436.16521)
					(end 393.242038 -436.219092)
				)
			)
		)
	)
	(zone
		(layer "In5.Cu")
		(hatch none 0.5)
		(connect_pads
			(clearance 0)
		)
		(min_thickness 0.25)
		(keepout
			(tracks not_allowed)
			(vias allowed)
			(pads allowed)
			(copperpour not_allowed)
			(footprints allowed)
		)
		(placement
			(enabled no)
			(sheetname "")
		)
		(fill
			(thermal_gap 0.5)
			(thermal_bridge_width 0.5)
			(island_removal_mode 0)
		)
		(polygon
			(pts
				(arc
					(start 395.242034 -428.960534)
					(mid 395.264352 -429.014416)
					(end 395.318234 -429.036734)
				)
				(arc
					(start 396.258034 -429.036734)
					(mid 396.311916 -429.014416)
					(end 396.334234 -428.960534)
				)
				(arc
					(start 396.334234 -426.41901)
					(mid 396.311916 -426.365128)
					(end 396.258034 -426.34281)
				)
				(arc
					(start 395.318234 -426.34281)
					(mid 395.264352 -426.365128)
					(end 395.242034 -426.41901)
				)
				(arc
					(start 395.242034 -427.146466)
					(mid 395.244033 -427.163807)
					(end 395.249908 -427.180248)
				)
				(arc
					(start 395.483334 -427.656498)
					(mid 395.491117 -427.690026)
					(end 395.483334 -427.723554)
				)
				(arc
					(start 395.249908 -428.199804)
					(mid 395.244013 -428.21624)
					(end 395.242034 -428.233586)
				)
			)
		)
	)
	(zone
		(layer "In5.Cu")
		(hatch none 0.5)
		(connect_pads
			(clearance 0)
		)
		(min_thickness 0.25)
		(keepout
			(tracks not_allowed)
			(vias allowed)
			(pads allowed)
			(copperpour not_allowed)
			(footprints allowed)
		)
		(placement
			(enabled no)
			(sheetname "")
		)
		(fill
			(thermal_gap 0.5)
			(thermal_bridge_width 0.5)
			(island_removal_mode 0)
		)
		(polygon
			(pts
				(arc
					(start 339.14207 -431.560732)
					(mid 339.164388 -431.614614)
					(end 339.21827 -431.636932)
				)
				(arc
					(start 340.15807 -431.636932)
					(mid 340.211952 -431.614614)
					(end 340.23427 -431.560732)
				)
				(arc
					(start 340.23427 -429.019208)
					(mid 340.211952 -428.965326)
					(end 340.15807 -428.943008)
				)
				(arc
					(start 339.21827 -428.943008)
					(mid 339.164388 -428.965326)
					(end 339.14207 -429.019208)
				)
			)
		)
	)
	(zone
		(layer "In5.Cu")
		(hatch none 0.5)
		(connect_pads
			(clearance 0)
		)
		(min_thickness 0.25)
		(keepout
			(tracks not_allowed)
			(vias allowed)
			(pads allowed)
			(copperpour not_allowed)
			(footprints allowed)
		)
		(placement
			(enabled no)
			(sheetname "")
		)
		(fill
			(thermal_gap 0.5)
			(thermal_bridge_width 0.5)
			(island_removal_mode 0)
		)
		(polygon
			(pts
				(arc
					(start 385.242054 -435.160674)
					(mid 385.264372 -435.214556)
					(end 385.318254 -435.236874)
				)
				(arc
					(start 386.258054 -435.236874)
					(mid 386.311936 -435.214556)
					(end 386.334254 -435.160674)
				)
				(arc
					(start 386.334254 -432.61915)
					(mid 386.311936 -432.565268)
					(end 386.258054 -432.54295)
				)
				(arc
					(start 385.318254 -432.54295)
					(mid 385.264372 -432.565268)
					(end 385.242054 -432.61915)
				)
			)
		)
	)
	(zone
		(layer "In5.Cu")
		(hatch none 0.5)
		(connect_pads
			(clearance 0)
		)
		(min_thickness 0.25)
		(keepout
			(tracks not_allowed)
			(vias allowed)
			(pads allowed)
			(copperpour not_allowed)
			(footprints allowed)
		)
		(placement
			(enabled no)
			(sheetname "")
		)
		(fill
			(thermal_gap 0.5)
			(thermal_bridge_width 0.5)
			(island_removal_mode 0)
		)
		(polygon
			(pts
				(arc
					(start 406.242012 -435.160674)
					(mid 406.26433 -435.214556)
					(end 406.318212 -435.236874)
				)
				(arc
					(start 407.258012 -435.236874)
					(mid 407.311894 -435.214556)
					(end 407.334212 -435.160674)
				)
				(arc
					(start 407.334212 -432.61915)
					(mid 407.311894 -432.565268)
					(end 407.258012 -432.54295)
				)
				(arc
					(start 406.318212 -432.54295)
					(mid 406.26433 -432.565268)
					(end 406.242012 -432.61915)
				)
			)
		)
	)
	(zone
		(layer "In5.Cu")
		(hatch none 0.5)
		(connect_pads
			(clearance 0)
		)
		(min_thickness 0.25)
		(keepout
			(tracks not_allowed)
			(vias allowed)
			(pads allowed)
			(copperpour not_allowed)
			(footprints allowed)
		)
		(placement
			(enabled no)
			(sheetname "")
		)
		(fill
			(thermal_gap 0.5)
			(thermal_bridge_width 0.5)
			(island_removal_mode 0)
		)
		(polygon
			(pts
				(xy 198.669656 -402.746972) (xy 198.669656 -401.144486) (xy 200.348088 -401.144486) (xy 200.348088 -402.746972)
			)
		)
	)
	(zone
		(layer "In5.Cu")
		(hatch none 0.5)
		(connect_pads
			(clearance 0)
		)
		(min_thickness 0.25)
		(keepout
			(tracks not_allowed)
			(vias allowed)
			(pads allowed)
			(copperpour not_allowed)
			(footprints allowed)
		)
		(placement
			(enabled no)
			(sheetname "")
		)
		(fill
			(thermal_gap 0.5)
			(thermal_bridge_width 0.5)
			(island_removal_mode 0)
		)
		(polygon
			(pts
				(arc
					(start 318.141858 -427.960536)
					(mid 318.164176 -428.014418)
					(end 318.218058 -428.036736)
				)
				(arc
					(start 319.157858 -428.036736)
					(mid 319.21174 -428.014418)
					(end 319.234058 -427.960536)
				)
				(arc
					(start 319.234058 -425.419012)
					(mid 319.21174 -425.36513)
					(end 319.157858 -425.342812)
				)
				(arc
					(start 318.218058 -425.342812)
					(mid 318.164176 -425.36513)
					(end 318.141858 -425.419012)
				)
				(arc
					(start 318.141858 -426.146468)
					(mid 318.143857 -426.163809)
					(end 318.149732 -426.18025)
				)
				(arc
					(start 318.383158 -426.6565)
					(mid 318.390941 -426.690028)
					(end 318.383158 -426.723556)
				)
				(arc
					(start 318.149732 -427.199806)
					(mid 318.143837 -427.216242)
					(end 318.141858 -427.233588)
				)
			)
		)
	)
	(zone
		(layer "In5.Cu")
		(hatch none 0.5)
		(connect_pads
			(clearance 0)
		)
		(min_thickness 0.25)
		(keepout
			(tracks not_allowed)
			(vias allowed)
			(pads allowed)
			(copperpour not_allowed)
			(footprints allowed)
		)
		(placement
			(enabled no)
			(sheetname "")
		)
		(fill
			(thermal_gap 0.5)
			(thermal_bridge_width 0.5)
			(island_removal_mode 0)
		)
		(polygon
			(pts
				(arc
					(start 406.242266 -431.560732)
					(mid 406.264584 -431.614614)
					(end 406.318466 -431.636932)
				)
				(arc
					(start 407.258266 -431.636932)
					(mid 407.312148 -431.614614)
					(end 407.334466 -431.560732)
				)
				(arc
					(start 407.334466 -429.019208)
					(mid 407.312148 -428.965326)
					(end 407.258266 -428.943008)
				)
				(arc
					(start 406.318466 -428.943008)
					(mid 406.264584 -428.965326)
					(end 406.242266 -429.019208)
				)
			)
		)
	)
	(zone
		(layer "In5.Cu")
		(hatch none 0.5)
		(connect_pads
			(clearance 0)
		)
		(min_thickness 0.25)
		(keepout
			(tracks not_allowed)
			(vias allowed)
			(pads allowed)
			(copperpour not_allowed)
			(footprints allowed)
		)
		(placement
			(enabled no)
			(sheetname "")
		)
		(fill
			(thermal_gap 0.5)
			(thermal_bridge_width 0.5)
			(island_removal_mode 0)
		)
		(polygon
			(pts
				(arc
					(start 404.24227 -432.56073)
					(mid 404.264588 -432.614612)
					(end 404.31847 -432.63693)
				)
				(arc
					(start 405.25827 -432.63693)
					(mid 405.312152 -432.614612)
					(end 405.33447 -432.56073)
				)
				(arc
					(start 405.33447 -430.019206)
					(mid 405.312152 -429.965324)
					(end 405.25827 -429.943006)
				)
				(arc
					(start 404.31847 -429.943006)
					(mid 404.264588 -429.965324)
					(end 404.24227 -430.019206)
				)
			)
		)
	)
	(zone
		(layer "In5.Cu")
		(hatch none 0.5)
		(connect_pads
			(clearance 0)
		)
		(min_thickness 0.25)
		(keepout
			(tracks not_allowed)
			(vias allowed)
			(pads allowed)
			(copperpour not_allowed)
			(footprints allowed)
		)
		(placement
			(enabled no)
			(sheetname "")
		)
		(fill
			(thermal_gap 0.5)
			(thermal_bridge_width 0.5)
			(island_removal_mode 0)
		)
		(polygon
			(pts
				(arc
					(start 406.242012 -438.760616)
					(mid 406.26433 -438.814498)
					(end 406.318212 -438.836816)
				)
				(arc
					(start 407.258012 -438.836816)
					(mid 407.311894 -438.814498)
					(end 407.334212 -438.760616)
				)
				(arc
					(start 407.334212 -436.219092)
					(mid 407.311894 -436.16521)
					(end 407.258012 -436.142892)
				)
				(arc
					(start 406.318212 -436.142892)
					(mid 406.26433 -436.16521)
					(end 406.242012 -436.219092)
				)
			)
		)
	)
	(zone
		(layer "In5.Cu")
		(hatch none 0.5)
		(connect_pads
			(clearance 0)
		)
		(min_thickness 0.25)
		(keepout
			(tracks not_allowed)
			(vias allowed)
			(pads allowed)
			(copperpour not_allowed)
			(footprints allowed)
		)
		(placement
			(enabled no)
			(sheetname "")
		)
		(fill
			(thermal_gap 0.5)
			(thermal_bridge_width 0.5)
			(island_removal_mode 0)
		)
		(polygon
			(pts
				(arc
					(start 391.242042 -428.960534)
					(mid 391.26436 -429.014416)
					(end 391.318242 -429.036734)
				)
				(arc
					(start 392.258042 -429.036734)
					(mid 392.311924 -429.014416)
					(end 392.334242 -428.960534)
				)
				(arc
					(start 392.334242 -426.41901)
					(mid 392.311924 -426.365128)
					(end 392.258042 -426.34281)
				)
				(arc
					(start 391.318242 -426.34281)
					(mid 391.26436 -426.365128)
					(end 391.242042 -426.41901)
				)
				(arc
					(start 391.242042 -427.146466)
					(mid 391.244041 -427.163807)
					(end 391.249916 -427.180248)
				)
				(arc
					(start 391.483342 -427.656498)
					(mid 391.491125 -427.690026)
					(end 391.483342 -427.723554)
				)
				(arc
					(start 391.249916 -428.199804)
					(mid 391.244021 -428.21624)
					(end 391.242042 -428.233586)
				)
			)
		)
	)
	(zone
		(layer "In5.Cu")
		(hatch none 0.5)
		(connect_pads
			(clearance 0)
		)
		(min_thickness 0.25)
		(keepout
			(tracks not_allowed)
			(vias allowed)
			(pads allowed)
			(copperpour not_allowed)
			(footprints allowed)
		)
		(placement
			(enabled no)
			(sheetname "")
		)
		(fill
			(thermal_gap 0.5)
			(thermal_bridge_width 0.5)
			(island_removal_mode 0)
		)
		(polygon
			(pts
				(arc
					(start 393.242038 -435.160674)
					(mid 393.264356 -435.214556)
					(end 393.318238 -435.236874)
				)
				(arc
					(start 394.258038 -435.236874)
					(mid 394.31192 -435.214556)
					(end 394.334238 -435.160674)
				)
				(arc
					(start 394.334238 -432.61915)
					(mid 394.31192 -432.565268)
					(end 394.258038 -432.54295)
				)
				(arc
					(start 393.318238 -432.54295)
					(mid 393.264356 -432.565268)
					(end 393.242038 -432.61915)
				)
			)
		)
	)
	(zone
		(layer "In5.Cu")
		(hatch none 0.5)
		(connect_pads
			(clearance 0)
		)
		(min_thickness 0.25)
		(keepout
			(tracks not_allowed)
			(vias allowed)
			(pads allowed)
			(copperpour not_allowed)
			(footprints allowed)
		)
		(placement
			(enabled no)
			(sheetname "")
		)
		(fill
			(thermal_gap 0.5)
			(thermal_bridge_width 0.5)
			(island_removal_mode 0)
		)
		(polygon
			(pts
				(arc
					(start 389.242046 -438.760616)
					(mid 389.264364 -438.814498)
					(end 389.318246 -438.836816)
				)
				(arc
					(start 390.258046 -438.836816)
					(mid 390.311928 -438.814498)
					(end 390.334246 -438.760616)
				)
				(arc
					(start 390.334246 -436.219092)
					(mid 390.311928 -436.16521)
					(end 390.258046 -436.142892)
				)
				(arc
					(start 389.318246 -436.142892)
					(mid 389.264364 -436.16521)
					(end 389.242046 -436.219092)
				)
			)
		)
	)
	(zone
		(layer "In5.Cu")
		(hatch none 0.5)
		(connect_pads
			(clearance 0)
		)
		(min_thickness 0.25)
		(keepout
			(tracks not_allowed)
			(vias allowed)
			(pads allowed)
			(copperpour not_allowed)
			(footprints allowed)
		)
		(placement
			(enabled no)
			(sheetname "")
		)
		(fill
			(thermal_gap 0.5)
			(thermal_bridge_width 0.5)
			(island_removal_mode 0)
		)
		(polygon
			(pts
				(xy 185.3819 -402.709126) (xy 185.3819 -401.144486) (xy 187.098178 -401.144486) (xy 187.098178 -402.709126)
			)
		)
	)
	(zone
		(layer "In5.Cu")
		(hatch none 0.5)
		(connect_pads
			(clearance 0)
		)
		(min_thickness 0.25)
		(keepout
			(tracks not_allowed)
			(vias allowed)
			(pads allowed)
			(copperpour not_allowed)
			(footprints allowed)
		)
		(placement
			(enabled no)
			(sheetname "")
		)
		(fill
			(thermal_gap 0.5)
			(thermal_bridge_width 0.5)
			(island_removal_mode 0)
		)
		(polygon
			(pts
				(arc
					(start 395.242034 -439.760614)
					(mid 395.264352 -439.814496)
					(end 395.318234 -439.836814)
				)
				(arc
					(start 396.258034 -439.836814)
					(mid 396.311916 -439.814496)
					(end 396.334234 -439.760614)
				)
				(arc
					(start 396.334234 -437.21909)
					(mid 396.311916 -437.165208)
					(end 396.258034 -437.14289)
				)
				(arc
					(start 395.318234 -437.14289)
					(mid 395.264352 -437.165208)
					(end 395.242034 -437.21909)
				)
			)
		)
	)
	(zone
		(layer "In5.Cu")
		(hatch none 0.5)
		(connect_pads
			(clearance 0)
		)
		(min_thickness 0.25)
		(keepout
			(tracks not_allowed)
			(vias allowed)
			(pads allowed)
			(copperpour not_allowed)
			(footprints allowed)
		)
		(placement
			(enabled no)
			(sheetname "")
		)
		(fill
			(thermal_gap 0.5)
			(thermal_bridge_width 0.5)
			(island_removal_mode 0)
		)
		(polygon
			(pts
				(arc
					(start 402.24202 -438.760616)
					(mid 402.264338 -438.814498)
					(end 402.31822 -438.836816)
				)
				(arc
					(start 403.25802 -438.836816)
					(mid 403.311902 -438.814498)
					(end 403.33422 -438.760616)
				)
				(arc
					(start 403.33422 -436.219092)
					(mid 403.311902 -436.16521)
					(end 403.25802 -436.142892)
				)
				(arc
					(start 402.31822 -436.142892)
					(mid 402.264338 -436.16521)
					(end 402.24202 -436.219092)
				)
			)
		)
	)
	(zone
		(layer "In5.Cu")
		(hatch none 0.5)
		(connect_pads
			(clearance 0)
		)
		(min_thickness 0.25)
		(keepout
			(tracks not_allowed)
			(vias allowed)
			(pads allowed)
			(copperpour not_allowed)
			(footprints allowed)
		)
		(placement
			(enabled no)
			(sheetname "")
		)
		(fill
			(thermal_gap 0.5)
			(thermal_bridge_width 0.5)
			(island_removal_mode 0)
		)
		(polygon
			(pts
				(arc
					(start 393.242038 -427.960536)
					(mid 393.264356 -428.014418)
					(end 393.318238 -428.036736)
				)
				(arc
					(start 394.258038 -428.036736)
					(mid 394.31192 -428.014418)
					(end 394.334238 -427.960536)
				)
				(arc
					(start 394.334238 -425.419012)
					(mid 394.31192 -425.36513)
					(end 394.258038 -425.342812)
				)
				(arc
					(start 393.318238 -425.342812)
					(mid 393.264356 -425.36513)
					(end 393.242038 -425.419012)
				)
				(arc
					(start 393.242038 -426.146468)
					(mid 393.244037 -426.163809)
					(end 393.249912 -426.18025)
				)
				(arc
					(start 393.483338 -426.6565)
					(mid 393.491121 -426.690028)
					(end 393.483338 -426.723556)
				)
				(arc
					(start 393.249912 -427.199806)
					(mid 393.244017 -427.216242)
					(end 393.242038 -427.233588)
				)
			)
		)
	)
	(zone
		(layer "In5.Cu")
		(hatch none 0.5)
		(connect_pads
			(clearance 0)
		)
		(min_thickness 0.25)
		(keepout
			(tracks not_allowed)
			(vias allowed)
			(pads allowed)
			(copperpour not_allowed)
			(footprints allowed)
		)
		(placement
			(enabled no)
			(sheetname "")
		)
		(fill
			(thermal_gap 0.5)
			(thermal_bridge_width 0.5)
			(island_removal_mode 0)
		)
		(polygon
			(pts
				(arc
					(start 410.242258 -431.560732)
					(mid 410.264576 -431.614614)
					(end 410.318458 -431.636932)
				)
				(arc
					(start 411.258258 -431.636932)
					(mid 411.31214 -431.614614)
					(end 411.334458 -431.560732)
				)
				(arc
					(start 411.334458 -429.019208)
					(mid 411.31214 -428.965326)
					(end 411.258258 -428.943008)
				)
				(arc
					(start 410.318458 -428.943008)
					(mid 410.264576 -428.965326)
					(end 410.242258 -429.019208)
				)
			)
		)
	)
	(zone
		(layer "In5.Cu")
		(hatch none 0.5)
		(connect_pads
			(clearance 0)
		)
		(min_thickness 0.25)
		(keepout
			(tracks not_allowed)
			(vias allowed)
			(pads allowed)
			(copperpour not_allowed)
			(footprints allowed)
		)
		(placement
			(enabled no)
			(sheetname "")
		)
		(fill
			(thermal_gap 0.5)
			(thermal_bridge_width 0.5)
			(island_removal_mode 0)
		)
		(polygon
			(pts
				(arc
					(start 400.242024 -436.160672)
					(mid 400.264342 -436.214554)
					(end 400.318224 -436.236872)
				)
				(arc
					(start 401.258024 -436.236872)
					(mid 401.311906 -436.214554)
					(end 401.334224 -436.160672)
				)
				(arc
					(start 401.334224 -433.619148)
					(mid 401.311906 -433.565266)
					(end 401.258024 -433.542948)
				)
				(arc
					(start 400.318224 -433.542948)
					(mid 400.264342 -433.565266)
					(end 400.242024 -433.619148)
				)
			)
		)
	)
	(zone
		(layer "In5.Cu")
		(hatch none 0.5)
		(connect_pads
			(clearance 0)
		)
		(min_thickness 0.25)
		(keepout
			(tracks not_allowed)
			(vias allowed)
			(pads allowed)
			(copperpour not_allowed)
			(footprints allowed)
		)
		(placement
			(enabled no)
			(sheetname "")
		)
		(fill
			(thermal_gap 0.5)
			(thermal_bridge_width 0.5)
			(island_removal_mode 0)
		)
		(polygon
			(pts
				(arc
					(start 314.141866 -427.960536)
					(mid 314.164184 -428.014418)
					(end 314.218066 -428.036736)
				)
				(arc
					(start 315.157866 -428.036736)
					(mid 315.211748 -428.014418)
					(end 315.234066 -427.960536)
				)
				(arc
					(start 315.234066 -425.419012)
					(mid 315.211748 -425.36513)
					(end 315.157866 -425.342812)
				)
				(arc
					(start 314.218066 -425.342812)
					(mid 314.164184 -425.36513)
					(end 314.141866 -425.419012)
				)
				(arc
					(start 314.141866 -426.146468)
					(mid 314.143865 -426.163809)
					(end 314.14974 -426.18025)
				)
				(arc
					(start 314.383166 -426.6565)
					(mid 314.390949 -426.690028)
					(end 314.383166 -426.723556)
				)
				(arc
					(start 314.14974 -427.199806)
					(mid 314.143845 -427.216242)
					(end 314.141866 -427.233588)
				)
			)
		)
	)
	(zone
		(layer "In5.Cu")
		(hatch none 0.5)
		(connect_pads
			(clearance 0)
		)
		(min_thickness 0.25)
		(keepout
			(tracks not_allowed)
			(vias allowed)
			(pads allowed)
			(copperpour not_allowed)
			(footprints allowed)
		)
		(placement
			(enabled no)
			(sheetname "")
		)
		(fill
			(thermal_gap 0.5)
			(thermal_bridge_width 0.5)
			(island_removal_mode 0)
		)
		(polygon
			(pts
				(arc
					(start 381.242062 -435.160674)
					(mid 381.26438 -435.214556)
					(end 381.318262 -435.236874)
				)
				(arc
					(start 382.258062 -435.236874)
					(mid 382.311944 -435.214556)
					(end 382.334262 -435.160674)
				)
				(arc
					(start 382.334262 -432.61915)
					(mid 382.311944 -432.565268)
					(end 382.258062 -432.54295)
				)
				(arc
					(start 381.318262 -432.54295)
					(mid 381.26438 -432.565268)
					(end 381.242062 -432.61915)
				)
			)
		)
	)
	(zone
		(layer "In5.Cu")
		(hatch none 0.5)
		(connect_pads
			(clearance 0)
		)
		(min_thickness 0.25)
		(keepout
			(tracks not_allowed)
			(vias allowed)
			(pads allowed)
			(copperpour not_allowed)
			(footprints allowed)
		)
		(placement
			(enabled no)
			(sheetname "")
		)
		(fill
			(thermal_gap 0.5)
			(thermal_bridge_width 0.5)
			(island_removal_mode 0)
		)
		(polygon
			(pts
				(arc
					(start 391.242042 -436.160672)
					(mid 391.26436 -436.214554)
					(end 391.318242 -436.236872)
				)
				(arc
					(start 392.258042 -436.236872)
					(mid 392.311924 -436.214554)
					(end 392.334242 -436.160672)
				)
				(arc
					(start 392.334242 -433.619148)
					(mid 392.311924 -433.565266)
					(end 392.258042 -433.542948)
				)
				(arc
					(start 391.318242 -433.542948)
					(mid 391.26436 -433.565266)
					(end 391.242042 -433.619148)
				)
			)
		)
	)
	(zone
		(layer "In5.Cu")
		(hatch none 0.5)
		(connect_pads
			(clearance 0)
		)
		(min_thickness 0.25)
		(keepout
			(tracks not_allowed)
			(vias allowed)
			(pads allowed)
			(copperpour not_allowed)
			(footprints allowed)
		)
		(placement
			(enabled no)
			(sheetname "")
		)
		(fill
			(thermal_gap 0.5)
			(thermal_bridge_width 0.5)
			(island_removal_mode 0)
		)
		(polygon
			(pts
				(arc
					(start 398.242028 -438.760616)
					(mid 398.264346 -438.814498)
					(end 398.318228 -438.836816)
				)
				(arc
					(start 399.258028 -438.836816)
					(mid 399.31191 -438.814498)
					(end 399.334228 -438.760616)
				)
				(arc
					(start 399.334228 -436.219092)
					(mid 399.31191 -436.16521)
					(end 399.258028 -436.142892)
				)
				(arc
					(start 398.318228 -436.142892)
					(mid 398.264346 -436.16521)
					(end 398.242028 -436.219092)
				)
			)
		)
	)
	(zone
		(layer "In5.Cu")
		(hatch none 0.5)
		(connect_pads
			(clearance 0)
		)
		(min_thickness 0.25)
		(keepout
			(tracks not_allowed)
			(vias allowed)
			(pads allowed)
			(copperpour not_allowed)
			(footprints allowed)
		)
		(placement
			(enabled no)
			(sheetname "")
		)
		(fill
			(thermal_gap 0.5)
			(thermal_bridge_width 0.5)
			(island_removal_mode 0)
		)
		(polygon
			(pts
				(arc
					(start 410.242004 -438.760616)
					(mid 410.264322 -438.814498)
					(end 410.318204 -438.836816)
				)
				(arc
					(start 411.258004 -438.836816)
					(mid 411.311886 -438.814498)
					(end 411.334204 -438.760616)
				)
				(arc
					(start 411.334204 -436.219092)
					(mid 411.311886 -436.16521)
					(end 411.258004 -436.142892)
				)
				(arc
					(start 410.318204 -436.142892)
					(mid 410.264322 -436.16521)
					(end 410.242004 -436.219092)
				)
			)
		)
	)
	(zone
		(layer "In5.Cu")
		(hatch none 0.5)
		(connect_pads
			(clearance 0)
		)
		(min_thickness 0.25)
		(keepout
			(tracks not_allowed)
			(vias allowed)
			(pads allowed)
			(copperpour not_allowed)
			(footprints allowed)
		)
		(placement
			(enabled no)
			(sheetname "")
		)
		(fill
			(thermal_gap 0.5)
			(thermal_bridge_width 0.5)
			(island_removal_mode 0)
		)
		(polygon
			(pts
				(arc
					(start 345.142058 -432.56073)
					(mid 345.164376 -432.614612)
					(end 345.218258 -432.63693)
				)
				(arc
					(start 346.158058 -432.63693)
					(mid 346.21194 -432.614612)
					(end 346.234258 -432.56073)
				)
				(arc
					(start 346.234258 -430.019206)
					(mid 346.21194 -429.965324)
					(end 346.158058 -429.943006)
				)
				(arc
					(start 345.218258 -429.943006)
					(mid 345.164376 -429.965324)
					(end 345.142058 -430.019206)
				)
			)
		)
	)
	(zone
		(layer "In5.Cu")
		(hatch none 0.5)
		(connect_pads
			(clearance 0)
		)
		(min_thickness 0.25)
		(keepout
			(tracks not_allowed)
			(vias allowed)
			(pads allowed)
			(copperpour not_allowed)
			(footprints allowed)
		)
		(placement
			(enabled no)
			(sheetname "")
		)
		(fill
			(thermal_gap 0.5)
			(thermal_bridge_width 0.5)
			(island_removal_mode 0)
		)
		(polygon
			(pts
				(arc
					(start 335.142078 -431.560732)
					(mid 335.164396 -431.614614)
					(end 335.218278 -431.636932)
				)
				(arc
					(start 336.158078 -431.636932)
					(mid 336.21196 -431.614614)
					(end 336.234278 -431.560732)
				)
				(arc
					(start 336.234278 -429.019208)
					(mid 336.21196 -428.965326)
					(end 336.158078 -428.943008)
				)
				(arc
					(start 335.218278 -428.943008)
					(mid 335.164396 -428.965326)
					(end 335.142078 -429.019208)
				)
			)
		)
	)
	(zone
		(layer "In5.Cu")
		(hatch none 0.5)
		(connect_pads
			(clearance 0)
		)
		(min_thickness 0.25)
		(keepout
			(tracks not_allowed)
			(vias allowed)
			(pads allowed)
			(copperpour not_allowed)
			(footprints allowed)
		)
		(placement
			(enabled no)
			(sheetname "")
		)
		(fill
			(thermal_gap 0.5)
			(thermal_bridge_width 0.5)
			(island_removal_mode 0)
		)
		(polygon
			(pts
				(arc
					(start 337.14182 -428.960534)
					(mid 337.164138 -429.014416)
					(end 337.21802 -429.036734)
				)
				(arc
					(start 338.15782 -429.036734)
					(mid 338.211702 -429.014416)
					(end 338.23402 -428.960534)
				)
				(arc
					(start 338.23402 -426.41901)
					(mid 338.211702 -426.365128)
					(end 338.15782 -426.34281)
				)
				(arc
					(start 337.21802 -426.34281)
					(mid 337.164138 -426.365128)
					(end 337.14182 -426.41901)
				)
				(arc
					(start 337.14182 -427.146466)
					(mid 337.143819 -427.163807)
					(end 337.149694 -427.180248)
				)
				(arc
					(start 337.38312 -427.656498)
					(mid 337.390903 -427.690026)
					(end 337.38312 -427.723554)
				)
				(arc
					(start 337.149694 -428.199804)
					(mid 337.143799 -428.21624)
					(end 337.14182 -428.233586)
				)
			)
		)
	)
	(zone
		(layer "In5.Cu")
		(hatch none 0.5)
		(connect_pads
			(clearance 0)
		)
		(min_thickness 0.25)
		(keepout
			(tracks not_allowed)
			(vias allowed)
			(pads allowed)
			(copperpour not_allowed)
			(footprints allowed)
		)
		(placement
			(enabled no)
			(sheetname "")
		)
		(fill
			(thermal_gap 0.5)
			(thermal_bridge_width 0.5)
			(island_removal_mode 0)
		)
		(polygon
			(pts
				(arc
					(start 402.24202 -435.160674)
					(mid 402.264338 -435.214556)
					(end 402.31822 -435.236874)
				)
				(arc
					(start 403.25802 -435.236874)
					(mid 403.311902 -435.214556)
					(end 403.33422 -435.160674)
				)
				(arc
					(start 403.33422 -432.61915)
					(mid 403.311902 -432.565268)
					(end 403.25802 -432.54295)
				)
				(arc
					(start 402.31822 -432.54295)
					(mid 402.264338 -432.565268)
					(end 402.24202 -432.61915)
				)
			)
		)
	)
	(zone
		(layer "In5.Cu")
		(hatch none 0.5)
		(connect_pads
			(clearance 0)
		)
		(min_thickness 0.25)
		(keepout
			(tracks not_allowed)
			(vias allowed)
			(pads allowed)
			(copperpour not_allowed)
			(footprints allowed)
		)
		(placement
			(enabled no)
			(sheetname "")
		)
		(fill
			(thermal_gap 0.5)
			(thermal_bridge_width 0.5)
			(island_removal_mode 0)
		)
		(polygon
			(pts
				(arc
					(start 345.141804 -428.960534)
					(mid 345.164122 -429.014416)
					(end 345.218004 -429.036734)
				)
				(arc
					(start 346.157804 -429.036734)
					(mid 346.211686 -429.014416)
					(end 346.234004 -428.960534)
				)
				(arc
					(start 346.234004 -426.41901)
					(mid 346.211686 -426.365128)
					(end 346.157804 -426.34281)
				)
				(arc
					(start 345.218004 -426.34281)
					(mid 345.164122 -426.365128)
					(end 345.141804 -426.41901)
				)
				(arc
					(start 345.141804 -427.146466)
					(mid 345.143803 -427.163807)
					(end 345.149678 -427.180248)
				)
				(arc
					(start 345.383104 -427.656498)
					(mid 345.390887 -427.690026)
					(end 345.383104 -427.723554)
				)
				(arc
					(start 345.149678 -428.199804)
					(mid 345.143783 -428.21624)
					(end 345.141804 -428.233586)
				)
			)
		)
	)
	(zone
		(layers "In5.Cu" "In7.Cu")
		(hatch none 0.5)
		(connect_pads
			(clearance 0)
		)
		(min_thickness 0.25)
		(keepout
			(tracks not_allowed)
			(vias allowed)
			(pads allowed)
			(copperpour not_allowed)
			(footprints allowed)
		)
		(placement
			(enabled no)
			(sheetname "")
		)
		(fill yes
			(thermal_gap 0.5)
			(thermal_bridge_width 0.5)
			(island_removal_mode 0)
		)
		(polygon
			(pts
				(arc
					(start 150.242016 -431.560478)
					(mid 150.264334 -431.61436)
					(end 150.318216 -431.636678)
				)
				(arc
					(start 151.258016 -431.636678)
					(mid 151.311898 -431.61436)
					(end 151.334216 -431.560478)
				)
				(arc
					(start 151.334216 -429.018954)
					(mid 151.311898 -428.965072)
					(end 151.258016 -428.942754)
				)
				(arc
					(start 150.318216 -428.942754)
					(mid 150.264334 -428.965072)
					(end 150.242016 -429.018954)
				)
			)
		)
	)
	(zone
		(layers "In5.Cu" "In7.Cu")
		(hatch none 0.5)
		(connect_pads
			(clearance 0)
		)
		(min_thickness 0.25)
		(keepout
			(tracks not_allowed)
			(vias allowed)
			(pads allowed)
			(copperpour not_allowed)
			(footprints allowed)
		)
		(placement
			(enabled no)
			(sheetname "")
		)
		(fill yes
			(thermal_gap 0.5)
			(thermal_bridge_width 0.5)
			(island_removal_mode 0)
		)
		(polygon
			(pts
				(arc
					(start 125.241812 -427.960536)
					(mid 125.26413 -428.014418)
					(end 125.318012 -428.036736)
				)
				(arc
					(start 126.257812 -428.036736)
					(mid 126.311694 -428.014418)
					(end 126.334012 -427.960536)
				)
				(arc
					(start 126.334012 -425.419012)
					(mid 126.311694 -425.36513)
					(end 126.257812 -425.342812)
				)
				(arc
					(start 125.318012 -425.342812)
					(mid 125.26413 -425.36513)
					(end 125.241812 -425.419012)
				)
				(arc
					(start 125.241812 -426.146468)
					(mid 125.243811 -426.163809)
					(end 125.249686 -426.18025)
				)
				(arc
					(start 125.483112 -426.6565)
					(mid 125.490895 -426.690028)
					(end 125.483112 -426.723556)
				)
				(arc
					(start 125.249686 -427.199806)
					(mid 125.243791 -427.216242)
					(end 125.241812 -427.233588)
				)
			)
		)
	)
	(zone
		(layers "In5.Cu" "In7.Cu")
		(hatch none 0.5)
		(connect_pads
			(clearance 0)
		)
		(min_thickness 0.25)
		(keepout
			(tracks not_allowed)
			(vias allowed)
			(pads allowed)
			(copperpour not_allowed)
			(footprints allowed)
		)
		(placement
			(enabled no)
			(sheetname "")
		)
		(fill yes
			(thermal_gap 0.5)
			(thermal_bridge_width 0.5)
			(island_removal_mode 0)
		)
		(polygon
			(pts
				(arc
					(start 68.14185 -428.960534)
					(mid 68.164168 -429.014416)
					(end 68.21805 -429.036734)
				)
				(arc
					(start 69.15785 -429.036734)
					(mid 69.211732 -429.014416)
					(end 69.23405 -428.960534)
				)
				(arc
					(start 69.23405 -426.41901)
					(mid 69.211732 -426.365128)
					(end 69.15785 -426.34281)
				)
				(arc
					(start 68.21805 -426.34281)
					(mid 68.164168 -426.365128)
					(end 68.14185 -426.41901)
				)
				(arc
					(start 68.14185 -427.146466)
					(mid 68.143849 -427.163807)
					(end 68.149724 -427.180248)
				)
				(arc
					(start 68.38315 -427.656498)
					(mid 68.390933 -427.690026)
					(end 68.38315 -427.723554)
				)
				(arc
					(start 68.149724 -428.199804)
					(mid 68.143829 -428.21624)
					(end 68.14185 -428.233586)
				)
			)
		)
	)
	(zone
		(layers "In5.Cu" "In7.Cu")
		(hatch none 0.5)
		(connect_pads
			(clearance 0)
		)
		(min_thickness 0.25)
		(keepout
			(tracks not_allowed)
			(vias allowed)
			(pads allowed)
			(copperpour not_allowed)
			(footprints allowed)
		)
		(placement
			(enabled no)
			(sheetname "")
		)
		(fill yes
			(thermal_gap 0.5)
			(thermal_bridge_width 0.5)
			(island_removal_mode 0)
		)
		(polygon
			(pts
				(arc
					(start 341.141812 -428.96028)
					(mid 341.16413 -429.014162)
					(end 341.218012 -429.03648)
				)
				(arc
					(start 342.157812 -429.03648)
					(mid 342.211694 -429.014162)
					(end 342.234012 -428.96028)
				)
				(arc
					(start 342.234012 -426.418756)
					(mid 342.211694 -426.364874)
					(end 342.157812 -426.342556)
				)
				(arc
					(start 341.218012 -426.342556)
					(mid 341.16413 -426.364874)
					(end 341.141812 -426.418756)
				)
				(arc
					(start 341.141812 -427.146212)
					(mid 341.143811 -427.163553)
					(end 341.149686 -427.179994)
				)
				(arc
					(start 341.383112 -427.656244)
					(mid 341.390895 -427.689772)
					(end 341.383112 -427.7233)
				)
				(arc
					(start 341.149686 -428.19955)
					(mid 341.143791 -428.215986)
					(end 341.141812 -428.233332)
				)
			)
		)
	)
	(zone
		(layers "In5.Cu" "In7.Cu")
		(hatch none 0.5)
		(connect_pads
			(clearance 0)
		)
		(min_thickness 0.25)
		(keepout
			(tracks not_allowed)
			(vias allowed)
			(pads allowed)
			(copperpour not_allowed)
			(footprints allowed)
		)
		(placement
			(enabled no)
			(sheetname "")
		)
		(fill yes
			(thermal_gap 0.5)
			(thermal_bridge_width 0.5)
			(island_removal_mode 0)
		)
		(polygon
			(pts
				(arc
					(start 343.141808 -427.960536)
					(mid 343.164126 -428.014418)
					(end 343.218008 -428.036736)
				)
				(arc
					(start 344.157808 -428.036736)
					(mid 344.21169 -428.014418)
					(end 344.234008 -427.960536)
				)
				(arc
					(start 344.234008 -425.419012)
					(mid 344.21169 -425.36513)
					(end 344.157808 -425.342812)
				)
				(arc
					(start 343.218008 -425.342812)
					(mid 343.164126 -425.36513)
					(end 343.141808 -425.419012)
				)
				(arc
					(start 343.141808 -426.146468)
					(mid 343.143807 -426.163809)
					(end 343.149682 -426.18025)
				)
				(arc
					(start 343.383108 -426.6565)
					(mid 343.390891 -426.690028)
					(end 343.383108 -426.723556)
				)
				(arc
					(start 343.149682 -427.199806)
					(mid 343.143787 -427.216242)
					(end 343.141808 -427.233588)
				)
			)
		)
	)
	(zone
		(layers "In5.Cu" "In7.Cu")
		(hatch none 0.5)
		(connect_pads
			(clearance 0)
		)
		(min_thickness 0.25)
		(keepout
			(tracks not_allowed)
			(vias allowed)
			(pads allowed)
			(copperpour not_allowed)
			(footprints allowed)
		)
		(placement
			(enabled no)
			(sheetname "")
		)
		(fill yes
			(thermal_gap 0.5)
			(thermal_bridge_width 0.5)
			(island_removal_mode 0)
		)
		(polygon
			(pts
				(arc
					(start 83.14182 -427.960536)
					(mid 83.164138 -428.014418)
					(end 83.21802 -428.036736)
				)
				(arc
					(start 84.15782 -428.036736)
					(mid 84.211702 -428.014418)
					(end 84.23402 -427.960536)
				)
				(arc
					(start 84.23402 -425.419012)
					(mid 84.211702 -425.36513)
					(end 84.15782 -425.342812)
				)
				(arc
					(start 83.21802 -425.342812)
					(mid 83.164138 -425.36513)
					(end 83.14182 -425.419012)
				)
				(arc
					(start 83.14182 -426.146468)
					(mid 83.143819 -426.163809)
					(end 83.149694 -426.18025)
				)
				(arc
					(start 83.38312 -426.6565)
					(mid 83.390903 -426.690028)
					(end 83.38312 -426.723556)
				)
				(arc
					(start 83.149694 -427.199806)
					(mid 83.143799 -427.216242)
					(end 83.14182 -427.233588)
				)
			)
		)
	)
	(zone
		(layers "In5.Cu" "In7.Cu")
		(hatch none 0.5)
		(connect_pads
			(clearance 0)
		)
		(min_thickness 0.25)
		(keepout
			(tracks not_allowed)
			(vias allowed)
			(pads allowed)
			(copperpour not_allowed)
			(footprints allowed)
		)
		(placement
			(enabled no)
			(sheetname "")
		)
		(fill yes
			(thermal_gap 0.5)
			(thermal_bridge_width 0.5)
			(island_removal_mode 0)
		)
		(polygon
			(pts
				(arc
					(start 77.141832 -428.960534)
					(mid 77.16415 -429.014416)
					(end 77.218032 -429.036734)
				)
				(arc
					(start 78.157832 -429.036734)
					(mid 78.211714 -429.014416)
					(end 78.234032 -428.960534)
				)
				(arc
					(start 78.234032 -426.41901)
					(mid 78.211714 -426.365128)
					(end 78.157832 -426.34281)
				)
				(arc
					(start 77.218032 -426.34281)
					(mid 77.16415 -426.365128)
					(end 77.141832 -426.41901)
				)
				(arc
					(start 77.141832 -427.146466)
					(mid 77.143831 -427.163807)
					(end 77.149706 -427.180248)
				)
				(arc
					(start 77.383132 -427.656498)
					(mid 77.390915 -427.690026)
					(end 77.383132 -427.723554)
				)
				(arc
					(start 77.149706 -428.199804)
					(mid 77.143811 -428.21624)
					(end 77.141832 -428.233586)
				)
			)
		)
	)
	(zone
		(layers "In5.Cu" "In7.Cu")
		(hatch none 0.5)
		(connect_pads
			(clearance 0)
		)
		(min_thickness 0.25)
		(keepout
			(tracks not_allowed)
			(vias allowed)
			(pads allowed)
			(copperpour not_allowed)
			(footprints allowed)
		)
		(placement
			(enabled no)
			(sheetname "")
		)
		(fill yes
			(thermal_gap 0.5)
			(thermal_bridge_width 0.5)
			(island_removal_mode 0)
		)
		(polygon
			(pts
				(arc
					(start 410.242004 -427.960536)
					(mid 410.264322 -428.014418)
					(end 410.318204 -428.036736)
				)
				(arc
					(start 411.258004 -428.036736)
					(mid 411.311886 -428.014418)
					(end 411.334204 -427.960536)
				)
				(arc
					(start 411.334204 -425.419012)
					(mid 411.311886 -425.36513)
					(end 411.258004 -425.342812)
				)
				(arc
					(start 410.318204 -425.342812)
					(mid 410.264322 -425.36513)
					(end 410.242004 -425.419012)
				)
				(arc
					(start 410.242004 -426.146468)
					(mid 410.244003 -426.163809)
					(end 410.249878 -426.18025)
				)
				(arc
					(start 410.483304 -426.6565)
					(mid 410.491087 -426.690028)
					(end 410.483304 -426.723556)
				)
				(arc
					(start 410.249878 -427.199806)
					(mid 410.243983 -427.216242)
					(end 410.242004 -427.233588)
				)
			)
		)
	)
	(zone
		(layers "In5.Cu" "In7.Cu")
		(hatch none 0.5)
		(connect_pads
			(clearance 0)
		)
		(min_thickness 0.25)
		(keepout
			(tracks not_allowed)
			(vias allowed)
			(pads allowed)
			(copperpour not_allowed)
			(footprints allowed)
		)
		(placement
			(enabled no)
			(sheetname "")
		)
		(fill yes
			(thermal_gap 0.5)
			(thermal_bridge_width 0.5)
			(island_removal_mode 0)
		)
		(polygon
			(pts
				(arc
					(start 64.141858 -428.960534)
					(mid 64.164176 -429.014416)
					(end 64.218058 -429.036734)
				)
				(arc
					(start 65.157858 -429.036734)
					(mid 65.21174 -429.014416)
					(end 65.234058 -428.960534)
				)
				(arc
					(start 65.234058 -426.41901)
					(mid 65.21174 -426.365128)
					(end 65.157858 -426.34281)
				)
				(arc
					(start 64.218058 -426.34281)
					(mid 64.164176 -426.365128)
					(end 64.141858 -426.41901)
				)
				(arc
					(start 64.141858 -427.146466)
					(mid 64.143857 -427.163807)
					(end 64.149732 -427.180248)
				)
				(arc
					(start 64.383158 -427.656498)
					(mid 64.390941 -427.690026)
					(end 64.383158 -427.723554)
				)
				(arc
					(start 64.149732 -428.199804)
					(mid 64.143837 -428.21624)
					(end 64.141858 -428.233586)
				)
			)
		)
	)
	(zone
		(layers "In5.Cu" "In7.Cu")
		(hatch none 0.5)
		(connect_pads
			(clearance 0)
		)
		(min_thickness 0.25)
		(keepout
			(tracks not_allowed)
			(vias allowed)
			(pads allowed)
			(copperpour not_allowed)
			(footprints allowed)
		)
		(placement
			(enabled no)
			(sheetname "")
		)
		(fill yes
			(thermal_gap 0.5)
			(thermal_bridge_width 0.5)
			(island_removal_mode 0)
		)
		(polygon
			(pts
				(arc
					(start 66.141854 -427.960536)
					(mid 66.164172 -428.014418)
					(end 66.218054 -428.036736)
				)
				(arc
					(start 67.157854 -428.036736)
					(mid 67.211736 -428.014418)
					(end 67.234054 -427.960536)
				)
				(arc
					(start 67.234054 -425.419012)
					(mid 67.211736 -425.36513)
					(end 67.157854 -425.342812)
				)
				(arc
					(start 66.218054 -425.342812)
					(mid 66.164172 -425.36513)
					(end 66.141854 -425.419012)
				)
				(arc
					(start 66.141854 -426.146468)
					(mid 66.143853 -426.163809)
					(end 66.149728 -426.18025)
				)
				(arc
					(start 66.383154 -426.6565)
					(mid 66.390937 -426.690028)
					(end 66.383154 -426.723556)
				)
				(arc
					(start 66.149728 -427.199806)
					(mid 66.143833 -427.216242)
					(end 66.141854 -427.233588)
				)
			)
		)
	)
	(zone
		(layers "In5.Cu" "In7.Cu")
		(hatch none 0.5)
		(connect_pads
			(clearance 0)
		)
		(min_thickness 0.25)
		(keepout
			(tracks not_allowed)
			(vias allowed)
			(pads allowed)
			(copperpour not_allowed)
			(footprints allowed)
		)
		(placement
			(enabled no)
			(sheetname "")
		)
		(fill yes
			(thermal_gap 0.5)
			(thermal_bridge_width 0.5)
			(island_removal_mode 0)
		)
		(polygon
			(pts
				(arc
					(start 154.242008 -427.960536)
					(mid 154.264326 -428.014418)
					(end 154.318208 -428.036736)
				)
				(arc
					(start 155.258008 -428.036736)
					(mid 155.31189 -428.014418)
					(end 155.334208 -427.960536)
				)
				(arc
					(start 155.334208 -425.419012)
					(mid 155.31189 -425.36513)
					(end 155.258008 -425.342812)
				)
				(arc
					(start 154.318208 -425.342812)
					(mid 154.264326 -425.36513)
					(end 154.242008 -425.419012)
				)
				(arc
					(start 154.242008 -426.146468)
					(mid 154.244007 -426.163809)
					(end 154.249882 -426.18025)
				)
				(arc
					(start 154.483308 -426.6565)
					(mid 154.491091 -426.690028)
					(end 154.483308 -426.723556)
				)
				(arc
					(start 154.249882 -427.199806)
					(mid 154.243987 -427.216242)
					(end 154.242008 -427.233588)
				)
			)
		)
	)
	(zone
		(layers "In5.Cu" "In7.Cu")
		(hatch none 0.5)
		(connect_pads
			(clearance 0)
		)
		(min_thickness 0.25)
		(keepout
			(tracks not_allowed)
			(vias allowed)
			(pads allowed)
			(copperpour not_allowed)
			(footprints allowed)
		)
		(placement
			(enabled no)
			(sheetname "")
		)
		(fill yes
			(thermal_gap 0.5)
			(thermal_bridge_width 0.5)
			(island_removal_mode 0)
		)
		(polygon
			(pts
				(arc
					(start 127.241808 -428.96028)
					(mid 127.264126 -429.014162)
					(end 127.318008 -429.03648)
				)
				(arc
					(start 128.257808 -429.03648)
					(mid 128.31169 -429.014162)
					(end 128.334008 -428.96028)
				)
				(arc
					(start 128.334008 -426.418756)
					(mid 128.31169 -426.364874)
					(end 128.257808 -426.342556)
				)
				(arc
					(start 127.318008 -426.342556)
					(mid 127.264126 -426.364874)
					(end 127.241808 -426.418756)
				)
				(arc
					(start 127.241808 -427.146212)
					(mid 127.243807 -427.163553)
					(end 127.249682 -427.179994)
				)
				(arc
					(start 127.483108 -427.656244)
					(mid 127.490891 -427.689772)
					(end 127.483108 -427.7233)
				)
				(arc
					(start 127.249682 -428.19955)
					(mid 127.243787 -428.215986)
					(end 127.241808 -428.233332)
				)
			)
		)
	)
	(zone
		(layers "In5.Cu" "In7.Cu")
		(hatch none 0.5)
		(connect_pads
			(clearance 0)
		)
		(min_thickness 0.25)
		(keepout
			(tracks not_allowed)
			(vias allowed)
			(pads allowed)
			(copperpour not_allowed)
			(footprints allowed)
		)
		(placement
			(enabled no)
			(sheetname "")
		)
		(fill yes
			(thermal_gap 0.5)
			(thermal_bridge_width 0.5)
			(island_removal_mode 0)
		)
		(polygon
			(pts
				(arc
					(start 331.141832 -427.960536)
					(mid 331.16415 -428.014418)
					(end 331.218032 -428.036736)
				)
				(arc
					(start 332.157832 -428.036736)
					(mid 332.211714 -428.014418)
					(end 332.234032 -427.960536)
				)
				(arc
					(start 332.234032 -425.419012)
					(mid 332.211714 -425.36513)
					(end 332.157832 -425.342812)
				)
				(arc
					(start 331.218032 -425.342812)
					(mid 331.16415 -425.36513)
					(end 331.141832 -425.419012)
				)
				(arc
					(start 331.141832 -426.146468)
					(mid 331.143831 -426.163809)
					(end 331.149706 -426.18025)
				)
				(arc
					(start 331.383132 -426.6565)
					(mid 331.390915 -426.690028)
					(end 331.383132 -426.723556)
				)
				(arc
					(start 331.149706 -427.199806)
					(mid 331.143811 -427.216242)
					(end 331.141832 -427.233588)
				)
			)
		)
	)
	(zone
		(layers "In5.Cu" "In7.Cu")
		(hatch none 0.5)
		(connect_pads
			(clearance 0)
		)
		(min_thickness 0.25)
		(keepout
			(tracks not_allowed)
			(vias allowed)
			(pads allowed)
			(copperpour not_allowed)
			(footprints allowed)
		)
		(placement
			(enabled no)
			(sheetname "")
		)
		(fill yes
			(thermal_gap 0.5)
			(thermal_bridge_width 0.5)
			(island_removal_mode 0)
		)
		(polygon
			(pts
				(arc
					(start 70.141846 -427.960536)
					(mid 70.164164 -428.014418)
					(end 70.218046 -428.036736)
				)
				(arc
					(start 71.157846 -428.036736)
					(mid 71.211728 -428.014418)
					(end 71.234046 -427.960536)
				)
				(arc
					(start 71.234046 -425.419012)
					(mid 71.211728 -425.36513)
					(end 71.157846 -425.342812)
				)
				(arc
					(start 70.218046 -425.342812)
					(mid 70.164164 -425.36513)
					(end 70.141846 -425.419012)
				)
				(arc
					(start 70.141846 -426.146468)
					(mid 70.143845 -426.163809)
					(end 70.14972 -426.18025)
				)
				(arc
					(start 70.383146 -426.6565)
					(mid 70.390929 -426.690028)
					(end 70.383146 -426.723556)
				)
				(arc
					(start 70.14972 -427.199806)
					(mid 70.143825 -427.216242)
					(end 70.141846 -427.233588)
				)
			)
		)
	)
	(zone
		(layers "In5.Cu" "In7.Cu")
		(hatch none 0.5)
		(connect_pads
			(clearance 0)
		)
		(min_thickness 0.25)
		(keepout
			(tracks not_allowed)
			(vias allowed)
			(pads allowed)
			(copperpour not_allowed)
			(footprints allowed)
		)
		(placement
			(enabled no)
			(sheetname "")
		)
		(fill yes
			(thermal_gap 0.5)
			(thermal_bridge_width 0.5)
			(island_removal_mode 0)
		)
		(polygon
			(pts
				(arc
					(start 408.242008 -428.96028)
					(mid 408.264326 -429.014162)
					(end 408.318208 -429.03648)
				)
				(arc
					(start 409.258008 -429.03648)
					(mid 409.31189 -429.014162)
					(end 409.334208 -428.96028)
				)
				(arc
					(start 409.334208 -426.418756)
					(mid 409.31189 -426.364874)
					(end 409.258008 -426.342556)
				)
				(arc
					(start 408.318208 -426.342556)
					(mid 408.264326 -426.364874)
					(end 408.242008 -426.418756)
				)
				(arc
					(start 408.242008 -427.146212)
					(mid 408.244007 -427.163553)
					(end 408.249882 -427.179994)
				)
				(arc
					(start 408.483308 -427.656244)
					(mid 408.491091 -427.689772)
					(end 408.483308 -427.7233)
				)
				(arc
					(start 408.249882 -428.19955)
					(mid 408.243987 -428.215986)
					(end 408.242008 -428.233332)
				)
			)
		)
	)
	(zone
		(layers "In5.Cu" "In7.Cu")
		(hatch none 0.5)
		(connect_pads
			(clearance 0)
		)
		(min_thickness 0.25)
		(keepout
			(tracks not_allowed)
			(vias allowed)
			(pads allowed)
			(copperpour not_allowed)
			(footprints allowed)
		)
		(placement
			(enabled no)
			(sheetname "")
		)
		(fill yes
			(thermal_gap 0.5)
			(thermal_bridge_width 0.5)
			(island_removal_mode 0)
		)
		(polygon
			(pts
				(arc
					(start 156.242004 -428.96028)
					(mid 156.264322 -429.014162)
					(end 156.318204 -429.03648)
				)
				(arc
					(start 157.258004 -429.03648)
					(mid 157.311886 -429.014162)
					(end 157.334204 -428.96028)
				)
				(arc
					(start 157.334204 -426.418756)
					(mid 157.311886 -426.364874)
					(end 157.258004 -426.342556)
				)
				(arc
					(start 156.318204 -426.342556)
					(mid 156.264322 -426.364874)
					(end 156.242004 -426.418756)
				)
				(arc
					(start 156.242004 -427.146212)
					(mid 156.244003 -427.163553)
					(end 156.249878 -427.179994)
				)
				(arc
					(start 156.483304 -427.656244)
					(mid 156.491087 -427.689772)
					(end 156.483304 -427.7233)
				)
				(arc
					(start 156.249878 -428.19955)
					(mid 156.243983 -428.215986)
					(end 156.242004 -428.233332)
				)
			)
		)
	)
	(zone
		(layers "In5.Cu" "In7.Cu")
		(hatch none 0.5)
		(connect_pads
			(clearance 0)
		)
		(min_thickness 0.25)
		(keepout
			(tracks not_allowed)
			(vias allowed)
			(pads allowed)
			(copperpour not_allowed)
			(footprints allowed)
		)
		(placement
			(enabled no)
			(sheetname "")
		)
		(fill yes
			(thermal_gap 0.5)
			(thermal_bridge_width 0.5)
			(island_removal_mode 0)
		)
		(polygon
			(pts
				(arc
					(start 72.141842 -428.960534)
					(mid 72.16416 -429.014416)
					(end 72.218042 -429.036734)
				)
				(arc
					(start 73.157842 -429.036734)
					(mid 73.211724 -429.014416)
					(end 73.234042 -428.960534)
				)
				(arc
					(start 73.234042 -426.41901)
					(mid 73.211724 -426.365128)
					(end 73.157842 -426.34281)
				)
				(arc
					(start 72.218042 -426.34281)
					(mid 72.16416 -426.365128)
					(end 72.141842 -426.41901)
				)
				(arc
					(start 72.141842 -427.146466)
					(mid 72.143841 -427.163807)
					(end 72.149716 -427.180248)
				)
				(arc
					(start 72.383142 -427.656498)
					(mid 72.390925 -427.690026)
					(end 72.383142 -427.723554)
				)
				(arc
					(start 72.149716 -428.199804)
					(mid 72.143821 -428.21624)
					(end 72.141842 -428.233586)
				)
			)
		)
	)
	(zone
		(layers "In5.Cu" "In7.Cu")
		(hatch none 0.5)
		(connect_pads
			(clearance 0)
		)
		(min_thickness 0.25)
		(keepout
			(tracks not_allowed)
			(vias allowed)
			(pads allowed)
			(copperpour not_allowed)
			(footprints allowed)
		)
		(placement
			(enabled no)
			(sheetname "")
		)
		(fill yes
			(thermal_gap 0.5)
			(thermal_bridge_width 0.5)
			(island_removal_mode 0)
		)
		(polygon
			(pts
				(arc
					(start 142.242032 -427.960536)
					(mid 142.26435 -428.014418)
					(end 142.318232 -428.036736)
				)
				(arc
					(start 143.258032 -428.036736)
					(mid 143.311914 -428.014418)
					(end 143.334232 -427.960536)
				)
				(arc
					(start 143.334232 -425.419012)
					(mid 143.311914 -425.36513)
					(end 143.258032 -425.342812)
				)
				(arc
					(start 142.318232 -425.342812)
					(mid 142.26435 -425.36513)
					(end 142.242032 -425.419012)
				)
				(arc
					(start 142.242032 -426.146468)
					(mid 142.244031 -426.163809)
					(end 142.249906 -426.18025)
				)
				(arc
					(start 142.483332 -426.6565)
					(mid 142.491115 -426.690028)
					(end 142.483332 -426.723556)
				)
				(arc
					(start 142.249906 -427.199806)
					(mid 142.244011 -427.216242)
					(end 142.242032 -427.233588)
				)
			)
		)
	)
	(zone
		(layers "In5.Cu" "In7.Cu")
		(hatch none 0.5)
		(connect_pads
			(clearance 0)
		)
		(min_thickness 0.25)
		(keepout
			(tracks not_allowed)
			(vias allowed)
			(pads allowed)
			(copperpour not_allowed)
			(footprints allowed)
		)
		(placement
			(enabled no)
			(sheetname "")
		)
		(fill yes
			(thermal_gap 0.5)
			(thermal_bridge_width 0.5)
			(island_removal_mode 0)
		)
		(polygon
			(pts
				(arc
					(start 62.141862 -427.960536)
					(mid 62.16418 -428.014418)
					(end 62.218062 -428.036736)
				)
				(arc
					(start 63.157862 -428.036736)
					(mid 63.211744 -428.014418)
					(end 63.234062 -427.960536)
				)
				(arc
					(start 63.234062 -425.419012)
					(mid 63.211744 -425.36513)
					(end 63.157862 -425.342812)
				)
				(arc
					(start 62.218062 -425.342812)
					(mid 62.16418 -425.36513)
					(end 62.141862 -425.419012)
				)
				(arc
					(start 62.141862 -426.146468)
					(mid 62.143861 -426.163809)
					(end 62.149736 -426.18025)
				)
				(arc
					(start 62.383162 -426.6565)
					(mid 62.390945 -426.690028)
					(end 62.383162 -426.723556)
				)
				(arc
					(start 62.149736 -427.199806)
					(mid 62.143841 -427.216242)
					(end 62.141862 -427.233588)
				)
			)
		)
	)
	(zone
		(layers "In5.Cu" "In7.Cu")
		(hatch none 0.5)
		(connect_pads
			(clearance 0)
		)
		(min_thickness 0.25)
		(keepout
			(tracks not_allowed)
			(vias allowed)
			(pads allowed)
			(copperpour not_allowed)
			(footprints allowed)
		)
		(placement
			(enabled no)
			(sheetname "")
		)
		(fill yes
			(thermal_gap 0.5)
			(thermal_bridge_width 0.5)
			(island_removal_mode 0)
		)
		(polygon
			(pts
				(arc
					(start 139.241784 -428.96028)
					(mid 139.264102 -429.014162)
					(end 139.317984 -429.03648)
				)
				(arc
					(start 140.257784 -429.03648)
					(mid 140.311666 -429.014162)
					(end 140.333984 -428.96028)
				)
				(arc
					(start 140.333984 -426.418756)
					(mid 140.311666 -426.364874)
					(end 140.257784 -426.342556)
				)
				(arc
					(start 139.317984 -426.342556)
					(mid 139.264102 -426.364874)
					(end 139.241784 -426.418756)
				)
				(arc
					(start 139.241784 -427.146212)
					(mid 139.243783 -427.163553)
					(end 139.249658 -427.179994)
				)
				(arc
					(start 139.483084 -427.656244)
					(mid 139.490867 -427.689772)
					(end 139.483084 -427.7233)
				)
				(arc
					(start 139.249658 -428.19955)
					(mid 139.243763 -428.215986)
					(end 139.241784 -428.233332)
				)
			)
		)
	)
	(zone
		(layers "In5.Cu" "In7.Cu")
		(hatch none 0.5)
		(connect_pads
			(clearance 0)
		)
		(min_thickness 0.25)
		(keepout
			(tracks not_allowed)
			(vias allowed)
			(pads allowed)
			(copperpour not_allowed)
			(footprints allowed)
		)
		(placement
			(enabled no)
			(sheetname "")
		)
		(fill yes
			(thermal_gap 0.5)
			(thermal_bridge_width 0.5)
			(island_removal_mode 0)
		)
		(polygon
			(pts
				(arc
					(start 144.242028 -428.96028)
					(mid 144.264346 -429.014162)
					(end 144.318228 -429.03648)
				)
				(arc
					(start 145.258028 -429.03648)
					(mid 145.31191 -429.014162)
					(end 145.334228 -428.96028)
				)
				(arc
					(start 145.334228 -426.418756)
					(mid 145.31191 -426.364874)
					(end 145.258028 -426.342556)
				)
				(arc
					(start 144.318228 -426.342556)
					(mid 144.264346 -426.364874)
					(end 144.242028 -426.418756)
				)
				(arc
					(start 144.242028 -427.146212)
					(mid 144.244027 -427.163553)
					(end 144.249902 -427.179994)
				)
				(arc
					(start 144.483328 -427.656244)
					(mid 144.491111 -427.689772)
					(end 144.483328 -427.7233)
				)
				(arc
					(start 144.249902 -428.19955)
					(mid 144.244007 -428.215986)
					(end 144.242028 -428.233332)
				)
			)
		)
	)
	(zone
		(layers "In5.Cu" "In7.Cu")
		(hatch none 0.5)
		(connect_pads
			(clearance 0)
		)
		(min_thickness 0.25)
		(keepout
			(tracks not_allowed)
			(vias allowed)
			(pads allowed)
			(copperpour not_allowed)
			(footprints allowed)
		)
		(placement
			(enabled no)
			(sheetname "")
		)
		(fill yes
			(thermal_gap 0.5)
			(thermal_bridge_width 0.5)
			(island_removal_mode 0)
		)
		(polygon
			(pts
				(arc
					(start 75.141836 -427.960536)
					(mid 75.164154 -428.014418)
					(end 75.218036 -428.036736)
				)
				(arc
					(start 76.157836 -428.036736)
					(mid 76.211718 -428.014418)
					(end 76.234036 -427.960536)
				)
				(arc
					(start 76.234036 -425.419012)
					(mid 76.211718 -425.36513)
					(end 76.157836 -425.342812)
				)
				(arc
					(start 75.218036 -425.342812)
					(mid 75.164154 -425.36513)
					(end 75.141836 -425.419012)
				)
				(arc
					(start 75.141836 -426.146468)
					(mid 75.143835 -426.163809)
					(end 75.14971 -426.18025)
				)
				(arc
					(start 75.383136 -426.6565)
					(mid 75.390919 -426.690028)
					(end 75.383136 -426.723556)
				)
				(arc
					(start 75.14971 -427.199806)
					(mid 75.143815 -427.216242)
					(end 75.141836 -427.233588)
				)
			)
		)
	)
	(zone
		(layers "In5.Cu" "In7.Cu")
		(hatch none 0.5)
		(connect_pads
			(clearance 0)
		)
		(min_thickness 0.25)
		(keepout
			(tracks not_allowed)
			(vias allowed)
			(pads allowed)
			(copperpour not_allowed)
			(footprints allowed)
		)
		(placement
			(enabled no)
			(sheetname "")
		)
		(fill yes
			(thermal_gap 0.5)
			(thermal_bridge_width 0.5)
			(island_removal_mode 0)
		)
		(polygon
			(pts
				(arc
					(start 150.242016 -427.960536)
					(mid 150.264334 -428.014418)
					(end 150.318216 -428.036736)
				)
				(arc
					(start 151.258016 -428.036736)
					(mid 151.311898 -428.014418)
					(end 151.334216 -427.960536)
				)
				(arc
					(start 151.334216 -425.419012)
					(mid 151.311898 -425.36513)
					(end 151.258016 -425.342812)
				)
				(arc
					(start 150.318216 -425.342812)
					(mid 150.264334 -425.36513)
					(end 150.242016 -425.419012)
				)
				(arc
					(start 150.242016 -426.146468)
					(mid 150.244015 -426.163809)
					(end 150.24989 -426.18025)
				)
				(arc
					(start 150.483316 -426.6565)
					(mid 150.491099 -426.690028)
					(end 150.483316 -426.723556)
				)
				(arc
					(start 150.24989 -427.199806)
					(mid 150.243995 -427.216242)
					(end 150.242016 -427.233588)
				)
			)
		)
	)
	(zone
		(layers "In5.Cu" "In7.Cu")
		(hatch none 0.5)
		(connect_pads
			(clearance 0)
		)
		(min_thickness 0.25)
		(keepout
			(tracks not_allowed)
			(vias allowed)
			(pads allowed)
			(copperpour not_allowed)
			(footprints allowed)
		)
		(placement
			(enabled no)
			(sheetname "")
		)
		(fill yes
			(thermal_gap 0.5)
			(thermal_bridge_width 0.5)
			(island_removal_mode 0)
		)
		(polygon
			(pts
				(arc
					(start 152.242012 -428.96028)
					(mid 152.26433 -429.014162)
					(end 152.318212 -429.03648)
				)
				(arc
					(start 153.258012 -429.03648)
					(mid 153.311894 -429.014162)
					(end 153.334212 -428.96028)
				)
				(arc
					(start 153.334212 -426.418756)
					(mid 153.311894 -426.364874)
					(end 153.258012 -426.342556)
				)
				(arc
					(start 152.318212 -426.342556)
					(mid 152.26433 -426.364874)
					(end 152.242012 -426.418756)
				)
				(arc
					(start 152.242012 -427.146212)
					(mid 152.244011 -427.163553)
					(end 152.249886 -427.179994)
				)
				(arc
					(start 152.483312 -427.656244)
					(mid 152.491095 -427.689772)
					(end 152.483312 -427.7233)
				)
				(arc
					(start 152.249886 -428.19955)
					(mid 152.243991 -428.215986)
					(end 152.242012 -428.233332)
				)
			)
		)
	)
	(zone
		(layers "In5.Cu" "In7.Cu")
		(hatch none 0.5)
		(connect_pads
			(clearance 0)
		)
		(min_thickness 0.25)
		(keepout
			(tracks not_allowed)
			(vias allowed)
			(pads allowed)
			(copperpour not_allowed)
			(footprints allowed)
		)
		(placement
			(enabled no)
			(sheetname "")
		)
		(fill yes
			(thermal_gap 0.5)
			(thermal_bridge_width 0.5)
			(island_removal_mode 0)
		)
		(polygon
			(pts
				(arc
					(start 60.141866 -428.960534)
					(mid 60.164184 -429.014416)
					(end 60.218066 -429.036734)
				)
				(arc
					(start 61.157866 -429.036734)
					(mid 61.211748 -429.014416)
					(end 61.234066 -428.960534)
				)
				(arc
					(start 61.234066 -426.41901)
					(mid 61.211748 -426.365128)
					(end 61.157866 -426.34281)
				)
				(arc
					(start 60.218066 -426.34281)
					(mid 60.164184 -426.365128)
					(end 60.141866 -426.41901)
				)
				(arc
					(start 60.141866 -427.146466)
					(mid 60.143865 -427.163807)
					(end 60.14974 -427.180248)
				)
				(arc
					(start 60.383166 -427.656498)
					(mid 60.390949 -427.690026)
					(end 60.383166 -427.723554)
				)
				(arc
					(start 60.14974 -428.199804)
					(mid 60.143845 -428.21624)
					(end 60.141866 -428.233586)
				)
			)
		)
	)
	(zone
		(layers "In5.Cu" "In7.Cu")
		(hatch none 0.5)
		(connect_pads
			(clearance 0)
		)
		(min_thickness 0.25)
		(keepout
			(tracks not_allowed)
			(vias allowed)
			(pads allowed)
			(copperpour not_allowed)
			(footprints allowed)
		)
		(placement
			(enabled no)
			(sheetname "")
		)
		(fill yes
			(thermal_gap 0.5)
			(thermal_bridge_width 0.5)
			(island_removal_mode 0)
		)
		(polygon
			(pts
				(arc
					(start 137.241788 -427.960536)
					(mid 137.264106 -428.014418)
					(end 137.317988 -428.036736)
				)
				(arc
					(start 138.257788 -428.036736)
					(mid 138.31167 -428.014418)
					(end 138.333988 -427.960536)
				)
				(arc
					(start 138.333988 -425.419012)
					(mid 138.31167 -425.36513)
					(end 138.257788 -425.342812)
				)
				(arc
					(start 137.317988 -425.342812)
					(mid 137.264106 -425.36513)
					(end 137.241788 -425.419012)
				)
				(arc
					(start 137.241788 -426.146468)
					(mid 137.243787 -426.163809)
					(end 137.249662 -426.18025)
				)
				(arc
					(start 137.483088 -426.6565)
					(mid 137.490871 -426.690028)
					(end 137.483088 -426.723556)
				)
				(arc
					(start 137.249662 -427.199806)
					(mid 137.243767 -427.216242)
					(end 137.241788 -427.233588)
				)
			)
		)
	)
	(zone
		(layers "In5.Cu" "In7.Cu")
		(hatch none 0.5)
		(connect_pads
			(clearance 0)
		)
		(min_thickness 0.25)
		(keepout
			(tracks not_allowed)
			(vias allowed)
			(pads allowed)
			(copperpour not_allowed)
			(footprints allowed)
		)
		(placement
			(enabled no)
			(sheetname "")
		)
		(fill yes
			(thermal_gap 0.5)
			(thermal_bridge_width 0.5)
			(island_removal_mode 0)
		)
		(polygon
			(pts
				(arc
					(start 58.14187 -427.960536)
					(mid 58.164188 -428.014418)
					(end 58.21807 -428.036736)
				)
				(arc
					(start 59.15787 -428.036736)
					(mid 59.211752 -428.014418)
					(end 59.23407 -427.960536)
				)
				(arc
					(start 59.23407 -425.419012)
					(mid 59.211752 -425.36513)
					(end 59.15787 -425.342812)
				)
				(arc
					(start 58.21807 -425.342812)
					(mid 58.164188 -425.36513)
					(end 58.14187 -425.419012)
				)
				(arc
					(start 58.14187 -426.146468)
					(mid 58.143869 -426.163809)
					(end 58.149744 -426.18025)
				)
				(arc
					(start 58.38317 -426.6565)
					(mid 58.390953 -426.690028)
					(end 58.38317 -426.723556)
				)
				(arc
					(start 58.149744 -427.199806)
					(mid 58.143849 -427.216242)
					(end 58.14187 -427.233588)
				)
			)
		)
	)
	(zone
		(layers "In5.Cu" "In7.Cu")
		(hatch none 0.5)
		(connect_pads
			(clearance 0)
		)
		(min_thickness 0.25)
		(keepout
			(tracks not_allowed)
			(vias allowed)
			(pads allowed)
			(copperpour not_allowed)
			(footprints allowed)
		)
		(placement
			(enabled no)
			(sheetname "")
		)
		(fill yes
			(thermal_gap 0.5)
			(thermal_bridge_width 0.5)
			(island_removal_mode 0)
		)
		(polygon
			(pts
				(arc
					(start 142.242032 -431.560478)
					(mid 142.26435 -431.61436)
					(end 142.318232 -431.636678)
				)
				(arc
					(start 143.258032 -431.636678)
					(mid 143.311914 -431.61436)
					(end 143.334232 -431.560478)
				)
				(arc
					(start 143.334232 -429.018954)
					(mid 143.311914 -428.965072)
					(end 143.258032 -428.942754)
				)
				(arc
					(start 142.318232 -428.942754)
					(mid 142.26435 -428.965072)
					(end 142.242032 -429.018954)
				)
			)
		)
	)
	(zone
		(layers "In5.Cu" "In7.Cu")
		(hatch none 0.5)
		(connect_pads
			(clearance 0)
		)
		(min_thickness 0.25)
		(keepout
			(tracks not_allowed)
			(vias allowed)
			(pads allowed)
			(copperpour not_allowed)
			(footprints allowed)
		)
		(placement
			(enabled no)
			(sheetname "")
		)
		(fill yes
			(thermal_gap 0.5)
			(thermal_bridge_width 0.5)
			(island_removal_mode 0)
		)
		(polygon
			(pts
				(arc
					(start 87.141812 -427.960536)
					(mid 87.16413 -428.014418)
					(end 87.218012 -428.036736)
				)
				(arc
					(start 88.157812 -428.036736)
					(mid 88.211694 -428.014418)
					(end 88.234012 -427.960536)
				)
				(arc
					(start 88.234012 -425.419012)
					(mid 88.211694 -425.36513)
					(end 88.157812 -425.342812)
				)
				(arc
					(start 87.218012 -425.342812)
					(mid 87.16413 -425.36513)
					(end 87.141812 -425.419012)
				)
				(arc
					(start 87.141812 -426.146468)
					(mid 87.143811 -426.163809)
					(end 87.149686 -426.18025)
				)
				(arc
					(start 87.383112 -426.6565)
					(mid 87.390895 -426.690028)
					(end 87.383112 -426.723556)
				)
				(arc
					(start 87.149686 -427.199806)
					(mid 87.143791 -427.216242)
					(end 87.141812 -427.233588)
				)
			)
		)
	)
	(zone
		(layers "In5.Cu" "In7.Cu")
		(hatch none 0.5)
		(connect_pads
			(clearance 0)
		)
		(min_thickness 0.25)
		(keepout
			(tracks not_allowed)
			(vias allowed)
			(pads allowed)
			(copperpour not_allowed)
			(footprints allowed)
		)
		(placement
			(enabled no)
			(sheetname "")
		)
		(fill yes
			(thermal_gap 0.5)
			(thermal_bridge_width 0.5)
			(island_removal_mode 0)
		)
		(polygon
			(pts
				(arc
					(start 402.24202 -427.960536)
					(mid 402.264338 -428.014418)
					(end 402.31822 -428.036736)
				)
				(arc
					(start 403.25802 -428.036736)
					(mid 403.311902 -428.014418)
					(end 403.33422 -427.960536)
				)
				(arc
					(start 403.33422 -425.419012)
					(mid 403.311902 -425.36513)
					(end 403.25802 -425.342812)
				)
				(arc
					(start 402.31822 -425.342812)
					(mid 402.264338 -425.36513)
					(end 402.24202 -425.419012)
				)
				(arc
					(start 402.24202 -426.146468)
					(mid 402.244019 -426.163809)
					(end 402.249894 -426.18025)
				)
				(arc
					(start 402.48332 -426.6565)
					(mid 402.491103 -426.690028)
					(end 402.48332 -426.723556)
				)
				(arc
					(start 402.249894 -427.199806)
					(mid 402.243999 -427.216242)
					(end 402.24202 -427.233588)
				)
			)
		)
	)
	(zone
		(layers "In5.Cu" "In7.Cu")
		(hatch none 0.5)
		(connect_pads
			(clearance 0)
		)
		(min_thickness 0.25)
		(keepout
			(tracks not_allowed)
			(vias allowed)
			(pads allowed)
			(copperpour not_allowed)
			(footprints allowed)
		)
		(placement
			(enabled no)
			(sheetname "")
		)
		(fill yes
			(thermal_gap 0.5)
			(thermal_bridge_width 0.5)
			(island_removal_mode 0)
		)
		(polygon
			(pts
				(arc
					(start 131.2418 -428.96028)
					(mid 131.264118 -429.014162)
					(end 131.318 -429.03648)
				)
				(arc
					(start 132.2578 -429.03648)
					(mid 132.311682 -429.014162)
					(end 132.334 -428.96028)
				)
				(arc
					(start 132.334 -426.418756)
					(mid 132.311682 -426.364874)
					(end 132.2578 -426.342556)
				)
				(arc
					(start 131.318 -426.342556)
					(mid 131.264118 -426.364874)
					(end 131.2418 -426.418756)
				)
				(arc
					(start 131.2418 -427.146212)
					(mid 131.243799 -427.163553)
					(end 131.249674 -427.179994)
				)
				(arc
					(start 131.4831 -427.656244)
					(mid 131.490883 -427.689772)
					(end 131.4831 -427.7233)
				)
				(arc
					(start 131.249674 -428.19955)
					(mid 131.243779 -428.215986)
					(end 131.2418 -428.233332)
				)
			)
		)
	)
	(zone
		(layers "In5.Cu" "In7.Cu")
		(hatch none 0.5)
		(connect_pads
			(clearance 0)
		)
		(min_thickness 0.25)
		(keepout
			(tracks not_allowed)
			(vias allowed)
			(pads allowed)
			(copperpour not_allowed)
			(footprints allowed)
		)
		(placement
			(enabled no)
			(sheetname "")
		)
		(fill yes
			(thermal_gap 0.5)
			(thermal_bridge_width 0.5)
			(island_removal_mode 0)
		)
		(polygon
			(pts
				(arc
					(start 156.242004 -432.560476)
					(mid 156.264322 -432.614358)
					(end 156.318204 -432.636676)
				)
				(arc
					(start 157.258004 -432.636676)
					(mid 157.311886 -432.614358)
					(end 157.334204 -432.560476)
				)
				(arc
					(start 157.334204 -430.018952)
					(mid 157.311886 -429.96507)
					(end 157.258004 -429.942752)
				)
				(arc
					(start 156.318204 -429.942752)
					(mid 156.264322 -429.96507)
					(end 156.242004 -430.018952)
				)
			)
		)
	)
	(zone
		(layers "In5.Cu" "In7.Cu")
		(hatch none 0.5)
		(connect_pads
			(clearance 0)
		)
		(min_thickness 0.25)
		(keepout
			(tracks not_allowed)
			(vias allowed)
			(pads allowed)
			(copperpour not_allowed)
			(footprints allowed)
		)
		(placement
			(enabled no)
			(sheetname "")
		)
		(fill yes
			(thermal_gap 0.5)
			(thermal_bridge_width 0.5)
			(island_removal_mode 0)
		)
		(polygon
			(pts
				(arc
					(start 406.242012 -427.960536)
					(mid 406.26433 -428.014418)
					(end 406.318212 -428.036736)
				)
				(arc
					(start 407.258012 -428.036736)
					(mid 407.311894 -428.014418)
					(end 407.334212 -427.960536)
				)
				(arc
					(start 407.334212 -425.419012)
					(mid 407.311894 -425.36513)
					(end 407.258012 -425.342812)
				)
				(arc
					(start 406.318212 -425.342812)
					(mid 406.26433 -425.36513)
					(end 406.242012 -425.419012)
				)
				(arc
					(start 406.242012 -426.146468)
					(mid 406.244011 -426.163809)
					(end 406.249886 -426.18025)
				)
				(arc
					(start 406.483312 -426.6565)
					(mid 406.491095 -426.690028)
					(end 406.483312 -426.723556)
				)
				(arc
					(start 406.249886 -427.199806)
					(mid 406.243991 -427.216242)
					(end 406.242012 -427.233588)
				)
			)
		)
	)
	(zone
		(layers "In5.Cu" "In7.Cu")
		(hatch none 0.5)
		(connect_pads
			(clearance 0)
		)
		(min_thickness 0.25)
		(keepout
			(tracks not_allowed)
			(vias allowed)
			(pads allowed)
			(copperpour not_allowed)
			(footprints allowed)
		)
		(placement
			(enabled no)
			(sheetname "")
		)
		(fill yes
			(thermal_gap 0.5)
			(thermal_bridge_width 0.5)
			(island_removal_mode 0)
		)
		(polygon
			(pts
				(arc
					(start 85.141816 -428.960534)
					(mid 85.164134 -429.014416)
					(end 85.218016 -429.036734)
				)
				(arc
					(start 86.157816 -429.036734)
					(mid 86.211698 -429.014416)
					(end 86.234016 -428.960534)
				)
				(arc
					(start 86.234016 -426.41901)
					(mid 86.211698 -426.365128)
					(end 86.157816 -426.34281)
				)
				(arc
					(start 85.218016 -426.34281)
					(mid 85.164134 -426.365128)
					(end 85.141816 -426.41901)
				)
				(arc
					(start 85.141816 -427.146466)
					(mid 85.143815 -427.163807)
					(end 85.14969 -427.180248)
				)
				(arc
					(start 85.383116 -427.656498)
					(mid 85.390899 -427.690026)
					(end 85.383116 -427.723554)
				)
				(arc
					(start 85.14969 -428.199804)
					(mid 85.143795 -428.21624)
					(end 85.141816 -428.233586)
				)
			)
		)
	)
	(zone
		(layers "In5.Cu" "In7.Cu")
		(hatch none 0.5)
		(connect_pads
			(clearance 0)
		)
		(min_thickness 0.25)
		(keepout
			(tracks not_allowed)
			(vias allowed)
			(pads allowed)
			(copperpour not_allowed)
			(footprints allowed)
		)
		(placement
			(enabled no)
			(sheetname "")
		)
		(fill yes
			(thermal_gap 0.5)
			(thermal_bridge_width 0.5)
			(island_removal_mode 0)
		)
		(polygon
			(pts
				(arc
					(start 148.24202 -428.96028)
					(mid 148.264338 -429.014162)
					(end 148.31822 -429.03648)
				)
				(arc
					(start 149.25802 -429.03648)
					(mid 149.311902 -429.014162)
					(end 149.33422 -428.96028)
				)
				(arc
					(start 149.33422 -426.418756)
					(mid 149.311902 -426.364874)
					(end 149.25802 -426.342556)
				)
				(arc
					(start 148.31822 -426.342556)
					(mid 148.264338 -426.364874)
					(end 148.24202 -426.418756)
				)
				(arc
					(start 148.24202 -427.146212)
					(mid 148.244019 -427.163553)
					(end 148.249894 -427.179994)
				)
				(arc
					(start 148.48332 -427.656244)
					(mid 148.491103 -427.689772)
					(end 148.48332 -427.7233)
				)
				(arc
					(start 148.249894 -428.19955)
					(mid 148.243999 -428.215986)
					(end 148.24202 -428.233332)
				)
			)
		)
	)
	(zone
		(layers "In5.Cu" "In7.Cu")
		(hatch none 0.5)
		(connect_pads
			(clearance 0)
		)
		(min_thickness 0.25)
		(keepout
			(tracks not_allowed)
			(vias allowed)
			(pads allowed)
			(copperpour not_allowed)
			(footprints allowed)
		)
		(placement
			(enabled no)
			(sheetname "")
		)
		(fill yes
			(thermal_gap 0.5)
			(thermal_bridge_width 0.5)
			(island_removal_mode 0)
		)
		(polygon
			(pts
				(arc
					(start 89.141808 -428.960534)
					(mid 89.164126 -429.014416)
					(end 89.218008 -429.036734)
				)
				(arc
					(start 90.157808 -429.036734)
					(mid 90.21169 -429.014416)
					(end 90.234008 -428.960534)
				)
				(arc
					(start 90.234008 -426.41901)
					(mid 90.21169 -426.365128)
					(end 90.157808 -426.34281)
				)
				(arc
					(start 89.218008 -426.34281)
					(mid 89.164126 -426.365128)
					(end 89.141808 -426.41901)
				)
				(arc
					(start 89.141808 -427.146466)
					(mid 89.143807 -427.163807)
					(end 89.149682 -427.180248)
				)
				(arc
					(start 89.383108 -427.656498)
					(mid 89.390891 -427.690026)
					(end 89.383108 -427.723554)
				)
				(arc
					(start 89.149682 -428.199804)
					(mid 89.143787 -428.21624)
					(end 89.141808 -428.233586)
				)
			)
		)
	)
	(zone
		(layers "In5.Cu" "In7.Cu")
		(hatch none 0.5)
		(connect_pads
			(clearance 0)
		)
		(min_thickness 0.25)
		(keepout
			(tracks not_allowed)
			(vias allowed)
			(pads allowed)
			(copperpour not_allowed)
			(footprints allowed)
		)
		(placement
			(enabled no)
			(sheetname "")
		)
		(fill yes
			(thermal_gap 0.5)
			(thermal_bridge_width 0.5)
			(island_removal_mode 0)
		)
		(polygon
			(pts
				(arc
					(start 135.241792 -428.96028)
					(mid 135.26411 -429.014162)
					(end 135.317992 -429.03648)
				)
				(arc
					(start 136.257792 -429.03648)
					(mid 136.311674 -429.014162)
					(end 136.333992 -428.96028)
				)
				(arc
					(start 136.333992 -426.418756)
					(mid 136.311674 -426.364874)
					(end 136.257792 -426.342556)
				)
				(arc
					(start 135.317992 -426.342556)
					(mid 135.26411 -426.364874)
					(end 135.241792 -426.418756)
				)
				(arc
					(start 135.241792 -427.146212)
					(mid 135.243791 -427.163553)
					(end 135.249666 -427.179994)
				)
				(arc
					(start 135.483092 -427.656244)
					(mid 135.490875 -427.689772)
					(end 135.483092 -427.7233)
				)
				(arc
					(start 135.249666 -428.19955)
					(mid 135.243771 -428.215986)
					(end 135.241792 -428.233332)
				)
			)
		)
	)
	(zone
		(layers "In5.Cu" "In7.Cu")
		(hatch none 0.5)
		(connect_pads
			(clearance 0)
		)
		(min_thickness 0.25)
		(keepout
			(tracks not_allowed)
			(vias allowed)
			(pads allowed)
			(copperpour not_allowed)
			(footprints allowed)
		)
		(placement
			(enabled no)
			(sheetname "")
		)
		(fill yes
			(thermal_gap 0.5)
			(thermal_bridge_width 0.5)
			(island_removal_mode 0)
		)
		(polygon
			(pts
				(arc
					(start 81.141824 -428.960534)
					(mid 81.164142 -429.014416)
					(end 81.218024 -429.036734)
				)
				(arc
					(start 82.157824 -429.036734)
					(mid 82.211706 -429.014416)
					(end 82.234024 -428.960534)
				)
				(arc
					(start 82.234024 -426.41901)
					(mid 82.211706 -426.365128)
					(end 82.157824 -426.34281)
				)
				(arc
					(start 81.218024 -426.34281)
					(mid 81.164142 -426.365128)
					(end 81.141824 -426.41901)
				)
				(arc
					(start 81.141824 -427.146466)
					(mid 81.143823 -427.163807)
					(end 81.149698 -427.180248)
				)
				(arc
					(start 81.383124 -427.656498)
					(mid 81.390907 -427.690026)
					(end 81.383124 -427.723554)
				)
				(arc
					(start 81.149698 -428.199804)
					(mid 81.143803 -428.21624)
					(end 81.141824 -428.233586)
				)
			)
		)
	)
	(zone
		(layers "In5.Cu" "In7.Cu")
		(hatch none 0.5)
		(connect_pads
			(clearance 0)
		)
		(min_thickness 0.25)
		(keepout
			(tracks not_allowed)
			(vias allowed)
			(pads allowed)
			(copperpour not_allowed)
			(footprints allowed)
		)
		(placement
			(enabled no)
			(sheetname "")
		)
		(fill yes
			(thermal_gap 0.5)
			(thermal_bridge_width 0.5)
			(island_removal_mode 0)
		)
		(polygon
			(pts
				(arc
					(start 339.141816 -427.960536)
					(mid 339.164134 -428.014418)
					(end 339.218016 -428.036736)
				)
				(arc
					(start 340.157816 -428.036736)
					(mid 340.211698 -428.014418)
					(end 340.234016 -427.960536)
				)
				(arc
					(start 340.234016 -425.419012)
					(mid 340.211698 -425.36513)
					(end 340.157816 -425.342812)
				)
				(arc
					(start 339.218016 -425.342812)
					(mid 339.164134 -425.36513)
					(end 339.141816 -425.419012)
				)
				(arc
					(start 339.141816 -426.146468)
					(mid 339.143815 -426.163809)
					(end 339.14969 -426.18025)
				)
				(arc
					(start 339.383116 -426.6565)
					(mid 339.390899 -426.690028)
					(end 339.383116 -426.723556)
				)
				(arc
					(start 339.14969 -427.199806)
					(mid 339.143795 -427.216242)
					(end 339.141816 -427.233588)
				)
			)
		)
	)
	(zone
		(layers "In5.Cu" "In7.Cu")
		(hatch none 0.5)
		(connect_pads
			(clearance 0)
		)
		(min_thickness 0.25)
		(keepout
			(tracks not_allowed)
			(vias allowed)
			(pads allowed)
			(copperpour not_allowed)
			(footprints allowed)
		)
		(placement
			(enabled no)
			(sheetname "")
		)
		(fill yes
			(thermal_gap 0.5)
			(thermal_bridge_width 0.5)
			(island_removal_mode 0)
		)
		(polygon
			(pts
				(arc
					(start 133.241796 -427.960536)
					(mid 133.264114 -428.014418)
					(end 133.317996 -428.036736)
				)
				(arc
					(start 134.257796 -428.036736)
					(mid 134.311678 -428.014418)
					(end 134.333996 -427.960536)
				)
				(arc
					(start 134.333996 -425.419012)
					(mid 134.311678 -425.36513)
					(end 134.257796 -425.342812)
				)
				(arc
					(start 133.317996 -425.342812)
					(mid 133.264114 -425.36513)
					(end 133.241796 -425.419012)
				)
				(arc
					(start 133.241796 -426.146468)
					(mid 133.243795 -426.163809)
					(end 133.24967 -426.18025)
				)
				(arc
					(start 133.483096 -426.6565)
					(mid 133.490879 -426.690028)
					(end 133.483096 -426.723556)
				)
				(arc
					(start 133.24967 -427.199806)
					(mid 133.243775 -427.216242)
					(end 133.241796 -427.233588)
				)
			)
		)
	)
	(zone
		(layers "In5.Cu" "In7.Cu")
		(hatch none 0.5)
		(connect_pads
			(clearance 0)
		)
		(min_thickness 0.25)
		(keepout
			(tracks not_allowed)
			(vias allowed)
			(pads allowed)
			(copperpour not_allowed)
			(footprints allowed)
		)
		(placement
			(enabled no)
			(sheetname "")
		)
		(fill yes
			(thermal_gap 0.5)
			(thermal_bridge_width 0.5)
			(island_removal_mode 0)
		)
		(polygon
			(pts
				(arc
					(start 146.242024 -431.560478)
					(mid 146.264342 -431.61436)
					(end 146.318224 -431.636678)
				)
				(arc
					(start 147.258024 -431.636678)
					(mid 147.311906 -431.61436)
					(end 147.334224 -431.560478)
				)
				(arc
					(start 147.334224 -429.018954)
					(mid 147.311906 -428.965072)
					(end 147.258024 -428.942754)
				)
				(arc
					(start 146.318224 -428.942754)
					(mid 146.264342 -428.965072)
					(end 146.242024 -429.018954)
				)
			)
		)
	)
	(zone
		(layers "In5.Cu" "In7.Cu")
		(hatch none 0.5)
		(connect_pads
			(clearance 0)
		)
		(min_thickness 0.25)
		(keepout
			(tracks not_allowed)
			(vias allowed)
			(pads allowed)
			(copperpour not_allowed)
			(footprints allowed)
		)
		(placement
			(enabled no)
			(sheetname "")
		)
		(fill yes
			(thermal_gap 0.5)
			(thermal_bridge_width 0.5)
			(island_removal_mode 0)
		)
		(polygon
			(pts
				(arc
					(start 335.141824 -427.960536)
					(mid 335.164142 -428.014418)
					(end 335.218024 -428.036736)
				)
				(arc
					(start 336.157824 -428.036736)
					(mid 336.211706 -428.014418)
					(end 336.234024 -427.960536)
				)
				(arc
					(start 336.234024 -425.419012)
					(mid 336.211706 -425.36513)
					(end 336.157824 -425.342812)
				)
				(arc
					(start 335.218024 -425.342812)
					(mid 335.164142 -425.36513)
					(end 335.141824 -425.419012)
				)
				(arc
					(start 335.141824 -426.146468)
					(mid 335.143823 -426.163809)
					(end 335.149698 -426.18025)
				)
				(arc
					(start 335.383124 -426.6565)
					(mid 335.390907 -426.690028)
					(end 335.383124 -426.723556)
				)
				(arc
					(start 335.149698 -427.199806)
					(mid 335.143803 -427.216242)
					(end 335.141824 -427.233588)
				)
			)
		)
	)
	(zone
		(layers "In5.Cu" "In7.Cu")
		(hatch none 0.5)
		(connect_pads
			(clearance 0)
		)
		(min_thickness 0.25)
		(keepout
			(tracks not_allowed)
			(vias allowed)
			(pads allowed)
			(copperpour not_allowed)
			(footprints allowed)
		)
		(placement
			(enabled no)
			(sheetname "")
		)
		(fill yes
			(thermal_gap 0.5)
			(thermal_bridge_width 0.5)
			(island_removal_mode 0)
		)
		(polygon
			(pts
				(arc
					(start 79.141828 -427.960536)
					(mid 79.164146 -428.014418)
					(end 79.218028 -428.036736)
				)
				(arc
					(start 80.157828 -428.036736)
					(mid 80.21171 -428.014418)
					(end 80.234028 -427.960536)
				)
				(arc
					(start 80.234028 -425.419012)
					(mid 80.21171 -425.36513)
					(end 80.157828 -425.342812)
				)
				(arc
					(start 79.218028 -425.342812)
					(mid 79.164146 -425.36513)
					(end 79.141828 -425.419012)
				)
				(arc
					(start 79.141828 -426.146468)
					(mid 79.143827 -426.163809)
					(end 79.149702 -426.18025)
				)
				(arc
					(start 79.383128 -426.6565)
					(mid 79.390911 -426.690028)
					(end 79.383128 -426.723556)
				)
				(arc
					(start 79.149702 -427.199806)
					(mid 79.143807 -427.216242)
					(end 79.141828 -427.233588)
				)
			)
		)
	)
	(zone
		(layers "In5.Cu" "In7.Cu")
		(hatch none 0.5)
		(connect_pads
			(clearance 0)
		)
		(min_thickness 0.25)
		(keepout
			(tracks not_allowed)
			(vias allowed)
			(pads allowed)
			(copperpour not_allowed)
			(footprints allowed)
		)
		(placement
			(enabled no)
			(sheetname "")
		)
		(fill yes
			(thermal_gap 0.5)
			(thermal_bridge_width 0.5)
			(island_removal_mode 0)
		)
		(polygon
			(pts
				(arc
					(start 152.242012 -432.560476)
					(mid 152.26433 -432.614358)
					(end 152.318212 -432.636676)
				)
				(arc
					(start 153.258012 -432.636676)
					(mid 153.311894 -432.614358)
					(end 153.334212 -432.560476)
				)
				(arc
					(start 153.334212 -430.018952)
					(mid 153.311894 -429.96507)
					(end 153.258012 -429.942752)
				)
				(arc
					(start 152.318212 -429.942752)
					(mid 152.26433 -429.96507)
					(end 152.242012 -430.018952)
				)
			)
		)
	)
	(zone
		(layers "In5.Cu" "In7.Cu")
		(hatch none 0.5)
		(connect_pads
			(clearance 0)
		)
		(min_thickness 0.25)
		(keepout
			(tracks not_allowed)
			(vias allowed)
			(pads allowed)
			(copperpour not_allowed)
			(footprints allowed)
		)
		(placement
			(enabled no)
			(sheetname "")
		)
		(fill yes
			(thermal_gap 0.5)
			(thermal_bridge_width 0.5)
			(island_removal_mode 0)
		)
		(polygon
			(pts
				(arc
					(start 146.242024 -427.960536)
					(mid 146.264342 -428.014418)
					(end 146.318224 -428.036736)
				)
				(arc
					(start 147.258024 -428.036736)
					(mid 147.311906 -428.014418)
					(end 147.334224 -427.960536)
				)
				(arc
					(start 147.334224 -425.419012)
					(mid 147.311906 -425.36513)
					(end 147.258024 -425.342812)
				)
				(arc
					(start 146.318224 -425.342812)
					(mid 146.264342 -425.36513)
					(end 146.242024 -425.419012)
				)
				(arc
					(start 146.242024 -426.146468)
					(mid 146.244023 -426.163809)
					(end 146.249898 -426.18025)
				)
				(arc
					(start 146.483324 -426.6565)
					(mid 146.491107 -426.690028)
					(end 146.483324 -426.723556)
				)
				(arc
					(start 146.249898 -427.199806)
					(mid 146.244003 -427.216242)
					(end 146.242024 -427.233588)
				)
			)
		)
	)
	(zone
		(layers "In5.Cu" "In7.Cu")
		(hatch none 0.5)
		(connect_pads
			(clearance 0)
		)
		(min_thickness 0.25)
		(keepout
			(tracks not_allowed)
			(vias allowed)
			(pads allowed)
			(copperpour not_allowed)
			(footprints allowed)
		)
		(placement
			(enabled no)
			(sheetname "")
		)
		(fill yes
			(thermal_gap 0.5)
			(thermal_bridge_width 0.5)
			(island_removal_mode 0)
		)
		(polygon
			(pts
				(arc
					(start 129.241804 -427.960536)
					(mid 129.264122 -428.014418)
					(end 129.318004 -428.036736)
				)
				(arc
					(start 130.257804 -428.036736)
					(mid 130.311686 -428.014418)
					(end 130.334004 -427.960536)
				)
				(arc
					(start 130.334004 -425.419012)
					(mid 130.311686 -425.36513)
					(end 130.257804 -425.342812)
				)
				(arc
					(start 129.318004 -425.342812)
					(mid 129.264122 -425.36513)
					(end 129.241804 -425.419012)
				)
				(arc
					(start 129.241804 -426.146468)
					(mid 129.243803 -426.163809)
					(end 129.249678 -426.18025)
				)
				(arc
					(start 129.483104 -426.6565)
					(mid 129.490887 -426.690028)
					(end 129.483104 -426.723556)
				)
				(arc
					(start 129.249678 -427.199806)
					(mid 129.243783 -427.216242)
					(end 129.241804 -427.233588)
				)
			)
		)
	)
	(zone
		(layers "In5.Cu" "In7.Cu")
		(hatch none 0.5)
		(connect_pads
			(clearance 0)
		)
		(min_thickness 0.25)
		(keepout
			(tracks not_allowed)
			(vias allowed)
			(pads allowed)
			(copperpour not_allowed)
			(footprints allowed)
		)
		(placement
			(enabled no)
			(sheetname "")
		)
		(fill yes
			(thermal_gap 0.5)
			(thermal_bridge_width 0.5)
			(island_removal_mode 0)
		)
		(polygon
			(pts
				(arc
					(start 154.242008 -431.560478)
					(mid 154.264326 -431.61436)
					(end 154.318208 -431.636678)
				)
				(arc
					(start 155.258008 -431.636678)
					(mid 155.31189 -431.61436)
					(end 155.334208 -431.560478)
				)
				(arc
					(start 155.334208 -429.018954)
					(mid 155.31189 -428.965072)
					(end 155.258008 -428.942754)
				)
				(arc
					(start 154.318208 -428.942754)
					(mid 154.264326 -428.965072)
					(end 154.242008 -429.018954)
				)
			)
		)
	)
	(zone
		(layers "In5.Cu" "In7.Cu")
		(hatch none 0.5)
		(connect_pads
			(clearance 0)
		)
		(min_thickness 0.25)
		(keepout
			(tracks not_allowed)
			(vias allowed)
			(pads allowed)
			(copperpour not_allowed)
			(footprints allowed)
		)
		(placement
			(enabled no)
			(sheetname "")
		)
		(fill yes
			(thermal_gap 0.5)
			(thermal_bridge_width 0.5)
			(island_removal_mode 0)
		)
		(polygon
			(pts
				(arc
					(start 148.24202 -432.560476)
					(mid 148.264338 -432.614358)
					(end 148.31822 -432.636676)
				)
				(arc
					(start 149.25802 -432.636676)
					(mid 149.311902 -432.614358)
					(end 149.33422 -432.560476)
				)
				(arc
					(start 149.33422 -430.018952)
					(mid 149.311902 -429.96507)
					(end 149.25802 -429.942752)
				)
				(arc
					(start 148.31822 -429.942752)
					(mid 148.264338 -429.96507)
					(end 148.24202 -430.018952)
				)
			)
		)
	)
	(zone
		(layers "In5.Cu" "In7.Cu")
		(hatch none 0.5)
		(connect_pads
			(clearance 0)
		)
		(min_thickness 0.25)
		(keepout
			(tracks not_allowed)
			(vias allowed)
			(pads allowed)
			(copperpour not_allowed)
			(footprints allowed)
		)
		(placement
			(enabled no)
			(sheetname "")
		)
		(fill yes
			(thermal_gap 0.5)
			(thermal_bridge_width 0.5)
			(island_removal_mode 0)
		)
		(polygon
			(pts
				(arc
					(start 144.242028 -432.560476)
					(mid 144.264346 -432.614358)
					(end 144.318228 -432.636676)
				)
				(arc
					(start 145.258028 -432.636676)
					(mid 145.31191 -432.614358)
					(end 145.334228 -432.560476)
				)
				(arc
					(start 145.334228 -430.018952)
					(mid 145.31191 -429.96507)
					(end 145.258028 -429.942752)
				)
				(arc
					(start 144.318228 -429.942752)
					(mid 144.264346 -429.96507)
					(end 144.242028 -430.018952)
				)
			)
		)
	)
	(zone
		(layers "In5.Cu" "In7.Cu")
		(hatch none 0.5)
		(connect_pads
			(clearance 0)
		)
		(min_thickness 0.25)
		(keepout
			(tracks not_allowed)
			(vias allowed)
			(pads allowed)
			(copperpour not_allowed)
			(footprints allowed)
		)
		(placement
			(enabled no)
			(sheetname "")
		)
		(fill yes
			(thermal_gap 0.5)
			(thermal_bridge_width 0.5)
			(island_removal_mode 0)
		)
		(polygon
			(pts
				(arc
					(start 398.242028 -427.960536)
					(mid 398.264346 -428.014418)
					(end 398.318228 -428.036736)
				)
				(arc
					(start 399.258028 -428.036736)
					(mid 399.31191 -428.014418)
					(end 399.334228 -427.960536)
				)
				(arc
					(start 399.334228 -425.419012)
					(mid 399.31191 -425.36513)
					(end 399.258028 -425.342812)
				)
				(arc
					(start 398.318228 -425.342812)
					(mid 398.264346 -425.36513)
					(end 398.242028 -425.419012)
				)
				(arc
					(start 398.242028 -426.146468)
					(mid 398.244027 -426.163809)
					(end 398.249902 -426.18025)
				)
				(arc
					(start 398.483328 -426.6565)
					(mid 398.491111 -426.690028)
					(end 398.483328 -426.723556)
				)
				(arc
					(start 398.249902 -427.199806)
					(mid 398.244007 -427.216242)
					(end 398.242028 -427.233588)
				)
			)
		)
	)
	(zone
		(layer "In6.Cu")
		(hatch none 0.5)
		(connect_pads
			(clearance 0)
		)
		(min_thickness 0.25)
		(keepout
			(tracks allowed)
			(vias allowed)
			(pads allowed)
			(copperpour allowed)
			(footprints allowed)
		)
		(placement
			(enabled no)
			(sheetname "")
		)
		(fill
			(thermal_gap 0.5)
			(thermal_bridge_width 0.5)
			(island_removal_mode 0)
		)
		(polygon
			(pts
				(xy 163.23564 -192.496948) (xy 163.23564 -319.66281) (xy 207.31099 -319.66281) (xy 207.31099 -192.496948)
			)
		)
	)
	(zone
		(layer "In6.Cu")
		(hatch none 0.5)
		(connect_pads
			(clearance 0)
		)
		(min_thickness 0.25)
		(keepout
			(tracks allowed)
			(vias allowed)
			(pads allowed)
			(copperpour allowed)
			(footprints allowed)
		)
		(placement
			(enabled no)
			(sheetname "")
		)
		(fill
			(thermal_gap 0.5)
			(thermal_bridge_width 0.5)
			(island_removal_mode 0)
		)
		(polygon
			(pts
				(xy 374.768618 -178.175412) (xy 374.768618 -179.039012) (xy 374.565418 -179.039012) (xy 374.565418 -178.175412)
			)
		)
	)
	(zone
		(layer "In6.Cu")
		(hatch none 0.5)
		(connect_pads
			(clearance 0)
		)
		(min_thickness 0.25)
		(keepout
			(tracks not_allowed)
			(vias allowed)
			(pads allowed)
			(copperpour not_allowed)
			(footprints allowed)
		)
		(placement
			(enabled no)
			(sheetname "")
		)
		(fill
			(thermal_gap 0.5)
			(thermal_bridge_width 0.5)
			(island_removal_mode 0)
		)
		(polygon
			(pts
				(xy 356.844346 -394.468096) (xy 356.844346 -392.54557) (xy 357.852726 -392.54557) (xy 357.852726 -394.468096)
			)
		)
	)
	(zone
		(layer "In6.Cu")
		(hatch none 0.5)
		(connect_pads
			(clearance 0)
		)
		(min_thickness 0.25)
		(keepout
			(tracks allowed)
			(vias allowed)
			(pads allowed)
			(copperpour allowed)
			(footprints allowed)
		)
		(placement
			(enabled no)
			(sheetname "")
		)
		(fill
			(thermal_gap 0.5)
			(thermal_bridge_width 0.5)
			(island_removal_mode 0)
		)
		(polygon
			(pts
				(xy 75.19289 -335.917032) (xy 75.19289 -336.722212) (xy 75.00747 -336.722212) (xy 75.00747 -335.917032)
			)
		)
	)
	(zone
		(layer "In6.Cu")
		(hatch none 0.5)
		(connect_pads
			(clearance 0)
		)
		(min_thickness 0.25)
		(keepout
			(tracks allowed)
			(vias allowed)
			(pads allowed)
			(copperpour allowed)
			(footprints allowed)
		)
		(placement
			(enabled no)
			(sheetname "")
		)
		(fill
			(thermal_gap 0.5)
			(thermal_bridge_width 0.5)
			(island_removal_mode 0)
		)
		(polygon
			(pts
				(xy 41.65981 -347.636592) (xy 41.65981 -348.441772) (xy 41.37025 -348.441772) (xy 41.37025 -347.636592)
			)
		)
	)
	(zone
		(layer "In6.Cu")
		(hatch none 0.5)
		(connect_pads
			(clearance 0)
		)
		(min_thickness 0.25)
		(keepout
			(tracks allowed)
			(vias allowed)
			(pads allowed)
			(copperpour allowed)
			(footprints allowed)
		)
		(placement
			(enabled no)
			(sheetname "")
		)
		(fill
			(thermal_gap 0.5)
			(thermal_bridge_width 0.5)
			(island_removal_mode 0)
		)
		(polygon
			(pts
				(xy 98.507804 -340.024212) (xy 98.507804 -339.477604) (xy 98.999548 -339.477604) (xy 98.999548 -340.024212)
			)
		)
	)
	(zone
		(layer "In6.Cu")
		(hatch none 0.5)
		(connect_pads
			(clearance 0)
		)
		(min_thickness 0.25)
		(keepout
			(tracks allowed)
			(vias allowed)
			(pads allowed)
			(copperpour allowed)
			(footprints allowed)
		)
		(placement
			(enabled no)
			(sheetname "")
		)
		(fill
			(thermal_gap 0.5)
			(thermal_bridge_width 0.5)
			(island_removal_mode 0)
		)
		(polygon
			(pts
				(xy 189.53861 -389.45947) (xy 189.53861 -388.912862) (xy 190.030354 -388.912862) (xy 190.030354 -389.45947)
			)
		)
	)
	(zone
		(layer "In6.Cu")
		(hatch none 0.5)
		(connect_pads
			(clearance 0)
		)
		(min_thickness 0.25)
		(keepout
			(tracks allowed)
			(vias allowed)
			(pads allowed)
			(copperpour allowed)
			(footprints allowed)
		)
		(placement
			(enabled no)
			(sheetname "")
		)
		(fill
			(thermal_gap 0.5)
			(thermal_bridge_width 0.5)
			(island_removal_mode 0)
		)
		(polygon
			(pts
				(xy 91.87307 -335.929732) (xy 91.87307 -336.709512) (xy 91.60891 -336.709512) (xy 91.60891 -335.929732)
			)
		)
	)
	(zone
		(layer "In6.Cu")
		(hatch none 0.5)
		(connect_pads
			(clearance 0)
		)
		(min_thickness 0.25)
		(keepout
			(tracks allowed)
			(vias allowed)
			(pads allowed)
			(copperpour allowed)
			(footprints allowed)
		)
		(placement
			(enabled no)
			(sheetname "")
		)
		(fill
			(thermal_gap 0.5)
			(thermal_bridge_width 0.5)
			(island_removal_mode 0)
		)
		(polygon
			(pts
				(xy 344.857324 -339.612986) (xy 344.857324 -339.066378) (xy 345.349068 -339.066378) (xy 345.349068 -339.612986)
			)
		)
	)
	(zone
		(layer "In6.Cu")
		(hatch none 0.5)
		(connect_pads
			(clearance 0)
		)
		(min_thickness 0.25)
		(keepout
			(tracks not_allowed)
			(vias allowed)
			(pads allowed)
			(copperpour not_allowed)
			(footprints allowed)
		)
		(placement
			(enabled no)
			(sheetname "")
		)
		(fill
			(thermal_gap 0.5)
			(thermal_bridge_width 0.5)
			(island_removal_mode 0)
		)
		(polygon
			(pts
				(xy 391.348214 -394.521944) (xy 391.348214 -392.438128) (xy 392.504422 -392.438128) (xy 392.504422 -394.521944)
			)
		)
	)
	(zone
		(layer "In6.Cu")
		(hatch none 0.5)
		(connect_pads
			(clearance 0)
		)
		(min_thickness 0.25)
		(keepout
			(tracks allowed)
			(vias allowed)
			(pads allowed)
			(copperpour allowed)
			(footprints allowed)
		)
		(placement
			(enabled no)
			(sheetname "")
		)
		(fill
			(thermal_gap 0.5)
			(thermal_bridge_width 0.5)
			(island_removal_mode 0)
		)
		(polygon
			(pts
				(xy 78.867 -179.848002) (xy 78.867 -179.301394) (xy 79.358744 -179.301394) (xy 79.358744 -179.848002)
			)
		)
	)
	(zone
		(layer "In6.Cu")
		(hatch none 0.5)
		(connect_pads
			(clearance 0)
		)
		(min_thickness 0.25)
		(keepout
			(tracks not_allowed)
			(vias allowed)
			(pads allowed)
			(copperpour not_allowed)
			(footprints allowed)
		)
		(placement
			(enabled no)
			(sheetname "")
		)
		(fill
			(thermal_gap 0.5)
			(thermal_bridge_width 0.5)
			(island_removal_mode 0)
		)
		(polygon
			(pts
				(xy 324.303136 -394.468096) (xy 324.303136 -392.5189) (xy 325.351648 -392.5189) (xy 325.351648 -394.468096)
			)
		)
	)
	(zone
		(layer "In6.Cu")
		(hatch none 0.5)
		(connect_pads
			(clearance 0)
		)
		(min_thickness 0.25)
		(keepout
			(tracks allowed)
			(vias allowed)
			(pads allowed)
			(copperpour allowed)
			(footprints allowed)
		)
		(placement
			(enabled no)
			(sheetname "")
		)
		(fill
			(thermal_gap 0.5)
			(thermal_bridge_width 0.5)
			(island_removal_mode 0)
		)
		(polygon
			(pts
				(xy 83.54695 -335.891632) (xy 83.54695 -336.709512) (xy 83.40217 -336.709512) (xy 83.40217 -335.891632)
			)
		)
	)
	(zone
		(layer "In6.Cu")
		(hatch none 0.5)
		(connect_pads
			(clearance 0)
		)
		(min_thickness 0.25)
		(keepout
			(tracks allowed)
			(vias allowed)
			(pads allowed)
			(copperpour allowed)
			(footprints allowed)
		)
		(placement
			(enabled no)
			(sheetname "")
		)
		(fill
			(thermal_gap 0.5)
			(thermal_bridge_width 0.5)
			(island_removal_mode 0)
		)
		(polygon
			(pts
				(xy 78.613 -179.086002) (xy 78.613 -178.539394) (xy 79.104744 -178.539394) (xy 79.104744 -179.086002)
			)
		)
	)
	(zone
		(layer "In6.Cu")
		(hatch none 0.5)
		(connect_pads
			(clearance 0)
		)
		(min_thickness 0.25)
		(keepout
			(tracks allowed)
			(vias allowed)
			(pads allowed)
			(copperpour allowed)
			(footprints allowed)
		)
		(placement
			(enabled no)
			(sheetname "")
		)
		(fill
			(thermal_gap 0.5)
			(thermal_bridge_width 0.5)
			(island_removal_mode 0)
		)
		(polygon
			(pts
				(xy 25.07361 -347.611192) (xy 25.07361 -348.573852) (xy 24.80945 -348.573852) (xy 24.80945 -347.611192)
			)
		)
	)
	(zone
		(layer "In6.Cu")
		(hatch none 0.5)
		(connect_pads
			(clearance 0)
		)
		(min_thickness 0.25)
		(keepout
			(tracks allowed)
			(vias allowed)
			(pads allowed)
			(copperpour allowed)
			(footprints allowed)
		)
		(placement
			(enabled no)
			(sheetname "")
		)
		(fill
			(thermal_gap 0.5)
			(thermal_bridge_width 0.5)
			(island_removal_mode 0)
		)
		(polygon
			(pts
				(xy 50.00117 -347.616272) (xy 50.00117 -348.408752) (xy 49.76241 -348.408752) (xy 49.76241 -347.616272)
			)
		)
	)
	(zone
		(layer "In6.Cu")
		(hatch none 0.5)
		(connect_pads
			(clearance 0)
		)
		(min_thickness 0.25)
		(keepout
			(tracks allowed)
			(vias allowed)
			(pads allowed)
			(copperpour allowed)
			(footprints allowed)
		)
		(placement
			(enabled no)
			(sheetname "")
		)
		(fill
			(thermal_gap 0.5)
			(thermal_bridge_width 0.5)
			(island_removal_mode 0)
		)
		(polygon
			(pts
				(xy 68.54317 -338.716112) (xy 68.54317 -339.506052) (xy 68.41109 -339.506052) (xy 68.41109 -338.716112)
			)
		)
	)
	(zone
		(layer "In6.Cu")
		(hatch none 0.5)
		(connect_pads
			(clearance 0)
		)
		(min_thickness 0.25)
		(keepout
			(tracks allowed)
			(vias allowed)
			(pads allowed)
			(copperpour allowed)
			(footprints allowed)
		)
		(placement
			(enabled no)
			(sheetname "")
		)
		(fill
			(thermal_gap 0.5)
			(thermal_bridge_width 0.5)
			(island_removal_mode 0)
		)
		(polygon
			(pts
				(xy 189.53607 -388.360666) (xy 189.53607 -387.814058) (xy 190.027814 -387.814058) (xy 190.027814 -388.360666)
			)
		)
	)
	(zone
		(layer "In6.Cu")
		(hatch none 0.5)
		(connect_pads
			(clearance 0)
		)
		(min_thickness 0.25)
		(keepout
			(tracks allowed)
			(vias allowed)
			(pads allowed)
			(copperpour allowed)
			(footprints allowed)
		)
		(placement
			(enabled no)
			(sheetname "")
		)
		(fill
			(thermal_gap 0.5)
			(thermal_bridge_width 0.5)
			(island_removal_mode 0)
		)
		(polygon
			(pts
				(xy 294.590724 -349.06966) (xy 294.590724 -348.523052) (xy 295.082468 -348.523052) (xy 295.082468 -349.06966)
			)
		)
	)
	(zone
		(layer "In6.Cu")
		(hatch none 0.5)
		(connect_pads
			(clearance 0)
		)
		(min_thickness 0.25)
		(keepout
			(tracks allowed)
			(vias allowed)
			(pads allowed)
			(copperpour allowed)
			(footprints allowed)
		)
		(placement
			(enabled no)
			(sheetname "")
		)
		(fill
			(thermal_gap 0.5)
			(thermal_bridge_width 0.5)
			(island_removal_mode 0)
		)
		(polygon
			(pts
				(xy 264.321798 -191.861948) (xy 264.321798 -319.66281) (xy 308.66588 -319.66281) (xy 308.66588 -191.861948)
			)
		)
	)
	(zone
		(layer "In6.Cu")
		(hatch none 0.5)
		(connect_pads
			(clearance 0)
		)
		(min_thickness 0.25)
		(keepout
			(tracks allowed)
			(vias allowed)
			(pads allowed)
			(copperpour allowed)
			(footprints allowed)
		)
		(placement
			(enabled no)
			(sheetname "")
		)
		(fill
			(thermal_gap 0.5)
			(thermal_bridge_width 0.5)
			(island_removal_mode 0)
		)
		(polygon
			(pts
				(xy 319.812924 -337.348576) (xy 319.812924 -336.801968) (xy 320.304668 -336.801968) (xy 320.304668 -337.348576)
			)
		)
	)
	(zone
		(layer "In6.Cu")
		(hatch none 0.5)
		(connect_pads
			(clearance 0)
		)
		(min_thickness 0.25)
		(keepout
			(tracks allowed)
			(vias allowed)
			(pads allowed)
			(copperpour allowed)
			(footprints allowed)
		)
		(placement
			(enabled no)
			(sheetname "")
		)
		(fill
			(thermal_gap 0.5)
			(thermal_bridge_width 0.5)
			(island_removal_mode 0)
		)
		(polygon
			(pts
				(xy 391.507218 -178.226212) (xy 391.507218 -179.115212) (xy 391.227818 -179.115212) (xy 391.227818 -178.226212)
			)
		)
	)
	(zone
		(layer "In6.Cu")
		(hatch none 0.5)
		(connect_pads
			(clearance 0)
		)
		(min_thickness 0.25)
		(keepout
			(tracks allowed)
			(vias allowed)
			(pads allowed)
			(copperpour allowed)
			(footprints allowed)
		)
		(placement
			(enabled no)
			(sheetname "")
		)
		(fill
			(thermal_gap 0.5)
			(thermal_bridge_width 0.5)
			(island_removal_mode 0)
		)
		(polygon
			(pts
				(xy 358.131618 -164.916612) (xy 358.131618 -165.754812) (xy 357.877618 -165.754812) (xy 357.877618 -164.916612)
			)
		)
	)
	(zone
		(layer "In6.Cu")
		(hatch none 0.5)
		(connect_pads
			(clearance 0)
		)
		(min_thickness 0.25)
		(keepout
			(tracks allowed)
			(vias allowed)
			(pads allowed)
			(copperpour allowed)
			(footprints allowed)
		)
		(placement
			(enabled no)
			(sheetname "")
		)
		(fill
			(thermal_gap 0.5)
			(thermal_bridge_width 0.5)
			(island_removal_mode 0)
		)
		(polygon
			(pts
				(xy 349.800418 -156.610812) (xy 349.800418 -157.550612) (xy 349.597218 -157.550612) (xy 349.597218 -156.610812)
			)
		)
	)
	(zone
		(layer "In6.Cu")
		(hatch none 0.5)
		(connect_pads
			(clearance 0)
		)
		(min_thickness 0.25)
		(keepout
			(tracks allowed)
			(vias allowed)
			(pads allowed)
			(copperpour allowed)
			(footprints allowed)
		)
		(placement
			(enabled no)
			(sheetname "")
		)
		(fill
			(thermal_gap 0.5)
			(thermal_bridge_width 0.5)
			(island_removal_mode 0)
		)
		(polygon
			(pts
				(xy 383.176018 -178.251612) (xy 383.176018 -179.089812) (xy 382.922018 -179.089812) (xy 382.922018 -178.251612)
			)
		)
	)
	(zone
		(layer "In6.Cu")
		(hatch none 0.5)
		(connect_pads
			(clearance 0)
		)
		(min_thickness 0.25)
		(keepout
			(tracks allowed)
			(vias allowed)
			(pads allowed)
			(copperpour allowed)
			(footprints allowed)
		)
		(placement
			(enabled no)
			(sheetname "")
		)
		(fill
			(thermal_gap 0.5)
			(thermal_bridge_width 0.5)
			(island_removal_mode 0)
		)
		(polygon
			(pts
				(xy 33.35909 -347.677232) (xy 33.35909 -348.416372) (xy 32.99079 -348.416372) (xy 32.99079 -347.677232)
			)
		)
	)
	(zone
		(layer "In6.Cu")
		(hatch none 0.5)
		(connect_pads
			(clearance 0)
		)
		(min_thickness 0.25)
		(keepout
			(tracks allowed)
			(vias allowed)
			(pads allowed)
			(copperpour allowed)
			(footprints allowed)
		)
		(placement
			(enabled no)
			(sheetname "")
		)
		(fill
			(thermal_gap 0.5)
			(thermal_bridge_width 0.5)
			(island_removal_mode 0)
		)
		(polygon
			(pts
				(xy 369.25758 -178.324002) (xy 369.25758 -177.777394) (xy 369.749324 -177.777394) (xy 369.749324 -178.324002)
			)
		)
	)
	(zone
		(layer "In6.Cu")
		(hatch none 0.5)
		(connect_pads
			(clearance 0)
		)
		(min_thickness 0.25)
		(keepout
			(tracks allowed)
			(vias allowed)
			(pads allowed)
			(copperpour allowed)
			(footprints allowed)
		)
		(placement
			(enabled no)
			(sheetname "")
		)
		(fill
			(thermal_gap 0.5)
			(thermal_bridge_width 0.5)
			(island_removal_mode 0)
		)
		(polygon
			(pts
				(xy 93.59011 -338.769452) (xy 93.59011 -339.719412) (xy 93.36405 -339.719412) (xy 93.36405 -338.769452)
			)
		)
	)
	(zone
		(layer "In6.Cu")
		(hatch none 0.5)
		(connect_pads
			(clearance 0)
		)
		(min_thickness 0.25)
		(keepout
			(tracks allowed)
			(vias allowed)
			(pads allowed)
			(copperpour allowed)
			(footprints allowed)
		)
		(placement
			(enabled no)
			(sheetname "")
		)
		(fill
			(thermal_gap 0.5)
			(thermal_bridge_width 0.5)
			(island_removal_mode 0)
		)
		(polygon
			(pts
				(xy 368.72418 -179.492402) (xy 368.72418 -178.945794) (xy 369.215924 -178.945794) (xy 369.215924 -179.492402)
			)
		)
	)
	(zone
		(layer "In6.Cu")
		(hatch none 0.5)
		(connect_pads
			(clearance 0)
		)
		(min_thickness 0.25)
		(keepout
			(tracks allowed)
			(vias allowed)
			(pads allowed)
			(copperpour allowed)
			(footprints allowed)
		)
		(placement
			(enabled no)
			(sheetname "")
		)
		(fill
			(thermal_gap 0.5)
			(thermal_bridge_width 0.5)
			(island_removal_mode 0)
		)
		(polygon
			(pts
				(xy 98.390964 -338.500212) (xy 98.390964 -337.953604) (xy 98.882708 -337.953604) (xy 98.882708 -338.500212)
			)
		)
	)
	(zone
		(layer "In6.Cu")
		(hatch none 0.5)
		(connect_pads
			(clearance 0)
		)
		(min_thickness 0.25)
		(keepout
			(tracks allowed)
			(vias allowed)
			(pads allowed)
			(copperpour allowed)
			(footprints allowed)
		)
		(placement
			(enabled no)
			(sheetname "")
		)
		(fill
			(thermal_gap 0.5)
			(thermal_bridge_width 0.5)
			(island_removal_mode 0)
		)
		(polygon
			(pts
				(xy 76.89469 -338.703412) (xy 76.89469 -339.559392) (xy 76.72451 -339.559392) (xy 76.72451 -338.703412)
			)
		)
	)
	(zone
		(layer "In6.Cu")
		(hatch none 0.5)
		(connect_pads
			(clearance 0)
		)
		(min_thickness 0.25)
		(keepout
			(tracks allowed)
			(vias allowed)
			(pads allowed)
			(copperpour allowed)
			(footprints allowed)
		)
		(placement
			(enabled no)
			(sheetname "")
		)
		(fill
			(thermal_gap 0.5)
			(thermal_bridge_width 0.5)
			(island_removal_mode 0)
		)
		(polygon
			(pts
				(xy 85.23605 -338.688172) (xy 85.23605 -339.572092) (xy 85.03793 -339.572092) (xy 85.03793 -338.688172)
			)
		)
	)
	(zone
		(layer "In6.Cu")
		(hatch none 0.5)
		(connect_pads
			(clearance 0)
		)
		(min_thickness 0.25)
		(keepout
			(tracks allowed)
			(vias allowed)
			(pads allowed)
			(copperpour allowed)
			(footprints allowed)
		)
		(placement
			(enabled no)
			(sheetname "")
		)
		(fill
			(thermal_gap 0.5)
			(thermal_bridge_width 0.5)
			(island_removal_mode 0)
		)
		(polygon
			(pts
				(xy 51.71567 -350.387412) (xy 51.71567 -351.245932) (xy 51.53025 -351.245932) (xy 51.53025 -350.387412)
			)
		)
	)
	(zone
		(layer "In6.Cu")
		(hatch none 0.5)
		(connect_pads
			(clearance 0)
		)
		(min_thickness 0.25)
		(keepout
			(tracks allowed)
			(vias allowed)
			(pads allowed)
			(copperpour allowed)
			(footprints allowed)
		)
		(placement
			(enabled no)
			(sheetname "")
		)
		(fill
			(thermal_gap 0.5)
			(thermal_bridge_width 0.5)
			(island_removal_mode 0)
		)
		(polygon
			(pts
				(xy 418.656008 -355.06025) (xy 418.656008 -354.513642) (xy 419.147752 -354.513642) (xy 419.147752 -355.06025)
			)
		)
	)
	(zone
		(layer "In6.Cu")
		(hatch none 0.5)
		(connect_pads
			(clearance 0)
		)
		(min_thickness 0.25)
		(keepout
			(tracks allowed)
			(vias allowed)
			(pads allowed)
			(copperpour allowed)
			(footprints allowed)
		)
		(placement
			(enabled no)
			(sheetname "")
		)
		(fill
			(thermal_gap 0.5)
			(thermal_bridge_width 0.5)
			(island_removal_mode 0)
		)
		(polygon
			(pts
				(xy 408.144218 -163.875212) (xy 407.991818 -163.875212) (xy 407.941018 -163.926012) (xy 407.941018 -164.891212)
				(xy 408.042618 -164.992812) (xy 408.220418 -164.992812) (xy 408.322018 -164.891212) (xy 408.322018 -164.053012)
			)
		)
	)
	(zone
		(layer "In6.Cu")
		(hatch none 0.5)
		(connect_pads
			(clearance 0)
		)
		(min_thickness 0.25)
		(keepout
			(tracks allowed)
			(vias allowed)
			(pads allowed)
			(copperpour allowed)
			(footprints allowed)
		)
		(placement
			(enabled no)
			(sheetname "")
		)
		(fill
			(thermal_gap 0.5)
			(thermal_bridge_width 0.5)
			(island_removal_mode 0)
		)
		(polygon
			(pts
				(xy 100.17379 -340.885272) (xy 100.17379 -341.698072) (xy 99.96297 -341.698072) (xy 99.96297 -340.885272)
			)
		)
	)
	(zone
		(layer "In6.Cu")
		(hatch none 0.5)
		(connect_pads
			(clearance 0)
		)
		(min_thickness 0.25)
		(keepout
			(tracks allowed)
			(vias allowed)
			(pads allowed)
			(copperpour allowed)
			(footprints allowed)
		)
		(placement
			(enabled no)
			(sheetname "")
		)
		(fill
			(thermal_gap 0.5)
			(thermal_bridge_width 0.5)
			(island_removal_mode 0)
		)
		(polygon
			(pts
				(xy 43.38955 -350.433132) (xy 43.38955 -351.266252) (xy 43.13809 -351.266252) (xy 43.13809 -350.433132)
			)
		)
	)
	(zone
		(layer "In6.Cu")
		(hatch none 0.5)
		(connect_pads
			(clearance 0)
		)
		(min_thickness 0.25)
		(keepout
			(tracks allowed)
			(vias allowed)
			(pads allowed)
			(copperpour allowed)
			(footprints allowed)
		)
		(placement
			(enabled no)
			(sheetname "")
		)
		(fill
			(thermal_gap 0.5)
			(thermal_bridge_width 0.5)
			(island_removal_mode 0)
		)
		(polygon
			(pts
				(xy 101.85019 -343.651332) (xy 101.85019 -344.415872) (xy 101.67747 -344.415872) (xy 101.67747 -343.651332)
			)
		)
	)
	(zone
		(layer "In6.Cu")
		(hatch none 0.5)
		(connect_pads
			(clearance 0)
		)
		(min_thickness 0.25)
		(keepout
			(tracks allowed)
			(vias allowed)
			(pads allowed)
			(copperpour allowed)
			(footprints allowed)
		)
		(placement
			(enabled no)
			(sheetname "")
		)
		(fill
			(thermal_gap 0.5)
			(thermal_bridge_width 0.5)
			(island_removal_mode 0)
		)
		(polygon
			(pts
				(xy 78.613 -178.324002) (xy 78.613 -177.777394) (xy 79.104744 -177.777394) (xy 79.104744 -178.324002)
			)
		)
	)
	(zone
		(layer "In6.Cu")
		(hatch none 0.5)
		(connect_pads
			(clearance 0)
		)
		(min_thickness 0.25)
		(keepout
			(tracks allowed)
			(vias allowed)
			(pads allowed)
			(copperpour allowed)
			(footprints allowed)
		)
		(placement
			(enabled no)
			(sheetname "")
		)
		(fill
			(thermal_gap 0.5)
			(thermal_bridge_width 0.5)
			(island_removal_mode 0)
		)
		(polygon
			(pts
				(xy 369.25758 -179.848002) (xy 369.25758 -179.301394) (xy 369.749324 -179.301394) (xy 369.749324 -179.848002)
			)
		)
	)
	(zone
		(layer "In6.Cu")
		(hatch none 0.5)
		(connect_pads
			(clearance 0)
		)
		(min_thickness 0.25)
		(keepout
			(tracks allowed)
			(vias allowed)
			(pads allowed)
			(copperpour allowed)
			(footprints allowed)
		)
		(placement
			(enabled no)
			(sheetname "")
		)
		(fill
			(thermal_gap 0.5)
			(thermal_bridge_width 0.5)
			(island_removal_mode 0)
		)
		(polygon
			(pts
				(xy 336.526124 -337.326986) (xy 336.526124 -336.780378) (xy 337.017868 -336.780378) (xy 337.017868 -337.326986)
			)
		)
	)
	(zone
		(layer "In6.Cu")
		(hatch none 0.5)
		(connect_pads
			(clearance 0)
		)
		(min_thickness 0.25)
		(keepout
			(tracks not_allowed)
			(vias allowed)
			(pads allowed)
			(copperpour not_allowed)
			(footprints allowed)
		)
		(placement
			(enabled no)
			(sheetname "")
		)
		(fill
			(thermal_gap 0.5)
			(thermal_bridge_width 0.5)
			(island_removal_mode 0)
		)
		(polygon
			(pts
				(arc
					(start 301.697136 -413.170116)
					(mid 293.443152 -413.170116)
					(end 301.697136 -413.170116)
				)
			)
		)
	)
	(zone
		(layer "In6.Cu")
		(hatch none 0.5)
		(connect_pads
			(clearance 0)
		)
		(min_thickness 0.25)
		(keepout
			(tracks allowed)
			(vias allowed)
			(pads allowed)
			(copperpour allowed)
			(footprints allowed)
		)
		(placement
			(enabled no)
			(sheetname "")
		)
		(fill
			(thermal_gap 0.5)
			(thermal_bridge_width 0.5)
			(island_removal_mode 0)
		)
		(polygon
			(pts
				(xy 60.02401 -350.461072) (xy 60.02401 -351.245932) (xy 59.80557 -351.245932) (xy 59.80557 -350.461072)
			)
		)
	)
	(zone
		(layer "In6.Cu")
		(hatch none 0.5)
		(connect_pads
			(clearance 0)
		)
		(min_thickness 0.25)
		(keepout
			(tracks allowed)
			(vias allowed)
			(pads allowed)
			(copperpour allowed)
			(footprints allowed)
		)
		(placement
			(enabled no)
			(sheetname "")
		)
		(fill
			(thermal_gap 0.5)
			(thermal_bridge_width 0.5)
			(island_removal_mode 0)
		)
		(polygon
			(pts
				(xy 75.955906 -296.612564) (xy 75.955906 -234.629198) (xy 75.564492 -234.237784) (xy 75.564492 -230.348028)
				(xy 75.497436 -230.280972) (xy 75.497436 -230.149908) (xy 75.927458 -229.719886) (xy 75.927458 -229.49027)
				(xy 75.487276 -229.050088) (xy 75.487276 -228.934264) (xy 75.955906 -228.465634) (xy 75.955906 -226.903534)
				(xy 75.943206 -226.903534) (xy 75.864466 -226.824794) (xy 75.864466 -226.774756) (xy 75.955906 -226.683316)
				(xy 75.955906 -226.666044) (xy 76.08951 -226.53244) (xy 76.02093 -226.46386) (xy 76.02093 -226.301046)
				(xy 76.082398 -226.239578) (xy 76.082398 -225.69551) (xy 75.763374 -225.376486) (xy 75.763374 -225.302318)
				(xy 76.092304 -224.973388) (xy 76.10729 -224.973388) (xy 76.363322 -224.717356) (xy 76.363322 -224.414334)
				(xy 76.493624 -224.284032) (xy 76.493624 -224.067116) (xy 76.494386 -224.066354) (xy 76.494386 -223.333564)
				(xy 78.653386 -221.174564) (xy 147.919186 -221.174564) (xy 147.919186 -296.612564)
			)
		)
	)
	(zone
		(layer "In6.Cu")
		(hatch none 0.5)
		(connect_pads
			(clearance 0)
		)
		(min_thickness 0.25)
		(keepout
			(tracks allowed)
			(vias allowed)
			(pads allowed)
			(copperpour allowed)
			(footprints allowed)
		)
		(placement
			(enabled no)
			(sheetname "")
		)
		(fill
			(thermal_gap 0.5)
			(thermal_bridge_width 0.5)
			(island_removal_mode 0)
		)
		(polygon
			(pts
				(xy 34.95675 -350.514412) (xy 34.95675 -351.411032) (xy 34.82467 -351.411032) (xy 34.82467 -350.514412)
			)
		)
	)
	(zone
		(layer "In6.Cu")
		(hatch none 0.5)
		(connect_pads
			(clearance 0)
		)
		(min_thickness 0.25)
		(keepout
			(tracks allowed)
			(vias allowed)
			(pads allowed)
			(copperpour allowed)
			(footprints allowed)
		)
		(placement
			(enabled no)
			(sheetname "")
		)
		(fill
			(thermal_gap 0.5)
			(thermal_bridge_width 0.5)
			(island_removal_mode 0)
		)
		(polygon
			(pts
				(xy 399.914618 -172.511212) (xy 399.635218 -172.511212) (xy 399.609818 -172.536612) (xy 399.609818 -173.501812)
				(xy 399.660618 -173.552612) (xy 399.889218 -173.552612) (xy 399.965418 -173.476412) (xy 399.965418 -172.562012)
			)
		)
	)
	(zone
		(layer "In6.Cu")
		(hatch none 0.5)
		(connect_pads
			(clearance 0)
		)
		(min_thickness 0.25)
		(keepout
			(tracks allowed)
			(vias allowed)
			(pads allowed)
			(copperpour allowed)
			(footprints allowed)
		)
		(placement
			(enabled no)
			(sheetname "")
		)
		(fill
			(thermal_gap 0.5)
			(thermal_bridge_width 0.5)
			(island_removal_mode 0)
		)
		(polygon
			(pts
				(xy 369.25758 -179.086002) (xy 369.25758 -178.539394) (xy 369.749324 -178.539394) (xy 369.749324 -179.086002)
			)
		)
	)
	(zone
		(layer "In6.Cu")
		(hatch none 0.5)
		(connect_pads
			(clearance 0)
		)
		(min_thickness 0.25)
		(keepout
			(tracks allowed)
			(vias allowed)
			(pads allowed)
			(copperpour allowed)
			(footprints allowed)
		)
		(placement
			(enabled no)
			(sheetname "")
		)
		(fill
			(thermal_gap 0.5)
			(thermal_bridge_width 0.5)
			(island_removal_mode 0)
		)
		(polygon
			(pts
				(xy 98.507804 -339.262212) (xy 98.507804 -338.715604) (xy 98.999548 -338.715604) (xy 98.999548 -339.262212)
			)
		)
	)
	(zone
		(layer "In6.Cu")
		(hatch none 0.5)
		(connect_pads
			(clearance 0)
		)
		(min_thickness 0.25)
		(keepout
			(tracks allowed)
			(vias allowed)
			(pads allowed)
			(copperpour allowed)
			(footprints allowed)
		)
		(placement
			(enabled no)
			(sheetname "")
		)
		(fill
			(thermal_gap 0.5)
			(thermal_bridge_width 0.5)
			(island_removal_mode 0)
		)
		(polygon
			(pts
				(xy 78.8924 -180.610002) (xy 78.8924 -180.063394) (xy 79.384144 -180.063394) (xy 79.384144 -180.610002)
			)
		)
	)
	(zone
		(layer "In6.Cu")
		(hatch none 0.5)
		(connect_pads
			(clearance 0)
		)
		(min_thickness 0.25)
		(keepout
			(tracks allowed)
			(vias allowed)
			(pads allowed)
			(copperpour allowed)
			(footprints allowed)
		)
		(placement
			(enabled no)
			(sheetname "")
		)
		(fill
			(thermal_gap 0.5)
			(thermal_bridge_width 0.5)
			(island_removal_mode 0)
		)
		(polygon
			(pts
				(xy 26.68143 -350.499172) (xy 26.68143 -351.411032) (xy 26.51125 -351.411032) (xy 26.51125 -350.499172)
			)
		)
	)
	(zone
		(layer "In6.Cu")
		(hatch none 0.5)
		(connect_pads
			(clearance 0)
		)
		(min_thickness 0.25)
		(keepout
			(tracks allowed)
			(vias allowed)
			(pads allowed)
			(copperpour allowed)
			(footprints allowed)
		)
		(placement
			(enabled no)
			(sheetname "")
		)
		(fill
			(thermal_gap 0.5)
			(thermal_bridge_width 0.5)
			(island_removal_mode 0)
		)
		(polygon
			(pts
				(xy 302.947324 -349.06966) (xy 302.947324 -348.523052) (xy 303.439068 -348.523052) (xy 303.439068 -349.06966)
			)
		)
	)
	(zone
		(layer "In6.Cu")
		(hatch none 0.5)
		(connect_pads
			(clearance 0)
		)
		(min_thickness 0.25)
		(keepout
			(tracks allowed)
			(vias allowed)
			(pads allowed)
			(copperpour allowed)
			(footprints allowed)
		)
		(placement
			(enabled no)
			(sheetname "")
		)
		(fill
			(thermal_gap 0.5)
			(thermal_bridge_width 0.5)
			(island_removal_mode 0)
		)
		(polygon
			(pts
				(xy 66.86677 -335.891632) (xy 66.86677 -336.734912) (xy 66.62801 -336.734912) (xy 66.62801 -335.891632)
			)
		)
	)
	(zone
		(layer "In6.Cu")
		(hatch none 0.5)
		(connect_pads
			(clearance 0)
		)
		(min_thickness 0.25)
		(keepout
			(tracks allowed)
			(vias allowed)
			(pads allowed)
			(copperpour allowed)
			(footprints allowed)
		)
		(placement
			(enabled no)
			(sheetname "")
		)
		(fill
			(thermal_gap 0.5)
			(thermal_bridge_width 0.5)
			(island_removal_mode 0)
		)
		(polygon
			(pts
				(xy 278.004524 -349.06966) (xy 278.004524 -348.523052) (xy 278.496268 -348.523052) (xy 278.496268 -349.06966)
			)
		)
	)
	(zone
		(layer "In6.Cu")
		(hatch none 0.5)
		(connect_pads
			(clearance 0)
		)
		(min_thickness 0.25)
		(keepout
			(tracks allowed)
			(vias allowed)
			(pads allowed)
			(copperpour allowed)
			(footprints allowed)
		)
		(placement
			(enabled no)
			(sheetname "")
		)
		(fill
			(thermal_gap 0.5)
			(thermal_bridge_width 0.5)
			(island_removal_mode 0)
		)
		(polygon
			(pts
				(xy 58.26125 -347.496892) (xy 58.26125 -348.525592) (xy 58.10377 -348.525592) (xy 58.10377 -347.496892)
			)
		)
	)
	(zone
		(layer "In6.Cu")
		(hatch none 0.5)
		(connect_pads
			(clearance 0)
		)
		(min_thickness 0.25)
		(keepout
			(tracks allowed)
			(vias allowed)
			(pads allowed)
			(copperpour allowed)
			(footprints allowed)
		)
		(placement
			(enabled no)
			(sheetname "")
		)
		(fill
			(thermal_gap 0.5)
			(thermal_bridge_width 0.5)
			(island_removal_mode 0)
		)
		(polygon
			(pts
				(xy 266.699238 -332.160372) (xy 265.464798 -332.160372) (xy 264.105898 -330.801472) (xy 264.105898 -323.234812)
				(xy 266.269978 -321.070732) (xy 308.916578 -321.070732) (xy 310.420258 -319.567052) (xy 310.420258 -318.096392)
				(xy 330.613258 -297.903392) (xy 338.784438 -297.903392) (xy 339.574378 -297.113452) (xy 339.574378 -296.293032)
				(xy 339.505798 -296.224452) (xy 338.946998 -296.224452) (xy 338.792058 -296.379392) (xy 338.792058 -296.788332)
				(xy 338.438998 -297.141392) (xy 330.260198 -297.141392) (xy 309.653178 -317.748412) (xy 309.653178 -317.837312)
				(xy 309.653178 -319.262252) (xy 308.624478 -320.290952) (xy 265.993118 -320.290952) (xy 263.420098 -322.863972)
				(xy 263.420098 -331.149452) (xy 265.175238 -332.904592) (xy 266.694158 -332.904592) (xy 267.044678 -333.255112)
				(xy 267.141198 -333.255112) (xy 267.280898 -333.115412) (xy 267.280898 -331.842872) (xy 267.016738 -331.842872)
			)
		)
	)
	(zone
		(layer "In6.Cu")
		(hatch none 0.5)
		(connect_pads
			(clearance 0)
		)
		(min_thickness 0.25)
		(keepout
			(tracks allowed)
			(vias allowed)
			(pads allowed)
			(copperpour allowed)
			(footprints allowed)
		)
		(placement
			(enabled no)
			(sheetname "")
		)
		(fill
			(thermal_gap 0.5)
			(thermal_bridge_width 0.5)
			(island_removal_mode 0)
		)
		(polygon
			(pts
				(xy 98.365564 -337.738212) (xy 98.365564 -337.191604) (xy 98.857308 -337.191604) (xy 98.857308 -337.738212)
			)
		)
	)
	(zone
		(layers "In6.Cu" "In11.Cu" "In15.Cu")
		(hatch none 0.5)
		(connect_pads
			(clearance 0)
		)
		(min_thickness 0.25)
		(keepout
			(tracks not_allowed)
			(vias allowed)
			(pads allowed)
			(copperpour not_allowed)
			(footprints allowed)
		)
		(placement
			(enabled no)
			(sheetname "")
		)
		(fill yes
			(thermal_gap 0.5)
			(thermal_bridge_width 0.5)
			(island_removal_mode 0)
		)
		(polygon
			(pts
				(arc
					(start 262.28802 -360.764074)
					(mid 253.9619 -360.764074)
					(end 262.28802 -360.764074)
				)
			)
		)
	)
	(zone
		(layers "In6.Cu" "In15.Cu")
		(hatch none 0.5)
		(connect_pads
			(clearance 0)
		)
		(min_thickness 0.25)
		(keepout
			(tracks not_allowed)
			(vias allowed)
			(pads allowed)
			(copperpour not_allowed)
			(footprints allowed)
		)
		(placement
			(enabled no)
			(sheetname "")
		)
		(fill yes
			(thermal_gap 0.5)
			(thermal_bridge_width 0.5)
			(island_removal_mode 0)
		)
		(polygon
			(pts
				(arc
					(start 431.1269 -413.170116)
					(mid 422.872916 -413.170116)
					(end 431.1269 -413.170116)
				)
			)
		)
	)
	(zone
		(layer "In7.Cu")
		(hatch none 0.5)
		(connect_pads
			(clearance 0)
		)
		(min_thickness 0.25)
		(keepout
			(tracks not_allowed)
			(vias allowed)
			(pads allowed)
			(copperpour not_allowed)
			(footprints allowed)
		)
		(placement
			(enabled no)
			(sheetname "")
		)
		(fill
			(thermal_gap 0.5)
			(thermal_bridge_width 0.5)
			(island_removal_mode 0)
		)
		(polygon
			(pts
				(arc
					(start 316.141608 -428.96028)
					(mid 316.163926 -429.014162)
					(end 316.217808 -429.03648)
				)
				(arc
					(start 317.157608 -429.03648)
					(mid 317.21149 -429.014162)
					(end 317.233808 -428.96028)
				)
				(arc
					(start 317.233808 -426.418756)
					(mid 317.21149 -426.364874)
					(end 317.157608 -426.342556)
				)
				(arc
					(start 316.217808 -426.342556)
					(mid 316.163926 -426.364874)
					(end 316.141608 -426.418756)
				)
				(arc
					(start 316.141608 -427.146212)
					(mid 316.143607 -427.163553)
					(end 316.149482 -427.179994)
				)
				(arc
					(start 316.382908 -427.656244)
					(mid 316.390691 -427.689772)
					(end 316.382908 -427.7233)
				)
				(arc
					(start 316.149482 -428.19955)
					(mid 316.143587 -428.215986)
					(end 316.141608 -428.233332)
				)
			)
		)
	)
	(zone
		(layer "In7.Cu")
		(hatch none 0.5)
		(connect_pads
			(clearance 0)
		)
		(min_thickness 0.25)
		(keepout
			(tracks not_allowed)
			(vias allowed)
			(pads allowed)
			(copperpour not_allowed)
			(footprints allowed)
		)
		(placement
			(enabled no)
			(sheetname "")
		)
		(fill
			(thermal_gap 0.5)
			(thermal_bridge_width 0.5)
			(island_removal_mode 0)
		)
		(polygon
			(pts
				(arc
					(start 383.241804 -428.96028)
					(mid 383.264122 -429.014162)
					(end 383.318004 -429.03648)
				)
				(arc
					(start 384.257804 -429.03648)
					(mid 384.311686 -429.014162)
					(end 384.334004 -428.96028)
				)
				(arc
					(start 384.334004 -426.418756)
					(mid 384.311686 -426.364874)
					(end 384.257804 -426.342556)
				)
				(arc
					(start 383.318004 -426.342556)
					(mid 383.264122 -426.364874)
					(end 383.241804 -426.418756)
				)
				(arc
					(start 383.241804 -427.146212)
					(mid 383.243803 -427.163553)
					(end 383.249678 -427.179994)
				)
				(arc
					(start 383.483104 -427.656244)
					(mid 383.490887 -427.689772)
					(end 383.483104 -427.7233)
				)
				(arc
					(start 383.249678 -428.19955)
					(mid 383.243783 -428.215986)
					(end 383.241804 -428.233332)
				)
			)
		)
	)
	(zone
		(layer "In7.Cu")
		(hatch none 0.5)
		(connect_pads
			(clearance 0)
		)
		(min_thickness 0.25)
		(keepout
			(tracks not_allowed)
			(vias allowed)
			(pads allowed)
			(copperpour not_allowed)
			(footprints allowed)
		)
		(placement
			(enabled no)
			(sheetname "")
		)
		(fill
			(thermal_gap 0.5)
			(thermal_bridge_width 0.5)
			(island_removal_mode 0)
		)
		(polygon
			(pts
				(arc
					(start 402.242274 -431.560478)
					(mid 402.264592 -431.61436)
					(end 402.318474 -431.636678)
				)
				(arc
					(start 403.258274 -431.636678)
					(mid 403.312156 -431.61436)
					(end 403.334474 -431.560478)
				)
				(arc
					(start 403.334474 -429.018954)
					(mid 403.312156 -428.965072)
					(end 403.258274 -428.942754)
				)
				(arc
					(start 402.318474 -428.942754)
					(mid 402.264592 -428.965072)
					(end 402.242274 -429.018954)
				)
			)
		)
	)
	(zone
		(layer "In7.Cu")
		(hatch none 0.5)
		(connect_pads
			(clearance 0)
		)
		(min_thickness 0.25)
		(keepout
			(tracks not_allowed)
			(vias allowed)
			(pads allowed)
			(copperpour not_allowed)
			(footprints allowed)
		)
		(placement
			(enabled no)
			(sheetname "")
		)
		(fill
			(thermal_gap 0.5)
			(thermal_bridge_width 0.5)
			(island_removal_mode 0)
		)
		(polygon
			(pts
				(arc
					(start 389.242046 -431.560478)
					(mid 389.264364 -431.61436)
					(end 389.318246 -431.636678)
				)
				(arc
					(start 390.258046 -431.636678)
					(mid 390.311928 -431.61436)
					(end 390.334246 -431.560478)
				)
				(arc
					(start 390.334246 -429.018954)
					(mid 390.311928 -428.965072)
					(end 390.258046 -428.942754)
				)
				(arc
					(start 389.318246 -428.942754)
					(mid 389.264364 -428.965072)
					(end 389.242046 -429.018954)
				)
			)
		)
	)
	(zone
		(layer "In7.Cu")
		(hatch none 0.5)
		(connect_pads
			(clearance 0)
		)
		(min_thickness 0.25)
		(keepout
			(tracks not_allowed)
			(vias allowed)
			(pads allowed)
			(copperpour not_allowed)
			(footprints allowed)
		)
		(placement
			(enabled no)
			(sheetname "")
		)
		(fill
			(thermal_gap 0.5)
			(thermal_bridge_width 0.5)
			(island_removal_mode 0)
		)
		(polygon
			(pts
				(arc
					(start 381.241808 -427.960536)
					(mid 381.264126 -428.014418)
					(end 381.318008 -428.036736)
				)
				(arc
					(start 382.257808 -428.036736)
					(mid 382.31169 -428.014418)
					(end 382.334008 -427.960536)
				)
				(arc
					(start 382.334008 -425.419012)
					(mid 382.31169 -425.36513)
					(end 382.257808 -425.342812)
				)
				(arc
					(start 381.318008 -425.342812)
					(mid 381.264126 -425.36513)
					(end 381.241808 -425.419012)
				)
				(arc
					(start 381.241808 -426.146468)
					(mid 381.243807 -426.163809)
					(end 381.249682 -426.18025)
				)
				(arc
					(start 381.483108 -426.6565)
					(mid 381.490891 -426.690028)
					(end 381.483108 -426.723556)
				)
				(arc
					(start 381.249682 -427.199806)
					(mid 381.243787 -427.216242)
					(end 381.241808 -427.233588)
				)
			)
		)
	)
	(zone
		(layer "In7.Cu")
		(hatch none 0.5)
		(connect_pads
			(clearance 0)
		)
		(min_thickness 0.25)
		(keepout
			(tracks not_allowed)
			(vias allowed)
			(pads allowed)
			(copperpour not_allowed)
			(footprints allowed)
		)
		(placement
			(enabled no)
			(sheetname "")
		)
		(fill
			(thermal_gap 0.5)
			(thermal_bridge_width 0.5)
			(island_removal_mode 0)
		)
		(polygon
			(pts
				(arc
					(start 389.241792 -427.960536)
					(mid 389.26411 -428.014418)
					(end 389.317992 -428.036736)
				)
				(arc
					(start 390.257792 -428.036736)
					(mid 390.311674 -428.014418)
					(end 390.333992 -427.960536)
				)
				(arc
					(start 390.333992 -425.419012)
					(mid 390.311674 -425.36513)
					(end 390.257792 -425.342812)
				)
				(arc
					(start 389.317992 -425.342812)
					(mid 389.26411 -425.36513)
					(end 389.241792 -425.419012)
				)
				(arc
					(start 389.241792 -426.146468)
					(mid 389.243791 -426.163809)
					(end 389.249666 -426.18025)
				)
				(arc
					(start 389.483092 -426.6565)
					(mid 389.490875 -426.690028)
					(end 389.483092 -426.723556)
				)
				(arc
					(start 389.249666 -427.199806)
					(mid 389.243771 -427.216242)
					(end 389.241792 -427.233588)
				)
			)
		)
	)
	(zone
		(layer "In7.Cu")
		(hatch none 0.5)
		(connect_pads
			(clearance 0)
		)
		(min_thickness 0.25)
		(keepout
			(tracks not_allowed)
			(vias allowed)
			(pads allowed)
			(copperpour not_allowed)
			(footprints allowed)
		)
		(placement
			(enabled no)
			(sheetname "")
		)
		(fill
			(thermal_gap 0.5)
			(thermal_bridge_width 0.5)
			(island_removal_mode 0)
		)
		(polygon
			(pts
				(arc
					(start 331.142086 -431.560478)
					(mid 331.164404 -431.61436)
					(end 331.218286 -431.636678)
				)
				(arc
					(start 332.158086 -431.636678)
					(mid 332.211968 -431.61436)
					(end 332.234286 -431.560478)
				)
				(arc
					(start 332.234286 -429.018954)
					(mid 332.211968 -428.965072)
					(end 332.158086 -428.942754)
				)
				(arc
					(start 331.218286 -428.942754)
					(mid 331.164404 -428.965072)
					(end 331.142086 -429.018954)
				)
			)
		)
	)
	(zone
		(layer "In7.Cu")
		(hatch none 0.5)
		(connect_pads
			(clearance 0)
		)
		(min_thickness 0.25)
		(keepout
			(tracks not_allowed)
			(vias allowed)
			(pads allowed)
			(copperpour not_allowed)
			(footprints allowed)
		)
		(placement
			(enabled no)
			(sheetname "")
		)
		(fill
			(thermal_gap 0.5)
			(thermal_bridge_width 0.5)
			(island_removal_mode 0)
		)
		(polygon
			(pts
				(arc
					(start 393.242038 -431.560478)
					(mid 393.264356 -431.61436)
					(end 393.318238 -431.636678)
				)
				(arc
					(start 394.258038 -431.636678)
					(mid 394.31192 -431.61436)
					(end 394.334238 -431.560478)
				)
				(arc
					(start 394.334238 -429.018954)
					(mid 394.31192 -428.965072)
					(end 394.258038 -428.942754)
				)
				(arc
					(start 393.318238 -428.942754)
					(mid 393.264356 -428.965072)
					(end 393.242038 -429.018954)
				)
			)
		)
	)
	(zone
		(layer "In7.Cu")
		(hatch none 0.5)
		(connect_pads
			(clearance 0)
		)
		(min_thickness 0.25)
		(keepout
			(tracks not_allowed)
			(vias allowed)
			(pads allowed)
			(copperpour not_allowed)
			(footprints allowed)
		)
		(placement
			(enabled no)
			(sheetname "")
		)
		(fill
			(thermal_gap 0.5)
			(thermal_bridge_width 0.5)
			(island_removal_mode 0)
		)
		(polygon
			(pts
				(arc
					(start 383.242058 -432.560476)
					(mid 383.264376 -432.614358)
					(end 383.318258 -432.636676)
				)
				(arc
					(start 384.258058 -432.636676)
					(mid 384.31194 -432.614358)
					(end 384.334258 -432.560476)
				)
				(arc
					(start 384.334258 -430.018952)
					(mid 384.31194 -429.96507)
					(end 384.258058 -429.942752)
				)
				(arc
					(start 383.318258 -429.942752)
					(mid 383.264376 -429.96507)
					(end 383.242058 -430.018952)
				)
			)
		)
	)
	(zone
		(layer "In7.Cu")
		(hatch none 0.5)
		(connect_pads
			(clearance 0)
		)
		(min_thickness 0.25)
		(keepout
			(tracks not_allowed)
			(vias allowed)
			(pads allowed)
			(copperpour not_allowed)
			(footprints allowed)
		)
		(placement
			(enabled no)
			(sheetname "")
		)
		(fill
			(thermal_gap 0.5)
			(thermal_bridge_width 0.5)
			(island_removal_mode 0)
		)
		(polygon
			(pts
				(arc
					(start 412.242254 -432.560476)
					(mid 412.264572 -432.614358)
					(end 412.318454 -432.636676)
				)
				(arc
					(start 413.258254 -432.636676)
					(mid 413.312136 -432.614358)
					(end 413.334454 -432.560476)
				)
				(arc
					(start 413.334454 -430.018952)
					(mid 413.312136 -429.96507)
					(end 413.258254 -429.942752)
				)
				(arc
					(start 412.318454 -429.942752)
					(mid 412.264572 -429.96507)
					(end 412.242254 -430.018952)
				)
			)
		)
	)
	(zone
		(layer "In7.Cu")
		(hatch none 0.5)
		(connect_pads
			(clearance 0)
		)
		(min_thickness 0.25)
		(keepout
			(tracks not_allowed)
			(vias allowed)
			(pads allowed)
			(copperpour not_allowed)
			(footprints allowed)
		)
		(placement
			(enabled no)
			(sheetname "")
		)
		(fill
			(thermal_gap 0.5)
			(thermal_bridge_width 0.5)
			(island_removal_mode 0)
		)
		(polygon
			(pts
				(arc
					(start 395.242034 -432.560476)
					(mid 395.264352 -432.614358)
					(end 395.318234 -432.636676)
				)
				(arc
					(start 396.258034 -432.636676)
					(mid 396.311916 -432.614358)
					(end 396.334234 -432.560476)
				)
				(arc
					(start 396.334234 -430.018952)
					(mid 396.311916 -429.96507)
					(end 396.258034 -429.942752)
				)
				(arc
					(start 395.318234 -429.942752)
					(mid 395.264352 -429.96507)
					(end 395.242034 -430.018952)
				)
			)
		)
	)
	(zone
		(layer "In7.Cu")
		(hatch none 0.5)
		(connect_pads
			(clearance 0)
		)
		(min_thickness 0.25)
		(keepout
			(tracks not_allowed)
			(vias allowed)
			(pads allowed)
			(copperpour not_allowed)
			(footprints allowed)
		)
		(placement
			(enabled no)
			(sheetname "")
		)
		(fill
			(thermal_gap 0.5)
			(thermal_bridge_width 0.5)
			(island_removal_mode 0)
		)
		(polygon
			(pts
				(arc
					(start 324.141592 -428.96028)
					(mid 324.16391 -429.014162)
					(end 324.217792 -429.03648)
				)
				(arc
					(start 325.157592 -429.03648)
					(mid 325.211474 -429.014162)
					(end 325.233792 -428.96028)
				)
				(arc
					(start 325.233792 -426.418756)
					(mid 325.211474 -426.364874)
					(end 325.157592 -426.342556)
				)
				(arc
					(start 324.217792 -426.342556)
					(mid 324.16391 -426.364874)
					(end 324.141592 -426.418756)
				)
				(arc
					(start 324.141592 -427.146212)
					(mid 324.143591 -427.163553)
					(end 324.149466 -427.179994)
				)
				(arc
					(start 324.382892 -427.656244)
					(mid 324.390675 -427.689772)
					(end 324.382892 -427.7233)
				)
				(arc
					(start 324.149466 -428.19955)
					(mid 324.143571 -428.215986)
					(end 324.141592 -428.233332)
				)
			)
		)
	)
	(zone
		(layer "In7.Cu")
		(hatch none 0.5)
		(connect_pads
			(clearance 0)
		)
		(min_thickness 0.25)
		(keepout
			(tracks not_allowed)
			(vias allowed)
			(pads allowed)
			(copperpour not_allowed)
			(footprints allowed)
		)
		(placement
			(enabled no)
			(sheetname "")
		)
		(fill
			(thermal_gap 0.5)
			(thermal_bridge_width 0.5)
			(island_removal_mode 0)
		)
		(polygon
			(pts
				(arc
					(start 393.241784 -427.960536)
					(mid 393.264102 -428.014418)
					(end 393.317984 -428.036736)
				)
				(arc
					(start 394.257784 -428.036736)
					(mid 394.311666 -428.014418)
					(end 394.333984 -427.960536)
				)
				(arc
					(start 394.333984 -425.419012)
					(mid 394.311666 -425.36513)
					(end 394.257784 -425.342812)
				)
				(arc
					(start 393.317984 -425.342812)
					(mid 393.264102 -425.36513)
					(end 393.241784 -425.419012)
				)
				(arc
					(start 393.241784 -426.146468)
					(mid 393.243783 -426.163809)
					(end 393.249658 -426.18025)
				)
				(arc
					(start 393.483084 -426.6565)
					(mid 393.490867 -426.690028)
					(end 393.483084 -426.723556)
				)
				(arc
					(start 393.249658 -427.199806)
					(mid 393.243763 -427.216242)
					(end 393.241784 -427.233588)
				)
			)
		)
	)
	(zone
		(layer "In7.Cu")
		(hatch none 0.5)
		(connect_pads
			(clearance 0)
		)
		(min_thickness 0.25)
		(keepout
			(tracks not_allowed)
			(vias allowed)
			(pads allowed)
			(copperpour not_allowed)
			(footprints allowed)
		)
		(placement
			(enabled no)
			(sheetname "")
		)
		(fill
			(thermal_gap 0.5)
			(thermal_bridge_width 0.5)
			(island_removal_mode 0)
		)
		(polygon
			(pts
				(arc
					(start 314.141612 -427.960536)
					(mid 314.16393 -428.014418)
					(end 314.217812 -428.036736)
				)
				(arc
					(start 315.157612 -428.036736)
					(mid 315.211494 -428.014418)
					(end 315.233812 -427.960536)
				)
				(arc
					(start 315.233812 -425.419012)
					(mid 315.211494 -425.36513)
					(end 315.157612 -425.342812)
				)
				(arc
					(start 314.217812 -425.342812)
					(mid 314.16393 -425.36513)
					(end 314.141612 -425.419012)
				)
				(arc
					(start 314.141612 -426.146468)
					(mid 314.143611 -426.163809)
					(end 314.149486 -426.18025)
				)
				(arc
					(start 314.382912 -426.6565)
					(mid 314.390695 -426.690028)
					(end 314.382912 -426.723556)
				)
				(arc
					(start 314.149486 -427.199806)
					(mid 314.143591 -427.216242)
					(end 314.141612 -427.233588)
				)
			)
		)
	)
	(zone
		(layer "In7.Cu")
		(hatch none 0.5)
		(connect_pads
			(clearance 0)
		)
		(min_thickness 0.25)
		(keepout
			(tracks not_allowed)
			(vias allowed)
			(pads allowed)
			(copperpour not_allowed)
			(footprints allowed)
		)
		(placement
			(enabled no)
			(sheetname "")
		)
		(fill
			(thermal_gap 0.5)
			(thermal_bridge_width 0.5)
			(island_removal_mode 0)
		)
		(polygon
			(pts
				(arc
					(start 385.2418 -427.960536)
					(mid 385.264118 -428.014418)
					(end 385.318 -428.036736)
				)
				(arc
					(start 386.2578 -428.036736)
					(mid 386.311682 -428.014418)
					(end 386.334 -427.960536)
				)
				(arc
					(start 386.334 -425.419012)
					(mid 386.311682 -425.36513)
					(end 386.2578 -425.342812)
				)
				(arc
					(start 385.318 -425.342812)
					(mid 385.264118 -425.36513)
					(end 385.2418 -425.419012)
				)
				(arc
					(start 385.2418 -426.146468)
					(mid 385.243799 -426.163809)
					(end 385.249674 -426.18025)
				)
				(arc
					(start 385.4831 -426.6565)
					(mid 385.490883 -426.690028)
					(end 385.4831 -426.723556)
				)
				(arc
					(start 385.249674 -427.199806)
					(mid 385.243779 -427.216242)
					(end 385.2418 -427.233588)
				)
			)
		)
	)
	(zone
		(layer "In7.Cu")
		(hatch none 0.5)
		(connect_pads
			(clearance 0)
		)
		(min_thickness 0.25)
		(keepout
			(tracks not_allowed)
			(vias allowed)
			(pads allowed)
			(copperpour not_allowed)
			(footprints allowed)
		)
		(placement
			(enabled no)
			(sheetname "")
		)
		(fill
			(thermal_gap 0.5)
			(thermal_bridge_width 0.5)
			(island_removal_mode 0)
		)
		(polygon
			(pts
				(arc
					(start 343.142062 -431.560478)
					(mid 343.16438 -431.61436)
					(end 343.218262 -431.636678)
				)
				(arc
					(start 344.158062 -431.636678)
					(mid 344.211944 -431.61436)
					(end 344.234262 -431.560478)
				)
				(arc
					(start 344.234262 -429.018954)
					(mid 344.211944 -428.965072)
					(end 344.158062 -428.942754)
				)
				(arc
					(start 343.218262 -428.942754)
					(mid 343.16438 -428.965072)
					(end 343.142062 -429.018954)
				)
			)
		)
	)
	(zone
		(layer "In7.Cu")
		(hatch none 0.5)
		(connect_pads
			(clearance 0)
		)
		(min_thickness 0.25)
		(keepout
			(tracks not_allowed)
			(vias allowed)
			(pads allowed)
			(copperpour not_allowed)
			(footprints allowed)
		)
		(placement
			(enabled no)
			(sheetname "")
		)
		(fill
			(thermal_gap 0.5)
			(thermal_bridge_width 0.5)
			(island_removal_mode 0)
		)
		(polygon
			(pts
				(arc
					(start 381.242062 -431.560478)
					(mid 381.26438 -431.61436)
					(end 381.318262 -431.636678)
				)
				(arc
					(start 382.258062 -431.636678)
					(mid 382.311944 -431.61436)
					(end 382.334262 -431.560478)
				)
				(arc
					(start 382.334262 -429.018954)
					(mid 382.311944 -428.965072)
					(end 382.258062 -428.942754)
				)
				(arc
					(start 381.318262 -428.942754)
					(mid 381.26438 -428.965072)
					(end 381.242062 -429.018954)
				)
			)
		)
	)
	(zone
		(layer "In7.Cu")
		(hatch none 0.5)
		(connect_pads
			(clearance 0)
		)
		(min_thickness 0.25)
		(keepout
			(tracks not_allowed)
			(vias allowed)
			(pads allowed)
			(copperpour not_allowed)
			(footprints allowed)
		)
		(placement
			(enabled no)
			(sheetname "")
		)
		(fill
			(thermal_gap 0.5)
			(thermal_bridge_width 0.5)
			(island_removal_mode 0)
		)
		(polygon
			(pts
				(arc
					(start 410.242258 -431.560478)
					(mid 410.264576 -431.61436)
					(end 410.318458 -431.636678)
				)
				(arc
					(start 411.258258 -431.636678)
					(mid 411.31214 -431.61436)
					(end 411.334458 -431.560478)
				)
				(arc
					(start 411.334458 -429.018954)
					(mid 411.31214 -428.965072)
					(end 411.258258 -428.942754)
				)
				(arc
					(start 410.318458 -428.942754)
					(mid 410.264576 -428.965072)
					(end 410.242258 -429.018954)
				)
			)
		)
	)
	(zone
		(layer "In7.Cu")
		(hatch none 0.5)
		(connect_pads
			(clearance 0)
		)
		(min_thickness 0.25)
		(keepout
			(tracks not_allowed)
			(vias allowed)
			(pads allowed)
			(copperpour not_allowed)
			(footprints allowed)
		)
		(placement
			(enabled no)
			(sheetname "")
		)
		(fill
			(thermal_gap 0.5)
			(thermal_bridge_width 0.5)
			(island_removal_mode 0)
		)
		(polygon
			(pts
				(arc
					(start 385.242054 -431.560478)
					(mid 385.264372 -431.61436)
					(end 385.318254 -431.636678)
				)
				(arc
					(start 386.258054 -431.636678)
					(mid 386.311936 -431.61436)
					(end 386.334254 -431.560478)
				)
				(arc
					(start 386.334254 -429.018954)
					(mid 386.311936 -428.965072)
					(end 386.258054 -428.942754)
				)
				(arc
					(start 385.318254 -428.942754)
					(mid 385.264372 -428.965072)
					(end 385.242054 -429.018954)
				)
			)
		)
	)
	(zone
		(layer "In7.Cu")
		(hatch none 0.5)
		(connect_pads
			(clearance 0)
		)
		(min_thickness 0.25)
		(keepout
			(tracks not_allowed)
			(vias allowed)
			(pads allowed)
			(copperpour not_allowed)
			(footprints allowed)
		)
		(placement
			(enabled no)
			(sheetname "")
		)
		(fill
			(thermal_gap 0.5)
			(thermal_bridge_width 0.5)
			(island_removal_mode 0)
		)
		(polygon
			(pts
				(arc
					(start 400.242278 -432.560476)
					(mid 400.264596 -432.614358)
					(end 400.318478 -432.636676)
				)
				(arc
					(start 401.258278 -432.636676)
					(mid 401.31216 -432.614358)
					(end 401.334478 -432.560476)
				)
				(arc
					(start 401.334478 -430.018952)
					(mid 401.31216 -429.96507)
					(end 401.258278 -429.942752)
				)
				(arc
					(start 400.318478 -429.942752)
					(mid 400.264596 -429.96507)
					(end 400.242278 -430.018952)
				)
			)
		)
	)
	(zone
		(layer "In7.Cu")
		(hatch none 0.5)
		(connect_pads
			(clearance 0)
		)
		(min_thickness 0.25)
		(keepout
			(tracks not_allowed)
			(vias allowed)
			(pads allowed)
			(copperpour not_allowed)
			(footprints allowed)
		)
		(placement
			(enabled no)
			(sheetname "")
		)
		(fill
			(thermal_gap 0.5)
			(thermal_bridge_width 0.5)
			(island_removal_mode 0)
		)
		(polygon
			(pts
				(arc
					(start 408.242262 -432.560476)
					(mid 408.26458 -432.614358)
					(end 408.318462 -432.636676)
				)
				(arc
					(start 409.258262 -432.636676)
					(mid 409.312144 -432.614358)
					(end 409.334462 -432.560476)
				)
				(arc
					(start 409.334462 -430.018952)
					(mid 409.312144 -429.96507)
					(end 409.258262 -429.942752)
				)
				(arc
					(start 408.318462 -429.942752)
					(mid 408.26458 -429.96507)
					(end 408.242262 -430.018952)
				)
			)
		)
	)
	(zone
		(layer "In7.Cu")
		(hatch none 0.5)
		(connect_pads
			(clearance 0)
		)
		(min_thickness 0.25)
		(keepout
			(tracks not_allowed)
			(vias allowed)
			(pads allowed)
			(copperpour not_allowed)
			(footprints allowed)
		)
		(placement
			(enabled no)
			(sheetname "")
		)
		(fill
			(thermal_gap 0.5)
			(thermal_bridge_width 0.5)
			(island_removal_mode 0)
		)
		(polygon
			(pts
				(arc
					(start 400.242024 -428.96028)
					(mid 400.264342 -429.014162)
					(end 400.318224 -429.03648)
				)
				(arc
					(start 401.258024 -429.03648)
					(mid 401.311906 -429.014162)
					(end 401.334224 -428.96028)
				)
				(arc
					(start 401.334224 -426.418756)
					(mid 401.311906 -426.364874)
					(end 401.258024 -426.342556)
				)
				(arc
					(start 400.318224 -426.342556)
					(mid 400.264342 -426.364874)
					(end 400.242024 -426.418756)
				)
				(arc
					(start 400.242024 -427.146212)
					(mid 400.244023 -427.163553)
					(end 400.249898 -427.179994)
				)
				(arc
					(start 400.483324 -427.656244)
					(mid 400.491107 -427.689772)
					(end 400.483324 -427.7233)
				)
				(arc
					(start 400.249898 -428.19955)
					(mid 400.244003 -428.215986)
					(end 400.242024 -428.233332)
				)
			)
		)
	)
	(zone
		(layer "In7.Cu")
		(hatch none 0.5)
		(connect_pads
			(clearance 0)
		)
		(min_thickness 0.25)
		(keepout
			(tracks not_allowed)
			(vias allowed)
			(pads allowed)
			(copperpour not_allowed)
			(footprints allowed)
		)
		(placement
			(enabled no)
			(sheetname "")
		)
		(fill
			(thermal_gap 0.5)
			(thermal_bridge_width 0.5)
			(island_removal_mode 0)
		)
		(polygon
			(pts
				(arc
					(start 335.142078 -431.560478)
					(mid 335.164396 -431.61436)
					(end 335.218278 -431.636678)
				)
				(arc
					(start 336.158078 -431.636678)
					(mid 336.21196 -431.61436)
					(end 336.234278 -431.560478)
				)
				(arc
					(start 336.234278 -429.018954)
					(mid 336.21196 -428.965072)
					(end 336.158078 -428.942754)
				)
				(arc
					(start 335.218278 -428.942754)
					(mid 335.164396 -428.965072)
					(end 335.142078 -429.018954)
				)
			)
		)
	)
	(zone
		(layer "In7.Cu")
		(hatch none 0.5)
		(connect_pads
			(clearance 0)
		)
		(min_thickness 0.25)
		(keepout
			(tracks not_allowed)
			(vias allowed)
			(pads allowed)
			(copperpour not_allowed)
			(footprints allowed)
		)
		(placement
			(enabled no)
			(sheetname "")
		)
		(fill
			(thermal_gap 0.5)
			(thermal_bridge_width 0.5)
			(island_removal_mode 0)
		)
		(polygon
			(pts
				(arc
					(start 345.142058 -432.560476)
					(mid 345.164376 -432.614358)
					(end 345.218258 -432.636676)
				)
				(arc
					(start 346.158058 -432.636676)
					(mid 346.21194 -432.614358)
					(end 346.234258 -432.560476)
				)
				(arc
					(start 346.234258 -430.018952)
					(mid 346.21194 -429.96507)
					(end 346.158058 -429.942752)
				)
				(arc
					(start 345.218258 -429.942752)
					(mid 345.164376 -429.96507)
					(end 345.142058 -430.018952)
				)
			)
		)
	)
	(zone
		(layer "In7.Cu")
		(hatch none 0.5)
		(connect_pads
			(clearance 0)
		)
		(min_thickness 0.25)
		(keepout
			(tracks not_allowed)
			(vias allowed)
			(pads allowed)
			(copperpour not_allowed)
			(footprints allowed)
		)
		(placement
			(enabled no)
			(sheetname "")
		)
		(fill
			(thermal_gap 0.5)
			(thermal_bridge_width 0.5)
			(island_removal_mode 0)
		)
		(polygon
			(pts
				(arc
					(start 337.142074 -432.560476)
					(mid 337.164392 -432.614358)
					(end 337.218274 -432.636676)
				)
				(arc
					(start 338.158074 -432.636676)
					(mid 338.211956 -432.614358)
					(end 338.234274 -432.560476)
				)
				(arc
					(start 338.234274 -430.018952)
					(mid 338.211956 -429.96507)
					(end 338.158074 -429.942752)
				)
				(arc
					(start 337.218274 -429.942752)
					(mid 337.164392 -429.96507)
					(end 337.142074 -430.018952)
				)
			)
		)
	)
	(zone
		(layer "In7.Cu")
		(hatch none 0.5)
		(connect_pads
			(clearance 0)
		)
		(min_thickness 0.25)
		(keepout
			(tracks not_allowed)
			(vias allowed)
			(pads allowed)
			(copperpour not_allowed)
			(footprints allowed)
		)
		(placement
			(enabled no)
			(sheetname "")
		)
		(fill
			(thermal_gap 0.5)
			(thermal_bridge_width 0.5)
			(island_removal_mode 0)
		)
		(polygon
			(pts
				(arc
					(start 322.141596 -427.960536)
					(mid 322.163914 -428.014418)
					(end 322.217796 -428.036736)
				)
				(arc
					(start 323.157596 -428.036736)
					(mid 323.211478 -428.014418)
					(end 323.233796 -427.960536)
				)
				(arc
					(start 323.233796 -425.419012)
					(mid 323.211478 -425.36513)
					(end 323.157596 -425.342812)
				)
				(arc
					(start 322.217796 -425.342812)
					(mid 322.163914 -425.36513)
					(end 322.141596 -425.419012)
				)
				(arc
					(start 322.141596 -426.146468)
					(mid 322.143595 -426.163809)
					(end 322.14947 -426.18025)
				)
				(arc
					(start 322.382896 -426.6565)
					(mid 322.390679 -426.690028)
					(end 322.382896 -426.723556)
				)
				(arc
					(start 322.14947 -427.199806)
					(mid 322.143575 -427.216242)
					(end 322.141596 -427.233588)
				)
			)
		)
	)
	(zone
		(layer "In7.Cu")
		(hatch none 0.5)
		(connect_pads
			(clearance 0)
		)
		(min_thickness 0.25)
		(keepout
			(tracks not_allowed)
			(vias allowed)
			(pads allowed)
			(copperpour not_allowed)
			(footprints allowed)
		)
		(placement
			(enabled no)
			(sheetname "")
		)
		(fill
			(thermal_gap 0.5)
			(thermal_bridge_width 0.5)
			(island_removal_mode 0)
		)
		(polygon
			(pts
				(arc
					(start 387.241796 -428.96028)
					(mid 387.264114 -429.014162)
					(end 387.317996 -429.03648)
				)
				(arc
					(start 388.257796 -429.03648)
					(mid 388.311678 -429.014162)
					(end 388.333996 -428.96028)
				)
				(arc
					(start 388.333996 -426.418756)
					(mid 388.311678 -426.364874)
					(end 388.257796 -426.342556)
				)
				(arc
					(start 387.317996 -426.342556)
					(mid 387.264114 -426.364874)
					(end 387.241796 -426.418756)
				)
				(arc
					(start 387.241796 -427.146212)
					(mid 387.243795 -427.163553)
					(end 387.24967 -427.179994)
				)
				(arc
					(start 387.483096 -427.656244)
					(mid 387.490879 -427.689772)
					(end 387.483096 -427.7233)
				)
				(arc
					(start 387.24967 -428.19955)
					(mid 387.243775 -428.215986)
					(end 387.241796 -428.233332)
				)
			)
		)
	)
	(zone
		(layer "In7.Cu")
		(hatch none 0.5)
		(connect_pads
			(clearance 0)
		)
		(min_thickness 0.25)
		(keepout
			(tracks not_allowed)
			(vias allowed)
			(pads allowed)
			(copperpour not_allowed)
			(footprints allowed)
		)
		(placement
			(enabled no)
			(sheetname "")
		)
		(fill
			(thermal_gap 0.5)
			(thermal_bridge_width 0.5)
			(island_removal_mode 0)
		)
		(polygon
			(pts
				(arc
					(start 318.141604 -427.960536)
					(mid 318.163922 -428.014418)
					(end 318.217804 -428.036736)
				)
				(arc
					(start 319.157604 -428.036736)
					(mid 319.211486 -428.014418)
					(end 319.233804 -427.960536)
				)
				(arc
					(start 319.233804 -425.419012)
					(mid 319.211486 -425.36513)
					(end 319.157604 -425.342812)
				)
				(arc
					(start 318.217804 -425.342812)
					(mid 318.163922 -425.36513)
					(end 318.141604 -425.419012)
				)
				(arc
					(start 318.141604 -426.146468)
					(mid 318.143603 -426.163809)
					(end 318.149478 -426.18025)
				)
				(arc
					(start 318.382904 -426.6565)
					(mid 318.390687 -426.690028)
					(end 318.382904 -426.723556)
				)
				(arc
					(start 318.149478 -427.199806)
					(mid 318.143583 -427.216242)
					(end 318.141604 -427.233588)
				)
			)
		)
	)
	(zone
		(layer "In7.Cu")
		(hatch none 0.5)
		(connect_pads
			(clearance 0)
		)
		(min_thickness 0.25)
		(keepout
			(tracks not_allowed)
			(vias allowed)
			(pads allowed)
			(copperpour not_allowed)
			(footprints allowed)
		)
		(placement
			(enabled no)
			(sheetname "")
		)
		(fill
			(thermal_gap 0.5)
			(thermal_bridge_width 0.5)
			(island_removal_mode 0)
		)
		(polygon
			(pts
				(arc
					(start 391.241788 -428.96028)
					(mid 391.264106 -429.014162)
					(end 391.317988 -429.03648)
				)
				(arc
					(start 392.257788 -429.03648)
					(mid 392.31167 -429.014162)
					(end 392.333988 -428.96028)
				)
				(arc
					(start 392.333988 -426.418756)
					(mid 392.31167 -426.364874)
					(end 392.257788 -426.342556)
				)
				(arc
					(start 391.317988 -426.342556)
					(mid 391.264106 -426.364874)
					(end 391.241788 -426.418756)
				)
				(arc
					(start 391.241788 -427.146212)
					(mid 391.243787 -427.163553)
					(end 391.249662 -427.179994)
				)
				(arc
					(start 391.483088 -427.656244)
					(mid 391.490871 -427.689772)
					(end 391.483088 -427.7233)
				)
				(arc
					(start 391.249662 -428.19955)
					(mid 391.243767 -428.215986)
					(end 391.241788 -428.233332)
				)
			)
		)
	)
	(zone
		(layer "In7.Cu")
		(hatch none 0.5)
		(connect_pads
			(clearance 0)
		)
		(min_thickness 0.25)
		(keepout
			(tracks not_allowed)
			(vias allowed)
			(pads allowed)
			(copperpour not_allowed)
			(footprints allowed)
		)
		(placement
			(enabled no)
			(sheetname "")
		)
		(fill
			(thermal_gap 0.5)
			(thermal_bridge_width 0.5)
			(island_removal_mode 0)
		)
		(polygon
			(pts
				(arc
					(start 339.14207 -431.560478)
					(mid 339.164388 -431.61436)
					(end 339.21827 -431.636678)
				)
				(arc
					(start 340.15807 -431.636678)
					(mid 340.211952 -431.61436)
					(end 340.23427 -431.560478)
				)
				(arc
					(start 340.23427 -429.018954)
					(mid 340.211952 -428.965072)
					(end 340.15807 -428.942754)
				)
				(arc
					(start 339.21827 -428.942754)
					(mid 339.164388 -428.965072)
					(end 339.14207 -429.018954)
				)
			)
		)
	)
	(zone
		(layer "In7.Cu")
		(hatch none 0.5)
		(connect_pads
			(clearance 0)
		)
		(min_thickness 0.25)
		(keepout
			(tracks not_allowed)
			(vias allowed)
			(pads allowed)
			(copperpour not_allowed)
			(footprints allowed)
		)
		(placement
			(enabled no)
			(sheetname "")
		)
		(fill
			(thermal_gap 0.5)
			(thermal_bridge_width 0.5)
			(island_removal_mode 0)
		)
		(polygon
			(pts
				(arc
					(start 398.242282 -431.560478)
					(mid 398.2646 -431.61436)
					(end 398.318482 -431.636678)
				)
				(arc
					(start 399.258282 -431.636678)
					(mid 399.312164 -431.61436)
					(end 399.334482 -431.560478)
				)
				(arc
					(start 399.334482 -429.018954)
					(mid 399.312164 -428.965072)
					(end 399.258282 -428.942754)
				)
				(arc
					(start 398.318482 -428.942754)
					(mid 398.2646 -428.965072)
					(end 398.242282 -429.018954)
				)
			)
		)
	)
	(zone
		(layer "In7.Cu")
		(hatch none 0.5)
		(connect_pads
			(clearance 0)
		)
		(min_thickness 0.25)
		(keepout
			(tracks not_allowed)
			(vias allowed)
			(pads allowed)
			(copperpour not_allowed)
			(footprints allowed)
		)
		(placement
			(enabled no)
			(sheetname "")
		)
		(fill
			(thermal_gap 0.5)
			(thermal_bridge_width 0.5)
			(island_removal_mode 0)
		)
		(polygon
			(pts
				(arc
					(start 341.142066 -432.560476)
					(mid 341.164384 -432.614358)
					(end 341.218266 -432.636676)
				)
				(arc
					(start 342.158066 -432.636676)
					(mid 342.211948 -432.614358)
					(end 342.234266 -432.560476)
				)
				(arc
					(start 342.234266 -430.018952)
					(mid 342.211948 -429.96507)
					(end 342.158066 -429.942752)
				)
				(arc
					(start 341.218266 -429.942752)
					(mid 341.164384 -429.96507)
					(end 341.142066 -430.018952)
				)
			)
		)
	)
	(zone
		(layer "In7.Cu")
		(hatch none 0.5)
		(connect_pads
			(clearance 0)
		)
		(min_thickness 0.25)
		(keepout
			(tracks not_allowed)
			(vias allowed)
			(pads allowed)
			(copperpour not_allowed)
			(footprints allowed)
		)
		(placement
			(enabled no)
			(sheetname "")
		)
		(fill
			(thermal_gap 0.5)
			(thermal_bridge_width 0.5)
			(island_removal_mode 0)
		)
		(polygon
			(pts
				(arc
					(start 406.242266 -431.560478)
					(mid 406.264584 -431.61436)
					(end 406.318466 -431.636678)
				)
				(arc
					(start 407.258266 -431.636678)
					(mid 407.312148 -431.61436)
					(end 407.334466 -431.560478)
				)
				(arc
					(start 407.334466 -429.018954)
					(mid 407.312148 -428.965072)
					(end 407.258266 -428.942754)
				)
				(arc
					(start 406.318466 -428.942754)
					(mid 406.264584 -428.965072)
					(end 406.242266 -429.018954)
				)
			)
		)
	)
	(zone
		(layer "In7.Cu")
		(hatch none 0.5)
		(connect_pads
			(clearance 0)
		)
		(min_thickness 0.25)
		(keepout
			(tracks not_allowed)
			(vias allowed)
			(pads allowed)
			(copperpour not_allowed)
			(footprints allowed)
		)
		(placement
			(enabled no)
			(sheetname "")
		)
		(fill
			(thermal_gap 0.5)
			(thermal_bridge_width 0.5)
			(island_removal_mode 0)
		)
		(polygon
			(pts
				(arc
					(start 391.242042 -432.560476)
					(mid 391.26436 -432.614358)
					(end 391.318242 -432.636676)
				)
				(arc
					(start 392.258042 -432.636676)
					(mid 392.311924 -432.614358)
					(end 392.334242 -432.560476)
				)
				(arc
					(start 392.334242 -430.018952)
					(mid 392.311924 -429.96507)
					(end 392.258042 -429.942752)
				)
				(arc
					(start 391.318242 -429.942752)
					(mid 391.26436 -429.96507)
					(end 391.242042 -430.018952)
				)
			)
		)
	)
	(zone
		(layer "In7.Cu")
		(hatch none 0.5)
		(connect_pads
			(clearance 0)
		)
		(min_thickness 0.25)
		(keepout
			(tracks not_allowed)
			(vias allowed)
			(pads allowed)
			(copperpour not_allowed)
			(footprints allowed)
		)
		(placement
			(enabled no)
			(sheetname "")
		)
		(fill
			(thermal_gap 0.5)
			(thermal_bridge_width 0.5)
			(island_removal_mode 0)
		)
		(polygon
			(pts
				(arc
					(start 320.1416 -428.96028)
					(mid 320.163918 -429.014162)
					(end 320.2178 -429.03648)
				)
				(arc
					(start 321.1576 -429.03648)
					(mid 321.211482 -429.014162)
					(end 321.2338 -428.96028)
				)
				(arc
					(start 321.2338 -426.418756)
					(mid 321.211482 -426.364874)
					(end 321.1576 -426.342556)
				)
				(arc
					(start 320.2178 -426.342556)
					(mid 320.163918 -426.364874)
					(end 320.1416 -426.418756)
				)
				(arc
					(start 320.1416 -427.146212)
					(mid 320.143599 -427.163553)
					(end 320.149474 -427.179994)
				)
				(arc
					(start 320.3829 -427.656244)
					(mid 320.390683 -427.689772)
					(end 320.3829 -427.7233)
				)
				(arc
					(start 320.149474 -428.19955)
					(mid 320.143579 -428.215986)
					(end 320.1416 -428.233332)
				)
			)
		)
	)
	(zone
		(layer "In7.Cu")
		(hatch none 0.5)
		(connect_pads
			(clearance 0)
		)
		(min_thickness 0.25)
		(keepout
			(tracks not_allowed)
			(vias allowed)
			(pads allowed)
			(copperpour not_allowed)
			(footprints allowed)
		)
		(placement
			(enabled no)
			(sheetname "")
		)
		(fill
			(thermal_gap 0.5)
			(thermal_bridge_width 0.5)
			(island_removal_mode 0)
		)
		(polygon
			(pts
				(arc
					(start 337.14182 -428.96028)
					(mid 337.164138 -429.014162)
					(end 337.21802 -429.03648)
				)
				(arc
					(start 338.15782 -429.03648)
					(mid 338.211702 -429.014162)
					(end 338.23402 -428.96028)
				)
				(arc
					(start 338.23402 -426.418756)
					(mid 338.211702 -426.364874)
					(end 338.15782 -426.342556)
				)
				(arc
					(start 337.21802 -426.342556)
					(mid 337.164138 -426.364874)
					(end 337.14182 -426.418756)
				)
				(arc
					(start 337.14182 -427.146212)
					(mid 337.143819 -427.163553)
					(end 337.149694 -427.179994)
				)
				(arc
					(start 337.38312 -427.656244)
					(mid 337.390903 -427.689772)
					(end 337.38312 -427.7233)
				)
				(arc
					(start 337.149694 -428.19955)
					(mid 337.143799 -428.215986)
					(end 337.14182 -428.233332)
				)
			)
		)
	)
	(zone
		(layer "In7.Cu")
		(hatch none 0.5)
		(connect_pads
			(clearance 0)
		)
		(min_thickness 0.25)
		(keepout
			(tracks not_allowed)
			(vias allowed)
			(pads allowed)
			(copperpour not_allowed)
			(footprints allowed)
		)
		(placement
			(enabled no)
			(sheetname "")
		)
		(fill
			(thermal_gap 0.5)
			(thermal_bridge_width 0.5)
			(island_removal_mode 0)
		)
		(polygon
			(pts
				(arc
					(start 328.141584 -428.96028)
					(mid 328.163902 -429.014162)
					(end 328.217784 -429.03648)
				)
				(arc
					(start 329.157584 -429.03648)
					(mid 329.211466 -429.014162)
					(end 329.233784 -428.96028)
				)
				(arc
					(start 329.233784 -426.418756)
					(mid 329.211466 -426.364874)
					(end 329.157584 -426.342556)
				)
				(arc
					(start 328.217784 -426.342556)
					(mid 328.163902 -426.364874)
					(end 328.141584 -426.418756)
				)
				(arc
					(start 328.141584 -427.146212)
					(mid 328.143583 -427.163553)
					(end 328.149458 -427.179994)
				)
				(arc
					(start 328.382884 -427.656244)
					(mid 328.390667 -427.689772)
					(end 328.382884 -427.7233)
				)
				(arc
					(start 328.149458 -428.19955)
					(mid 328.143563 -428.215986)
					(end 328.141584 -428.233332)
				)
			)
		)
	)
	(zone
		(layer "In7.Cu")
		(hatch none 0.5)
		(connect_pads
			(clearance 0)
		)
		(min_thickness 0.25)
		(keepout
			(tracks not_allowed)
			(vias allowed)
			(pads allowed)
			(copperpour not_allowed)
			(footprints allowed)
		)
		(placement
			(enabled no)
			(sheetname "")
		)
		(fill
			(thermal_gap 0.5)
			(thermal_bridge_width 0.5)
			(island_removal_mode 0)
		)
		(polygon
			(pts
				(arc
					(start 326.141588 -427.960536)
					(mid 326.163906 -428.014418)
					(end 326.217788 -428.036736)
				)
				(arc
					(start 327.157588 -428.036736)
					(mid 327.21147 -428.014418)
					(end 327.233788 -427.960536)
				)
				(arc
					(start 327.233788 -425.419012)
					(mid 327.21147 -425.36513)
					(end 327.157588 -425.342812)
				)
				(arc
					(start 326.217788 -425.342812)
					(mid 326.163906 -425.36513)
					(end 326.141588 -425.419012)
				)
				(arc
					(start 326.141588 -426.146468)
					(mid 326.143587 -426.163809)
					(end 326.149462 -426.18025)
				)
				(arc
					(start 326.382888 -426.6565)
					(mid 326.390671 -426.690028)
					(end 326.382888 -426.723556)
				)
				(arc
					(start 326.149462 -427.199806)
					(mid 326.143567 -427.216242)
					(end 326.141588 -427.233588)
				)
			)
		)
	)
	(zone
		(layer "In7.Cu")
		(hatch none 0.5)
		(connect_pads
			(clearance 0)
		)
		(min_thickness 0.25)
		(keepout
			(tracks not_allowed)
			(vias allowed)
			(pads allowed)
			(copperpour not_allowed)
			(footprints allowed)
		)
		(placement
			(enabled no)
			(sheetname "")
		)
		(fill
			(thermal_gap 0.5)
			(thermal_bridge_width 0.5)
			(island_removal_mode 0)
		)
		(polygon
			(pts
				(arc
					(start 395.24178 -428.96028)
					(mid 395.264098 -429.014162)
					(end 395.31798 -429.03648)
				)
				(arc
					(start 396.25778 -429.03648)
					(mid 396.311662 -429.014162)
					(end 396.33398 -428.96028)
				)
				(arc
					(start 396.33398 -426.418756)
					(mid 396.311662 -426.364874)
					(end 396.25778 -426.342556)
				)
				(arc
					(start 395.31798 -426.342556)
					(mid 395.264098 -426.364874)
					(end 395.24178 -426.418756)
				)
				(arc
					(start 395.24178 -427.146212)
					(mid 395.243779 -427.163553)
					(end 395.249654 -427.179994)
				)
				(arc
					(start 395.48308 -427.656244)
					(mid 395.490863 -427.689772)
					(end 395.48308 -427.7233)
				)
				(arc
					(start 395.249654 -428.19955)
					(mid 395.243759 -428.215986)
					(end 395.24178 -428.233332)
				)
			)
		)
	)
	(zone
		(layer "In7.Cu")
		(hatch none 0.5)
		(connect_pads
			(clearance 0)
		)
		(min_thickness 0.25)
		(keepout
			(tracks not_allowed)
			(vias allowed)
			(pads allowed)
			(copperpour not_allowed)
			(footprints allowed)
		)
		(placement
			(enabled no)
			(sheetname "")
		)
		(fill
			(thermal_gap 0.5)
			(thermal_bridge_width 0.5)
			(island_removal_mode 0)
		)
		(polygon
			(pts
				(arc
					(start 333.142082 -432.560476)
					(mid 333.1644 -432.614358)
					(end 333.218282 -432.636676)
				)
				(arc
					(start 334.158082 -432.636676)
					(mid 334.211964 -432.614358)
					(end 334.234282 -432.560476)
				)
				(arc
					(start 334.234282 -430.018952)
					(mid 334.211964 -429.96507)
					(end 334.158082 -429.942752)
				)
				(arc
					(start 333.218282 -429.942752)
					(mid 333.1644 -429.96507)
					(end 333.142082 -430.018952)
				)
			)
		)
	)
	(zone
		(layer "In7.Cu")
		(hatch none 0.5)
		(connect_pads
			(clearance 0)
		)
		(min_thickness 0.25)
		(keepout
			(tracks not_allowed)
			(vias allowed)
			(pads allowed)
			(copperpour not_allowed)
			(footprints allowed)
		)
		(placement
			(enabled no)
			(sheetname "")
		)
		(fill
			(thermal_gap 0.5)
			(thermal_bridge_width 0.5)
			(island_removal_mode 0)
		)
		(polygon
			(pts
				(arc
					(start 412.242 -428.96028)
					(mid 412.264318 -429.014162)
					(end 412.3182 -429.03648)
				)
				(arc
					(start 413.258 -429.03648)
					(mid 413.311882 -429.014162)
					(end 413.3342 -428.96028)
				)
				(arc
					(start 413.3342 -426.418756)
					(mid 413.311882 -426.364874)
					(end 413.258 -426.342556)
				)
				(arc
					(start 412.3182 -426.342556)
					(mid 412.264318 -426.364874)
					(end 412.242 -426.418756)
				)
				(arc
					(start 412.242 -427.146212)
					(mid 412.243999 -427.163553)
					(end 412.249874 -427.179994)
				)
				(arc
					(start 412.4833 -427.656244)
					(mid 412.491083 -427.689772)
					(end 412.4833 -427.7233)
				)
				(arc
					(start 412.249874 -428.19955)
					(mid 412.243979 -428.215986)
					(end 412.242 -428.233332)
				)
			)
		)
	)
	(zone
		(layer "In7.Cu")
		(hatch none 0.5)
		(connect_pads
			(clearance 0)
		)
		(min_thickness 0.25)
		(keepout
			(tracks not_allowed)
			(vias allowed)
			(pads allowed)
			(copperpour not_allowed)
			(footprints allowed)
		)
		(placement
			(enabled no)
			(sheetname "")
		)
		(fill
			(thermal_gap 0.5)
			(thermal_bridge_width 0.5)
			(island_removal_mode 0)
		)
		(polygon
			(pts
				(arc
					(start 387.24205 -432.560476)
					(mid 387.264368 -432.614358)
					(end 387.31825 -432.636676)
				)
				(arc
					(start 388.25805 -432.636676)
					(mid 388.311932 -432.614358)
					(end 388.33425 -432.560476)
				)
				(arc
					(start 388.33425 -430.018952)
					(mid 388.311932 -429.96507)
					(end 388.25805 -429.942752)
				)
				(arc
					(start 387.31825 -429.942752)
					(mid 387.264368 -429.96507)
					(end 387.24205 -430.018952)
				)
			)
		)
	)
	(zone
		(layer "In7.Cu")
		(hatch none 0.5)
		(connect_pads
			(clearance 0)
		)
		(min_thickness 0.25)
		(keepout
			(tracks not_allowed)
			(vias allowed)
			(pads allowed)
			(copperpour not_allowed)
			(footprints allowed)
		)
		(placement
			(enabled no)
			(sheetname "")
		)
		(fill
			(thermal_gap 0.5)
			(thermal_bridge_width 0.5)
			(island_removal_mode 0)
		)
		(polygon
			(pts
				(arc
					(start 404.242016 -428.96028)
					(mid 404.264334 -429.014162)
					(end 404.318216 -429.03648)
				)
				(arc
					(start 405.258016 -429.03648)
					(mid 405.311898 -429.014162)
					(end 405.334216 -428.96028)
				)
				(arc
					(start 405.334216 -426.418756)
					(mid 405.311898 -426.364874)
					(end 405.258016 -426.342556)
				)
				(arc
					(start 404.318216 -426.342556)
					(mid 404.264334 -426.364874)
					(end 404.242016 -426.418756)
				)
				(arc
					(start 404.242016 -427.146212)
					(mid 404.244015 -427.163553)
					(end 404.24989 -427.179994)
				)
				(arc
					(start 404.483316 -427.656244)
					(mid 404.491099 -427.689772)
					(end 404.483316 -427.7233)
				)
				(arc
					(start 404.24989 -428.19955)
					(mid 404.243995 -428.215986)
					(end 404.242016 -428.233332)
				)
			)
		)
	)
	(zone
		(layer "In7.Cu")
		(hatch none 0.5)
		(connect_pads
			(clearance 0)
		)
		(min_thickness 0.25)
		(keepout
			(tracks not_allowed)
			(vias allowed)
			(pads allowed)
			(copperpour not_allowed)
			(footprints allowed)
		)
		(placement
			(enabled no)
			(sheetname "")
		)
		(fill
			(thermal_gap 0.5)
			(thermal_bridge_width 0.5)
			(island_removal_mode 0)
		)
		(polygon
			(pts
				(arc
					(start 345.141804 -428.96028)
					(mid 345.164122 -429.014162)
					(end 345.218004 -429.03648)
				)
				(arc
					(start 346.157804 -429.03648)
					(mid 346.211686 -429.014162)
					(end 346.234004 -428.96028)
				)
				(arc
					(start 346.234004 -426.418756)
					(mid 346.211686 -426.364874)
					(end 346.157804 -426.342556)
				)
				(arc
					(start 345.218004 -426.342556)
					(mid 345.164122 -426.364874)
					(end 345.141804 -426.418756)
				)
				(arc
					(start 345.141804 -427.146212)
					(mid 345.143803 -427.163553)
					(end 345.149678 -427.179994)
				)
				(arc
					(start 345.383104 -427.656244)
					(mid 345.390887 -427.689772)
					(end 345.383104 -427.7233)
				)
				(arc
					(start 345.149678 -428.19955)
					(mid 345.143783 -428.215986)
					(end 345.141804 -428.233332)
				)
			)
		)
	)
	(zone
		(layer "In7.Cu")
		(hatch none 0.5)
		(connect_pads
			(clearance 0)
		)
		(min_thickness 0.25)
		(keepout
			(tracks not_allowed)
			(vias allowed)
			(pads allowed)
			(copperpour not_allowed)
			(footprints allowed)
		)
		(placement
			(enabled no)
			(sheetname "")
		)
		(fill
			(thermal_gap 0.5)
			(thermal_bridge_width 0.5)
			(island_removal_mode 0)
		)
		(polygon
			(pts
				(arc
					(start 404.24227 -432.560476)
					(mid 404.264588 -432.614358)
					(end 404.31847 -432.636676)
				)
				(arc
					(start 405.25827 -432.636676)
					(mid 405.312152 -432.614358)
					(end 405.33447 -432.560476)
				)
				(arc
					(start 405.33447 -430.018952)
					(mid 405.312152 -429.96507)
					(end 405.25827 -429.942752)
				)
				(arc
					(start 404.31847 -429.942752)
					(mid 404.264588 -429.96507)
					(end 404.24227 -430.018952)
				)
			)
		)
	)
	(zone
		(layer "In7.Cu")
		(hatch none 0.5)
		(connect_pads
			(clearance 0)
		)
		(min_thickness 0.25)
		(keepout
			(tracks not_allowed)
			(vias allowed)
			(pads allowed)
			(copperpour not_allowed)
			(footprints allowed)
		)
		(placement
			(enabled no)
			(sheetname "")
		)
		(fill
			(thermal_gap 0.5)
			(thermal_bridge_width 0.5)
			(island_removal_mode 0)
		)
		(polygon
			(pts
				(arc
					(start 333.141828 -428.96028)
					(mid 333.164146 -429.014162)
					(end 333.218028 -429.03648)
				)
				(arc
					(start 334.157828 -429.03648)
					(mid 334.21171 -429.014162)
					(end 334.234028 -428.96028)
				)
				(arc
					(start 334.234028 -426.418756)
					(mid 334.21171 -426.364874)
					(end 334.157828 -426.342556)
				)
				(arc
					(start 333.218028 -426.342556)
					(mid 333.164146 -426.364874)
					(end 333.141828 -426.418756)
				)
				(arc
					(start 333.141828 -427.146212)
					(mid 333.143827 -427.163553)
					(end 333.149702 -427.179994)
				)
				(arc
					(start 333.383128 -427.656244)
					(mid 333.390911 -427.689772)
					(end 333.383128 -427.7233)
				)
				(arc
					(start 333.149702 -428.19955)
					(mid 333.143807 -428.215986)
					(end 333.141828 -428.233332)
				)
			)
		)
	)
	(zone
		(layers "In7.Cu" "In10.Cu")
		(hatch none 0.5)
		(connect_pads
			(clearance 0)
		)
		(min_thickness 0.25)
		(keepout
			(tracks allowed)
			(vias allowed)
			(pads allowed)
			(copperpour allowed)
			(footprints allowed)
		)
		(placement
			(enabled no)
			(sheetname "")
		)
		(fill yes
			(thermal_gap 0.5)
			(thermal_bridge_width 0.5)
			(island_removal_mode 0)
		)
		(polygon
			(pts
				(xy 97.536 -280.162) (xy 125.476 -280.162) (xy 127.381 -278.257) (xy 127.381 -270.383) (xy 126.492 -269.494)
				(xy 117.094 -269.494) (xy 116.332 -268.732) (xy 98.425 -268.732) (xy 97.155 -270.002) (xy 97.155 -279.781)
			)
		)
	)
	(zone
		(layers "In7.Cu" "In10.Cu")
		(hatch none 0.5)
		(connect_pads
			(clearance 0)
		)
		(min_thickness 0.25)
		(keepout
			(tracks allowed)
			(vias allowed)
			(pads allowed)
			(copperpour allowed)
			(footprints allowed)
		)
		(placement
			(enabled no)
			(sheetname "")
		)
		(fill yes
			(thermal_gap 0.5)
			(thermal_bridge_width 0.5)
			(island_removal_mode 0)
		)
		(polygon
			(pts
				(xy 345.476068 -280.161746) (xy 373.416068 -280.161746) (xy 375.321068 -278.256746) (xy 375.321068 -270.382746)
				(xy 374.432068 -269.493746) (xy 365.034068 -269.493746) (xy 364.272068 -268.731746) (xy 346.365068 -268.731746)
				(xy 345.095068 -270.001746) (xy 345.095068 -279.780746)
			)
		)
	)
	(zone
		(layer "In8.Cu")
		(hatch none 0.5)
		(connect_pads
			(clearance 0)
		)
		(min_thickness 0.25)
		(keepout
			(tracks not_allowed)
			(vias allowed)
			(pads allowed)
			(copperpour not_allowed)
			(footprints allowed)
		)
		(placement
			(enabled no)
			(sheetname "")
		)
		(fill
			(thermal_gap 0.5)
			(thermal_bridge_width 0.5)
			(island_removal_mode 0)
		)
		(polygon
			(pts
				(arc
					(start 18.270474 -435.600348)
					(mid 16.006237 -439.929384)
					(end 11.158982 -440.53887)
				)
				(xy 8.309864 -440.53887) (xy 7.998714 -440.22772)
				(arc
					(start 7.998714 -437.263286)
					(mid 12.157679 -430.397608)
					(end 18.270474 -435.600348)
				)
			)
		)
	)
	(zone
		(layer "In8.Cu")
		(hatch none 0.5)
		(connect_pads
			(clearance 0)
		)
		(min_thickness 0.25)
		(keepout
			(tracks not_allowed)
			(vias allowed)
			(pads allowed)
			(copperpour not_allowed)
			(footprints allowed)
		)
		(placement
			(enabled no)
			(sheetname "")
		)
		(fill
			(thermal_gap 0.5)
			(thermal_bridge_width 0.5)
			(island_removal_mode 0)
		)
		(polygon
			(pts
				(arc
					(start 464.070446 -435.600348)
					(mid 463.997624 -436.473476)
					(end 463.78114 -437.322468)
				)
				(xy 463.78114 -440.14644) (xy 463.465672 -440.461908) (xy 460.83474 -440.461908)
				(arc
					(start 460.833978 -440.46267)
					(mid 454.412059 -432.679874)
					(end 464.070446 -435.600348)
				)
			)
		)
	)
	(zone
		(layer "In8.Cu")
		(hatch none 0.5)
		(connect_pads
			(clearance 0)
		)
		(min_thickness 0.25)
		(keepout
			(tracks not_allowed)
			(vias allowed)
			(pads allowed)
			(copperpour not_allowed)
			(footprints allowed)
		)
		(placement
			(enabled no)
			(sheetname "")
		)
		(fill
			(thermal_gap 0.5)
			(thermal_bridge_width 0.5)
			(island_removal_mode 0)
		)
		(polygon
			(pts
				(arc
					(start 319.510664 -394.50391)
					(mid 319.622913 -394.639357)
					(end 319.791334 -394.690092)
				)
				(arc
					(start 319.791334 -394.690092)
					(mid 320.00686 -394.600818)
					(end 320.096134 -394.385292)
				)
				(arc
					(start 320.096134 -394.385292)
					(mid 320.0863 -394.308239)
					(end 320.057272 -394.236194)
				)
				(arc
					(start 319.678304 -393.58951)
					(mid 319.259791 -393.417135)
					(end 319.131188 -393.85113)
				)
			)
		)
	)
	(zone
		(layers "In8.Cu" "In9.Cu")
		(hatch none 0.5)
		(connect_pads
			(clearance 0)
		)
		(min_thickness 0.25)
		(keepout
			(tracks not_allowed)
			(vias allowed)
			(pads allowed)
			(copperpour not_allowed)
			(footprints allowed)
		)
		(placement
			(enabled no)
			(sheetname "")
		)
		(fill yes
			(thermal_gap 0.5)
			(thermal_bridge_width 0.5)
			(island_removal_mode 0)
		)
		(polygon
			(pts
				(arc
					(start 114.247422 -436.49011)
					(mid 109.802422 -436.49011)
					(end 114.247422 -436.49011)
				)
			)
		)
	)
	(zone
		(layers "In8.Cu" "In9.Cu")
		(hatch none 0.5)
		(connect_pads
			(clearance 0)
		)
		(min_thickness 0.25)
		(keepout
			(tracks not_allowed)
			(vias allowed)
			(pads allowed)
			(copperpour not_allowed)
			(footprints allowed)
		)
		(placement
			(enabled no)
			(sheetname "")
		)
		(fill yes
			(thermal_gap 0.5)
			(thermal_bridge_width 0.5)
			(island_removal_mode 0)
		)
		(polygon
			(pts
				(arc
					(start 63.510922 -386.12191)
					(mid 63.623171 -386.257357)
					(end 63.791592 -386.308092)
				)
				(arc
					(start 63.791592 -386.308092)
					(mid 64.007118 -386.218818)
					(end 64.096392 -386.003292)
				)
				(arc
					(start 64.096392 -386.003292)
					(mid 64.086558 -385.926239)
					(end 64.05753 -385.854194)
				)
				(arc
					(start 63.678562 -385.20751)
					(mid 63.260049 -385.035135)
					(end 63.131446 -385.46913)
				)
			)
		)
	)
	(zone
		(layers "In8.Cu" "In9.Cu")
		(hatch none 0.5)
		(connect_pads
			(clearance 0)
		)
		(min_thickness 0.25)
		(keepout
			(tracks not_allowed)
			(vias allowed)
			(pads allowed)
			(copperpour not_allowed)
			(footprints allowed)
		)
		(placement
			(enabled no)
			(sheetname "")
		)
		(fill yes
			(thermal_gap 0.5)
			(thermal_bridge_width 0.5)
			(island_removal_mode 0)
		)
		(polygon
			(pts
				(arc
					(start 115.911122 -431.360072)
					(mid 108.138722 -431.360072)
					(end 115.911122 -431.360072)
				)
			)
		)
		(polygon
			(pts
				(arc
					(start 113.485422 -431.360072)
					(mid 110.564422 -431.360072)
					(end 113.485422 -431.360072)
				)
			)
		)
	)
	(zone
		(layers "In8.Cu" "In9.Cu")
		(hatch none 0.5)
		(connect_pads
			(clearance 0)
		)
		(min_thickness 0.25)
		(keepout
			(tracks not_allowed)
			(vias allowed)
			(pads allowed)
			(copperpour not_allowed)
			(footprints allowed)
		)
		(placement
			(enabled no)
			(sheetname "")
		)
		(fill yes
			(thermal_gap 0.5)
			(thermal_bridge_width 0.5)
			(island_removal_mode 0)
		)
		(polygon
			(pts
				(arc
					(start 62.310772 -386.12191)
					(mid 62.423021 -386.257357)
					(end 62.591442 -386.308092)
				)
				(arc
					(start 62.591442 -386.308092)
					(mid 62.806968 -386.218818)
					(end 62.896242 -386.003292)
				)
				(arc
					(start 62.896242 -386.003292)
					(mid 62.886408 -385.926239)
					(end 62.85738 -385.854194)
				)
				(arc
					(start 62.478412 -385.20751)
					(mid 62.059899 -385.035135)
					(end 61.931296 -385.46913)
				)
			)
		)
	)
	(zone
		(layers "In8.Cu" "In9.Cu")
		(hatch none 0.5)
		(connect_pads
			(clearance 0)
		)
		(min_thickness 0.25)
		(keepout
			(tracks not_allowed)
			(vias allowed)
			(pads allowed)
			(copperpour not_allowed)
			(footprints allowed)
		)
		(placement
			(enabled no)
			(sheetname "")
		)
		(fill yes
			(thermal_gap 0.5)
			(thermal_bridge_width 0.5)
			(island_removal_mode 0)
		)
		(polygon
			(pts
				(arc
					(start 318.310514 -394.50391)
					(mid 318.422763 -394.639357)
					(end 318.591184 -394.690092)
				)
				(arc
					(start 318.591184 -394.690092)
					(mid 318.80671 -394.600818)
					(end 318.895984 -394.385292)
				)
				(arc
					(start 318.895984 -394.385292)
					(mid 318.88615 -394.308239)
					(end 318.857122 -394.236194)
				)
				(arc
					(start 318.478154 -393.58951)
					(mid 318.059641 -393.417135)
					(end 317.931038 -393.85113)
				)
			)
		)
	)
	(zone
		(layers "In8.Cu" "In9.Cu")
		(hatch none 0.5)
		(connect_pads
			(clearance 0)
		)
		(min_thickness 0.25)
		(keepout
			(tracks not_allowed)
			(vias allowed)
			(pads allowed)
			(copperpour not_allowed)
			(footprints allowed)
		)
		(placement
			(enabled no)
			(sheetname "")
		)
		(fill yes
			(thermal_gap 0.5)
			(thermal_bridge_width 0.5)
			(island_removal_mode 0)
		)
		(polygon
			(pts
				(arc
					(start 59.91098 -386.12191)
					(mid 60.023229 -386.257357)
					(end 60.19165 -386.308092)
				)
				(arc
					(start 60.19165 -386.308092)
					(mid 60.407176 -386.218818)
					(end 60.49645 -386.003292)
				)
				(arc
					(start 60.49645 -386.003292)
					(mid 60.486616 -385.926239)
					(end 60.457588 -385.854194)
				)
				(arc
					(start 60.07862 -385.20751)
					(mid 59.660107 -385.035135)
					(end 59.531504 -385.46913)
				)
			)
		)
	)
	(zone
		(layers "In8.Cu" "In9.Cu")
		(hatch none 0.5)
		(connect_pads
			(clearance 0)
		)
		(min_thickness 0.25)
		(keepout
			(tracks not_allowed)
			(vias allowed)
			(pads allowed)
			(copperpour not_allowed)
			(footprints allowed)
		)
		(placement
			(enabled no)
			(sheetname "")
		)
		(fill yes
			(thermal_gap 0.5)
			(thermal_bridge_width 0.5)
			(island_removal_mode 0)
		)
		(polygon
			(pts
				(arc
					(start 205.17612 -433.04206)
					(mid 196.79412 -433.04206)
					(end 205.17612 -433.04206)
				)
			)
		)
		(polygon
			(pts
				(arc
					(start 202.38212 -433.04206)
					(mid 199.58812 -433.04206)
					(end 202.38212 -433.04206)
				)
			)
		)
	)
	(zone
		(layers "In8.Cu" "In9.Cu")
		(hatch none 0.5)
		(connect_pads
			(clearance 0)
		)
		(min_thickness 0.25)
		(keepout
			(tracks not_allowed)
			(vias allowed)
			(pads allowed)
			(copperpour not_allowed)
			(footprints allowed)
		)
		(placement
			(enabled no)
			(sheetname "")
		)
		(fill yes
			(thermal_gap 0.5)
			(thermal_bridge_width 0.5)
			(island_removal_mode 0)
		)
		(polygon
			(pts
				(arc
					(start 65.910968 -386.12191)
					(mid 66.023217 -386.257357)
					(end 66.191638 -386.308092)
				)
				(arc
					(start 66.191638 -386.308092)
					(mid 66.407164 -386.218818)
					(end 66.496438 -386.003292)
				)
				(arc
					(start 66.496438 -386.003292)
					(mid 66.486604 -385.926239)
					(end 66.457576 -385.854194)
				)
				(arc
					(start 66.078608 -385.20751)
					(mid 65.660095 -385.035135)
					(end 65.531492 -385.46913)
				)
			)
		)
	)
	(zone
		(layers "In8.Cu" "In9.Cu")
		(hatch none 0.5)
		(connect_pads
			(clearance 0)
		)
		(min_thickness 0.25)
		(keepout
			(tracks not_allowed)
			(vias allowed)
			(pads allowed)
			(copperpour not_allowed)
			(footprints allowed)
		)
		(placement
			(enabled no)
			(sheetname "")
		)
		(fill yes
			(thermal_gap 0.5)
			(thermal_bridge_width 0.5)
			(island_removal_mode 0)
		)
		(polygon
			(pts
				(arc
					(start 58.71083 -386.12191)
					(mid 58.823079 -386.257357)
					(end 58.9915 -386.308092)
				)
				(arc
					(start 58.9915 -386.308092)
					(mid 59.207026 -386.218818)
					(end 59.2963 -386.003292)
				)
				(arc
					(start 59.2963 -386.003292)
					(mid 59.286466 -385.926239)
					(end 59.257438 -385.854194)
				)
				(arc
					(start 58.87847 -385.20751)
					(mid 58.459957 -385.035135)
					(end 58.331354 -385.46913)
				)
			)
		)
	)
	(zone
		(layers "In8.Cu" "In9.Cu")
		(hatch none 0.5)
		(connect_pads
			(clearance 0)
		)
		(min_thickness 0.25)
		(keepout
			(tracks not_allowed)
			(vias allowed)
			(pads allowed)
			(copperpour not_allowed)
			(footprints allowed)
		)
		(placement
			(enabled no)
			(sheetname "")
		)
		(fill yes
			(thermal_gap 0.5)
			(thermal_bridge_width 0.5)
			(island_removal_mode 0)
		)
		(polygon
			(pts
				(arc
					(start 361.997498 -424.74007)
					(mid 357.552498 -424.74007)
					(end 361.997498 -424.74007)
				)
			)
		)
	)
	(zone
		(layers "In8.Cu" "In9.Cu")
		(hatch none 0.5)
		(connect_pads
			(clearance 0)
		)
		(min_thickness 0.25)
		(keepout
			(tracks not_allowed)
			(vias allowed)
			(pads allowed)
			(copperpour not_allowed)
			(footprints allowed)
		)
		(placement
			(enabled no)
			(sheetname "")
		)
		(fill yes
			(thermal_gap 0.5)
			(thermal_bridge_width 0.5)
			(island_removal_mode 0)
		)
		(polygon
			(pts
				(arc
					(start 320.71056 -394.50391)
					(mid 320.822809 -394.639357)
					(end 320.99123 -394.690092)
				)
				(arc
					(start 320.99123 -394.690092)
					(mid 321.206756 -394.600818)
					(end 321.29603 -394.385292)
				)
				(arc
					(start 321.29603 -394.385292)
					(mid 321.286196 -394.308239)
					(end 321.257168 -394.236194)
				)
				(arc
					(start 320.8782 -393.58951)
					(mid 320.459687 -393.417135)
					(end 320.331084 -393.85113)
				)
			)
		)
	)
	(zone
		(layers "In8.Cu" "In9.Cu")
		(hatch none 0.5)
		(connect_pads
			(clearance 0)
		)
		(min_thickness 0.25)
		(keepout
			(tracks not_allowed)
			(vias allowed)
			(pads allowed)
			(copperpour not_allowed)
			(footprints allowed)
		)
		(placement
			(enabled no)
			(sheetname "")
		)
		(fill yes
			(thermal_gap 0.5)
			(thermal_bridge_width 0.5)
			(island_removal_mode 0)
		)
		(polygon
			(pts
				(arc
					(start 57.510934 -386.12191)
					(mid 57.623183 -386.257357)
					(end 57.791604 -386.308092)
				)
				(arc
					(start 57.791604 -386.308092)
					(mid 58.00713 -386.218818)
					(end 58.096404 -386.003292)
				)
				(arc
					(start 58.096404 -386.003292)
					(mid 58.08657 -385.926239)
					(end 58.057542 -385.854194)
				)
				(arc
					(start 57.678574 -385.20751)
					(mid 57.260061 -385.035135)
					(end 57.131458 -385.46913)
				)
			)
		)
	)
	(zone
		(layers "In8.Cu" "In9.Cu")
		(hatch none 0.5)
		(connect_pads
			(clearance 0)
		)
		(min_thickness 0.25)
		(keepout
			(tracks not_allowed)
			(vias allowed)
			(pads allowed)
			(copperpour not_allowed)
			(footprints allowed)
		)
		(placement
			(enabled no)
			(sheetname "")
		)
		(fill yes
			(thermal_gap 0.5)
			(thermal_bridge_width 0.5)
			(island_removal_mode 0)
		)
		(polygon
			(pts
				(arc
					(start 321.910456 -394.50391)
					(mid 322.022705 -394.639357)
					(end 322.191126 -394.690092)
				)
				(arc
					(start 322.191126 -394.690092)
					(mid 322.406652 -394.600818)
					(end 322.495926 -394.385292)
				)
				(arc
					(start 322.495926 -394.385292)
					(mid 322.486092 -394.308239)
					(end 322.457064 -394.236194)
				)
				(arc
					(start 322.078096 -393.58951)
					(mid 321.659583 -393.417135)
					(end 321.53098 -393.85113)
				)
			)
		)
	)
	(zone
		(layers "In8.Cu" "In9.Cu")
		(hatch none 0.5)
		(connect_pads
			(clearance 0)
		)
		(min_thickness 0.25)
		(keepout
			(tracks not_allowed)
			(vias allowed)
			(pads allowed)
			(copperpour not_allowed)
			(footprints allowed)
		)
		(placement
			(enabled no)
			(sheetname "")
		)
		(fill yes
			(thermal_gap 0.5)
			(thermal_bridge_width 0.5)
			(island_removal_mode 0)
		)
		(polygon
			(pts
				(arc
					(start 317.110618 -394.50391)
					(mid 317.222867 -394.639357)
					(end 317.391288 -394.690092)
				)
				(arc
					(start 317.391288 -394.690092)
					(mid 317.606814 -394.600818)
					(end 317.696088 -394.385292)
				)
				(arc
					(start 317.696088 -394.385292)
					(mid 317.686254 -394.308239)
					(end 317.657226 -394.236194)
				)
				(arc
					(start 317.278258 -393.58951)
					(mid 316.859745 -393.417135)
					(end 316.731142 -393.85113)
				)
			)
		)
	)
	(zone
		(layers "In8.Cu" "In9.Cu")
		(hatch none 0.5)
		(connect_pads
			(clearance 0)
		)
		(min_thickness 0.25)
		(keepout
			(tracks not_allowed)
			(vias allowed)
			(pads allowed)
			(copperpour not_allowed)
			(footprints allowed)
		)
		(placement
			(enabled no)
			(sheetname "")
		)
		(fill yes
			(thermal_gap 0.5)
			(thermal_bridge_width 0.5)
			(island_removal_mode 0)
		)
		(polygon
			(pts
				(arc
					(start 361.997498 -436.49011)
					(mid 357.552498 -436.49011)
					(end 361.997498 -436.49011)
				)
			)
		)
	)
	(zone
		(layers "In8.Cu" "In9.Cu")
		(hatch none 0.5)
		(connect_pads
			(clearance 0)
		)
		(min_thickness 0.25)
		(keepout
			(tracks not_allowed)
			(vias allowed)
			(pads allowed)
			(copperpour not_allowed)
			(footprints allowed)
		)
		(placement
			(enabled no)
			(sheetname "")
		)
		(fill yes
			(thermal_gap 0.5)
			(thermal_bridge_width 0.5)
			(island_removal_mode 0)
		)
		(polygon
			(pts
				(arc
					(start 114.247422 -424.74007)
					(mid 109.802422 -424.74007)
					(end 114.247422 -424.74007)
				)
			)
		)
	)
	(zone
		(layers "In8.Cu" "In9.Cu")
		(hatch none 0.5)
		(connect_pads
			(clearance 0)
		)
		(min_thickness 0.25)
		(keepout
			(tracks not_allowed)
			(vias allowed)
			(pads allowed)
			(copperpour not_allowed)
			(footprints allowed)
		)
		(placement
			(enabled no)
			(sheetname "")
		)
		(fill yes
			(thermal_gap 0.5)
			(thermal_bridge_width 0.5)
			(island_removal_mode 0)
		)
		(polygon
			(pts
				(arc
					(start 313.510676 -394.50391)
					(mid 313.622925 -394.639357)
					(end 313.791346 -394.690092)
				)
				(arc
					(start 313.791346 -394.690092)
					(mid 314.006872 -394.600818)
					(end 314.096146 -394.385292)
				)
				(arc
					(start 314.096146 -394.385292)
					(mid 314.086312 -394.308239)
					(end 314.057284 -394.236194)
				)
				(arc
					(start 313.678316 -393.58951)
					(mid 313.259803 -393.417135)
					(end 313.1312 -393.85113)
				)
			)
		)
	)
	(zone
		(layers "In8.Cu" "In9.Cu")
		(hatch none 0.5)
		(connect_pads
			(clearance 0)
		)
		(min_thickness 0.25)
		(keepout
			(tracks not_allowed)
			(vias allowed)
			(pads allowed)
			(copperpour not_allowed)
			(footprints allowed)
		)
		(placement
			(enabled no)
			(sheetname "")
		)
		(fill yes
			(thermal_gap 0.5)
			(thermal_bridge_width 0.5)
			(island_removal_mode 0)
		)
		(polygon
			(pts
				(arc
					(start 275.02612 -433.04206)
					(mid 266.64412 -433.04206)
					(end 275.02612 -433.04206)
				)
			)
		)
		(polygon
			(pts
				(arc
					(start 272.23212 -433.04206)
					(mid 269.43812 -433.04206)
					(end 272.23212 -433.04206)
				)
			)
		)
	)
	(zone
		(layers "In8.Cu" "In9.Cu")
		(hatch none 0.5)
		(connect_pads
			(clearance 0)
		)
		(min_thickness 0.25)
		(keepout
			(tracks not_allowed)
			(vias allowed)
			(pads allowed)
			(copperpour not_allowed)
			(footprints allowed)
		)
		(placement
			(enabled no)
			(sheetname "")
		)
		(fill yes
			(thermal_gap 0.5)
			(thermal_bridge_width 0.5)
			(island_removal_mode 0)
		)
		(polygon
			(pts
				(arc
					(start 451.936866 -435.59984)
					(mid 445.663066 -435.59984)
					(end 451.936866 -435.59984)
				)
			)
		)
	)
	(zone
		(layers "In8.Cu" "In9.Cu")
		(hatch none 0.5)
		(connect_pads
			(clearance 0)
		)
		(min_thickness 0.25)
		(keepout
			(tracks not_allowed)
			(vias allowed)
			(pads allowed)
			(copperpour not_allowed)
			(footprints allowed)
		)
		(placement
			(enabled no)
			(sheetname "")
		)
		(fill yes
			(thermal_gap 0.5)
			(thermal_bridge_width 0.5)
			(island_removal_mode 0)
		)
		(polygon
			(pts
				(arc
					(start 314.710572 -394.50391)
					(mid 314.822821 -394.639357)
					(end 314.991242 -394.690092)
				)
				(arc
					(start 314.991242 -394.690092)
					(mid 315.206768 -394.600818)
					(end 315.296042 -394.385292)
				)
				(arc
					(start 315.296042 -394.385292)
					(mid 315.286208 -394.308239)
					(end 315.25718 -394.236194)
				)
				(arc
					(start 314.878212 -393.58951)
					(mid 314.459699 -393.417135)
					(end 314.331096 -393.85113)
				)
			)
		)
	)
	(zone
		(layers "In8.Cu" "In9.Cu")
		(hatch none 0.5)
		(connect_pads
			(clearance 0)
		)
		(min_thickness 0.25)
		(keepout
			(tracks not_allowed)
			(vias allowed)
			(pads allowed)
			(copperpour not_allowed)
			(footprints allowed)
		)
		(placement
			(enabled no)
			(sheetname "")
		)
		(fill yes
			(thermal_gap 0.5)
			(thermal_bridge_width 0.5)
			(island_removal_mode 0)
		)
		(polygon
			(pts
				(arc
					(start 363.661198 -431.360072)
					(mid 355.888798 -431.360072)
					(end 363.661198 -431.360072)
				)
			)
		)
		(polygon
			(pts
				(arc
					(start 361.235498 -431.360072)
					(mid 358.314498 -431.360072)
					(end 361.235498 -431.360072)
				)
			)
		)
	)
	(zone
		(layers "In8.Cu" "In9.Cu")
		(hatch none 0.5)
		(connect_pads
			(clearance 0)
		)
		(min_thickness 0.25)
		(keepout
			(tracks not_allowed)
			(vias allowed)
			(pads allowed)
			(copperpour not_allowed)
			(footprints allowed)
		)
		(placement
			(enabled no)
			(sheetname "")
		)
		(fill yes
			(thermal_gap 0.5)
			(thermal_bridge_width 0.5)
			(island_removal_mode 0)
		)
		(polygon
			(pts
				(arc
					(start 61.110876 -386.12191)
					(mid 61.223125 -386.257357)
					(end 61.391546 -386.308092)
				)
				(arc
					(start 61.391546 -386.308092)
					(mid 61.607072 -386.218818)
					(end 61.696346 -386.003292)
				)
				(arc
					(start 61.696346 -386.003292)
					(mid 61.686512 -385.926239)
					(end 61.657484 -385.854194)
				)
				(arc
					(start 61.278516 -385.20751)
					(mid 60.860003 -385.035135)
					(end 60.7314 -385.46913)
				)
			)
		)
	)
	(zone
		(layers "In8.Cu" "In9.Cu")
		(hatch none 0.5)
		(connect_pads
			(clearance 0)
		)
		(min_thickness 0.25)
		(keepout
			(tracks not_allowed)
			(vias allowed)
			(pads allowed)
			(copperpour not_allowed)
			(footprints allowed)
		)
		(placement
			(enabled no)
			(sheetname "")
		)
		(fill yes
			(thermal_gap 0.5)
			(thermal_bridge_width 0.5)
			(island_removal_mode 0)
		)
		(polygon
			(pts
				(arc
					(start 64.710818 -386.12191)
					(mid 64.823067 -386.257357)
					(end 64.991488 -386.308092)
				)
				(arc
					(start 64.991488 -386.308092)
					(mid 65.207014 -386.218818)
					(end 65.296288 -386.003292)
				)
				(arc
					(start 65.296288 -386.003292)
					(mid 65.286454 -385.926239)
					(end 65.257426 -385.854194)
				)
				(arc
					(start 64.878458 -385.20751)
					(mid 64.459945 -385.035135)
					(end 64.331342 -385.46913)
				)
			)
		)
	)
	(zone
		(layers "In8.Cu" "In9.Cu")
		(hatch none 0.5)
		(connect_pads
			(clearance 0)
		)
		(min_thickness 0.25)
		(keepout
			(tracks not_allowed)
			(vias allowed)
			(pads allowed)
			(copperpour not_allowed)
			(footprints allowed)
		)
		(placement
			(enabled no)
			(sheetname "")
		)
		(fill yes
			(thermal_gap 0.5)
			(thermal_bridge_width 0.5)
			(island_removal_mode 0)
		)
		(polygon
			(pts
				(arc
					(start 315.910468 -394.50391)
					(mid 316.022717 -394.639357)
					(end 316.191138 -394.690092)
				)
				(arc
					(start 316.191138 -394.690092)
					(mid 316.406664 -394.600818)
					(end 316.495938 -394.385292)
				)
				(arc
					(start 316.495938 -394.385292)
					(mid 316.486104 -394.308239)
					(end 316.457076 -394.236194)
				)
				(arc
					(start 316.078108 -393.58951)
					(mid 315.659595 -393.417135)
					(end 315.530992 -393.85113)
				)
			)
		)
	)
	(zone
		(layer "Cmts.User")
		(hatch none 0.5)
		(connect_pads
			(clearance 0)
		)
		(min_thickness 0.25)
		(keepout
			(tracks allowed)
			(vias allowed)
			(pads allowed)
			(copperpour allowed)
			(footprints allowed)
		)
		(placement
			(enabled no)
			(sheetname "")
		)
		(fill
			(thermal_gap 0.5)
			(thermal_bridge_width 0.5)
			(island_removal_mode 0)
		)
		(polygon
			(pts
				(xy 138.813286 -20.54606) (xy 138.813286 -19.51863) (xy 140.448538 -19.51863) (xy 140.448538 -20.54606)
			)
		)
	)
	(zone
		(layer "Cmts.User")
		(hatch none 0.5)
		(connect_pads
			(clearance 0)
		)
		(min_thickness 0.25)
		(keepout
			(tracks allowed)
			(vias allowed)
			(pads allowed)
			(copperpour allowed)
			(footprints allowed)
		)
		(placement
			(enabled no)
			(sheetname "")
		)
		(fill
			(thermal_gap 0.5)
			(thermal_bridge_width 0.5)
			(island_removal_mode 0)
		)
		(polygon
			(pts
				(xy 319.435226 -363.558328) (xy 318.754506 -363.558328) (xy 318.754506 -362.945172) (xy 319.435226 -362.945172)
			)
		)
	)
	(zone
		(layer "Cmts.User")
		(hatch none 0.5)
		(connect_pads
			(clearance 0)
		)
		(min_thickness 0.25)
		(keepout
			(tracks allowed)
			(vias allowed)
			(pads allowed)
			(copperpour allowed)
			(footprints allowed)
		)
		(placement
			(enabled no)
			(sheetname "")
		)
		(fill
			(thermal_gap 0.5)
			(thermal_bridge_width 0.5)
			(island_removal_mode 0)
		)
		(polygon
			(pts
				(xy 56.943244 -349.090742) (xy 56.943244 -348.46006) (xy 57.555638 -348.46006) (xy 57.555638 -349.090742)
			)
		)
	)
	(zone
		(layer "Cmts.User")
		(hatch none 0.5)
		(connect_pads
			(clearance 0)
		)
		(min_thickness 0.25)
		(keepout
			(tracks allowed)
			(vias allowed)
			(pads allowed)
			(copperpour allowed)
			(footprints allowed)
		)
		(placement
			(enabled no)
			(sheetname "")
		)
		(fill
			(thermal_gap 0.5)
			(thermal_bridge_width 0.5)
			(island_removal_mode 0)
		)
		(polygon
			(pts
				(xy 382.311148 -143.000476) (xy 382.311148 -142.363952) (xy 382.899666 -142.363952) (xy 382.899666 -143.000476)
			)
		)
	)
	(zone
		(layer "Cmts.User")
		(hatch none 0.5)
		(connect_pads
			(clearance 0)
		)
		(min_thickness 0.25)
		(keepout
			(tracks allowed)
			(vias allowed)
			(pads allowed)
			(copperpour allowed)
			(footprints allowed)
		)
		(placement
			(enabled no)
			(sheetname "")
		)
		(fill
			(thermal_gap 0.5)
			(thermal_bridge_width 0.5)
			(island_removal_mode 0)
		)
		(polygon
			(pts
				(xy 389.983218 -178.08194) (xy 389.424418 -178.08194) (xy 389.221218 -178.28514) (xy 389.221218 -178.97094)
				(xy 389.602218 -179.35194) (xy 390.186418 -179.35194) (xy 390.618218 -178.92014) (xy 390.618218 -178.71694)
			)
		)
	)
	(zone
		(layer "Cmts.User")
		(hatch none 0.5)
		(connect_pads
			(clearance 0)
		)
		(min_thickness 0.25)
		(keepout
			(tracks allowed)
			(vias allowed)
			(pads allowed)
			(copperpour allowed)
			(footprints allowed)
		)
		(placement
			(enabled no)
			(sheetname "")
		)
		(fill
			(thermal_gap 0.5)
			(thermal_bridge_width 0.5)
			(island_removal_mode 0)
		)
		(polygon
			(pts
				(xy 38.896544 -366.38484) (xy 38.896544 -365.754158) (xy 39.508938 -365.754158) (xy 39.508938 -366.38484)
			)
		)
	)
	(zone
		(layer "Cmts.User")
		(hatch none 0.5)
		(connect_pads
			(clearance 0)
		)
		(min_thickness 0.25)
		(keepout
			(tracks allowed)
			(vias allowed)
			(pads allowed)
			(copperpour allowed)
			(footprints allowed)
		)
		(placement
			(enabled no)
			(sheetname "")
		)
		(fill
			(thermal_gap 0.5)
			(thermal_bridge_width 0.5)
			(island_removal_mode 0)
		)
		(polygon
			(pts
				(xy 280.753058 -350.817434) (xy 280.072338 -350.817434) (xy 280.072338 -350.204278) (xy 280.753058 -350.204278)
			)
		)
	)
	(zone
		(layer "Cmts.User")
		(hatch none 0.5)
		(connect_pads
			(clearance 0)
		)
		(min_thickness 0.25)
		(keepout
			(tracks allowed)
			(vias allowed)
			(pads allowed)
			(copperpour allowed)
			(footprints allowed)
		)
		(placement
			(enabled no)
			(sheetname "")
		)
		(fill
			(thermal_gap 0.5)
			(thermal_bridge_width 0.5)
			(island_removal_mode 0)
		)
		(polygon
			(pts
				(xy 133.136894 -151.924512) (xy 132.374894 -151.924512) (xy 132.222494 -152.076912) (xy 132.222494 -152.737312)
				(xy 132.603494 -153.118312) (xy 133.263894 -153.118312) (xy 133.644894 -152.737312) (xy 133.644894 -152.432512)
			)
		)
	)
	(zone
		(layer "Cmts.User")
		(hatch none 0.5)
		(connect_pads
			(clearance 0)
		)
		(min_thickness 0.25)
		(keepout
			(tracks allowed)
			(vias allowed)
			(pads allowed)
			(copperpour allowed)
			(footprints allowed)
		)
		(placement
			(enabled no)
			(sheetname "")
		)
		(fill
			(thermal_gap 0.5)
			(thermal_bridge_width 0.5)
			(island_removal_mode 0)
		)
		(polygon
			(pts
				(xy 141.521942 -441.239148) (xy 141.521942 -425.547282) (xy 141.521942 -424.043348) (xy 157.727142 -424.043348)
				(xy 157.727142 -441.239148) (xy 155.349702 -441.239148)
			)
		)
	)
	(zone
		(layer "Cmts.User")
		(hatch none 0.5)
		(connect_pads
			(clearance 0)
		)
		(min_thickness 0.25)
		(keepout
			(tracks allowed)
			(vias allowed)
			(pads allowed)
			(copperpour allowed)
			(footprints allowed)
		)
		(placement
			(enabled no)
			(sheetname "")
		)
		(fill
			(thermal_gap 0.5)
			(thermal_bridge_width 0.5)
			(island_removal_mode 0)
		)
		(polygon
			(pts
				(xy 48.542194 -409.80487) (xy 95.677482 -409.80487) (xy 95.677482 -410.323538) (xy 48.542194 -410.323538)
				(xy 48.39589 -410.323538) (xy 48.354234 -410.281882) (xy 48.354234 -409.82773) (xy 48.377094 -409.80487)
			)
		)
	)
	(zone
		(layer "Cmts.User")
		(hatch none 0.5)
		(connect_pads
			(clearance 0)
		)
		(min_thickness 0.25)
		(keepout
			(tracks allowed)
			(vias allowed)
			(pads allowed)
			(copperpour allowed)
			(footprints allowed)
		)
		(placement
			(enabled no)
			(sheetname "")
		)
		(fill
			(thermal_gap 0.5)
			(thermal_bridge_width 0.5)
			(island_removal_mode 0)
		)
		(polygon
			(pts
				(xy 181.066694 -354.908612) (xy 180.863494 -354.908612) (xy 180.711094 -355.061012) (xy 180.711094 -355.721412)
				(xy 180.965094 -355.975412) (xy 181.015894 -355.975412) (xy 181.168294 -355.823012) (xy 181.168294 -355.010212)
			)
		)
	)
	(zone
		(layer "Cmts.User")
		(hatch none 0.5)
		(connect_pads
			(clearance 0)
		)
		(min_thickness 0.25)
		(keepout
			(tracks allowed)
			(vias allowed)
			(pads allowed)
			(copperpour allowed)
			(footprints allowed)
		)
		(placement
			(enabled no)
			(sheetname "")
		)
		(fill
			(thermal_gap 0.5)
			(thermal_bridge_width 0.5)
			(island_removal_mode 0)
		)
		(polygon
			(pts
				(xy 314.16371 -337.476846) (xy 314.16371 -335.419446) (xy 315.104526 -335.419446) (xy 315.104526 -337.476846)
			)
		)
	)
	(zone
		(layer "Cmts.User")
		(hatch none 0.5)
		(connect_pads
			(clearance 0)
		)
		(min_thickness 0.25)
		(keepout
			(tracks allowed)
			(vias allowed)
			(pads allowed)
			(copperpour allowed)
			(footprints allowed)
		)
		(placement
			(enabled no)
			(sheetname "")
		)
		(fill
			(thermal_gap 0.5)
			(thermal_bridge_width 0.5)
			(island_removal_mode 0)
		)
		(polygon
			(pts
				(xy 430.064418 -354.807012) (xy 429.886618 -354.807012) (xy 429.861218 -354.832412) (xy 429.861218 -355.670612)
				(xy 429.937418 -355.746812) (xy 430.064418 -355.746812) (xy 430.140618 -355.670612) (xy 430.140618 -354.883212)
			)
		)
	)
	(zone
		(layer "Cmts.User")
		(hatch none 0.5)
		(connect_pads
			(clearance 0)
		)
		(min_thickness 0.25)
		(keepout
			(tracks allowed)
			(vias allowed)
			(pads allowed)
			(copperpour allowed)
			(footprints allowed)
		)
		(placement
			(enabled no)
			(sheetname "")
		)
		(fill
			(thermal_gap 0.5)
			(thermal_bridge_width 0.5)
			(island_removal_mode 0)
		)
		(polygon
			(pts
				(xy 115.642136 -406.779222) (xy 162.777424 -406.779222) (xy 162.777424 -407.29789) (xy 115.642136 -407.29789)
				(xy 115.495832 -407.29789) (xy 115.454176 -407.256234) (xy 115.454176 -406.802082) (xy 115.477036 -406.779222)
			)
		)
	)
	(zone
		(layer "Cmts.User")
		(hatch none 0.5)
		(connect_pads
			(clearance 0)
		)
		(min_thickness 0.25)
		(keepout
			(tracks allowed)
			(vias allowed)
			(pads allowed)
			(copperpour allowed)
			(footprints allowed)
		)
		(placement
			(enabled no)
			(sheetname "")
		)
		(fill
			(thermal_gap 0.5)
			(thermal_bridge_width 0.5)
			(island_removal_mode 0)
		)
		(polygon
			(pts
				(xy 114.170206 -23.775416) (xy 114.170206 -24.51354) (xy 112.788192 -24.51354) (xy 112.788192 -23.775416)
			)
		)
	)
	(zone
		(layer "Cmts.User")
		(hatch none 0.5)
		(connect_pads
			(clearance 0)
		)
		(min_thickness 0.25)
		(keepout
			(tracks allowed)
			(vias allowed)
			(pads allowed)
			(copperpour allowed)
			(footprints allowed)
		)
		(placement
			(enabled no)
			(sheetname "")
		)
		(fill
			(thermal_gap 0.5)
			(thermal_bridge_width 0.5)
			(island_removal_mode 0)
		)
		(polygon
			(pts
				(xy 92.700094 -178.061112) (xy 92.623894 -178.061112) (xy 92.471494 -178.213512) (xy 92.471494 -178.899312)
				(xy 92.598494 -179.026312) (xy 92.674694 -179.026312) (xy 92.776294 -178.924712) (xy 92.776294 -178.137312)
			)
		)
	)
	(zone
		(layer "Cmts.User")
		(hatch none 0.5)
		(connect_pads
			(clearance 0)
		)
		(min_thickness 0.25)
		(keepout
			(tracks allowed)
			(vias allowed)
			(pads allowed)
			(copperpour allowed)
			(footprints allowed)
		)
		(placement
			(enabled no)
			(sheetname "")
		)
		(fill
			(thermal_gap 0.5)
			(thermal_bridge_width 0.5)
			(island_removal_mode 0)
		)
		(polygon
			(pts
				(xy 334.872076 -393.07008) (xy 334.872076 -391.083546) (xy 354.993956 -391.083546) (xy 354.993956 -393.07008)
				(xy 354.993956 -394.504672) (xy 335.76387 -394.504672) (xy 335.76387 -393.07008)
			)
		)
	)
	(zone
		(layer "Cmts.User")
		(hatch none 0.5)
		(connect_pads
			(clearance 0)
		)
		(min_thickness 0.25)
		(keepout
			(tracks allowed)
			(vias allowed)
			(pads allowed)
			(copperpour allowed)
			(footprints allowed)
		)
		(placement
			(enabled no)
			(sheetname "")
		)
		(fill
			(thermal_gap 0.5)
			(thermal_bridge_width 0.5)
			(island_removal_mode 0)
		)
		(polygon
			(pts
				(xy 182.743094 -354.832412) (xy 182.133494 -354.832412) (xy 181.854094 -355.111812) (xy 182.590694 -355.848412)
				(xy 182.997094 -355.848412) (xy 183.098694 -355.746812) (xy 183.098694 -355.188012)
			)
		)
	)
	(zone
		(layer "Cmts.User")
		(hatch none 0.5)
		(connect_pads
			(clearance 0)
		)
		(min_thickness 0.25)
		(keepout
			(tracks allowed)
			(vias allowed)
			(pads allowed)
			(copperpour allowed)
			(footprints allowed)
		)
		(placement
			(enabled no)
			(sheetname "")
		)
		(fill
			(thermal_gap 0.5)
			(thermal_bridge_width 0.5)
			(island_removal_mode 0)
		)
		(polygon
			(pts
				(xy 66.414904 -336.958686) (xy 66.414904 -336.328004) (xy 67.027298 -336.328004) (xy 67.027298 -336.958686)
			)
		)
	)
	(zone
		(layer "Cmts.User")
		(hatch none 0.5)
		(connect_pads
			(clearance 0)
		)
		(min_thickness 0.25)
		(keepout
			(tracks allowed)
			(vias allowed)
			(pads allowed)
			(copperpour allowed)
			(footprints allowed)
		)
		(placement
			(enabled no)
			(sheetname "")
		)
		(fill
			(thermal_gap 0.5)
			(thermal_bridge_width 0.5)
			(island_removal_mode 0)
		)
		(polygon
			(pts
				(xy 274.30095 -351.343214) (xy 274.30095 -350.151446) (xy 275.681186 -350.151446) (xy 275.681186 -351.343214)
			)
		)
	)
	(zone
		(layer "Cmts.User")
		(hatch none 0.5)
		(connect_pads
			(clearance 0)
		)
		(min_thickness 0.25)
		(keepout
			(tracks allowed)
			(vias allowed)
			(pads allowed)
			(copperpour allowed)
			(footprints allowed)
		)
		(placement
			(enabled no)
			(sheetname "")
		)
		(fill
			(thermal_gap 0.5)
			(thermal_bridge_width 0.5)
			(island_removal_mode 0)
		)
		(polygon
			(pts
				(xy 115.642136 -409.80487) (xy 162.777424 -409.80487) (xy 162.777424 -410.323538) (xy 115.642136 -410.323538)
				(xy 115.495832 -410.323538) (xy 115.454176 -410.281882) (xy 115.454176 -409.82773) (xy 115.477036 -409.80487)
			)
		)
	)
	(zone
		(layer "Cmts.User")
		(hatch none 0.5)
		(connect_pads
			(clearance 0)
		)
		(min_thickness 0.25)
		(keepout
			(tracks allowed)
			(vias allowed)
			(pads allowed)
			(copperpour allowed)
			(footprints allowed)
		)
		(placement
			(enabled no)
			(sheetname "")
		)
		(fill
			(thermal_gap 0.5)
			(thermal_bridge_width 0.5)
			(island_removal_mode 0)
		)
		(polygon
			(pts
				(xy 40.280844 -349.090742) (xy 40.280844 -348.46006) (xy 40.893238 -348.46006) (xy 40.893238 -349.090742)
			)
		)
	)
	(zone
		(layer "Cmts.User")
		(hatch none 0.5)
		(connect_pads
			(clearance 0)
		)
		(min_thickness 0.25)
		(keepout
			(tracks allowed)
			(vias allowed)
			(pads allowed)
			(copperpour allowed)
			(footprints allowed)
		)
		(placement
			(enabled no)
			(sheetname "")
		)
		(fill
			(thermal_gap 0.5)
			(thermal_bridge_width 0.5)
			(island_removal_mode 0)
		)
		(polygon
			(pts
				(xy 333.937864 -339.60054) (xy 333.937864 -338.408772) (xy 335.3181 -338.408772) (xy 335.3181 -339.60054)
			)
		)
	)
	(zone
		(layer "Cmts.User")
		(hatch none 0.5)
		(connect_pads
			(clearance 0)
		)
		(min_thickness 0.25)
		(keepout
			(tracks allowed)
			(vias allowed)
			(pads allowed)
			(copperpour allowed)
			(footprints allowed)
		)
		(placement
			(enabled no)
			(sheetname "")
		)
		(fill
			(thermal_gap 0.5)
			(thermal_bridge_width 0.5)
			(island_removal_mode 0)
		)
		(polygon
			(pts
				(xy 296.182796 -349.19793) (xy 296.182796 -347.14053) (xy 297.123612 -347.14053) (xy 297.123612 -349.19793)
			)
		)
	)
	(zone
		(layer "Cmts.User")
		(hatch none 0.5)
		(connect_pads
			(clearance 0)
		)
		(min_thickness 0.25)
		(keepout
			(tracks allowed)
			(vias allowed)
			(pads allowed)
			(copperpour allowed)
			(footprints allowed)
		)
		(placement
			(enabled no)
			(sheetname "")
		)
		(fill
			(thermal_gap 0.5)
			(thermal_bridge_width 0.5)
			(island_removal_mode 0)
		)
		(polygon
			(pts
				(xy 279.520396 -349.19793) (xy 279.520396 -347.14053) (xy 280.461212 -347.14053) (xy 280.461212 -349.19793)
			)
		)
	)
	(zone
		(layer "Cmts.User")
		(hatch none 0.5)
		(connect_pads
			(clearance 0)
		)
		(min_thickness 0.25)
		(keepout
			(tracks allowed)
			(vias allowed)
			(pads allowed)
			(copperpour allowed)
			(footprints allowed)
		)
		(placement
			(enabled no)
			(sheetname "")
		)
		(fill
			(thermal_gap 0.5)
			(thermal_bridge_width 0.5)
			(island_removal_mode 0)
		)
		(polygon
			(pts
				(xy 303.438306 -399.507456) (xy 322.088764 -399.507456) (xy 322.088764 -402.229574) (xy 322.088764 -402.52396)
				(xy 302.951134 -402.52396) (xy 302.951134 -399.507456)
			)
		)
	)
	(zone
		(layer "Cmts.User")
		(hatch none 0.5)
		(connect_pads
			(clearance 0)
		)
		(min_thickness 0.25)
		(keepout
			(tracks allowed)
			(vias allowed)
			(pads allowed)
			(copperpour allowed)
			(footprints allowed)
		)
		(placement
			(enabled no)
			(sheetname "")
		)
		(fill
			(thermal_gap 0.5)
			(thermal_bridge_width 0.5)
			(island_removal_mode 0)
		)
		(polygon
			(pts
				(xy 317.224664 -339.62213) (xy 317.224664 -338.430362) (xy 318.6049 -338.430362) (xy 318.6049 -339.62213)
			)
		)
	)
	(zone
		(layer "Cmts.User")
		(hatch none 0.5)
		(connect_pads
			(clearance 0)
		)
		(min_thickness 0.25)
		(keepout
			(tracks allowed)
			(vias allowed)
			(pads allowed)
			(copperpour allowed)
			(footprints allowed)
		)
		(placement
			(enabled no)
			(sheetname "")
		)
		(fill
			(thermal_gap 0.5)
			(thermal_bridge_width 0.5)
			(island_removal_mode 0)
		)
		(polygon
			(pts
				(xy 103.53929 -343.407492) (xy 103.02367 -343.407492) (xy 102.65537 -343.775792) (xy 103.32339 -344.443812)
				(xy 103.71201 -344.443812) (xy 103.79075 -344.365072) (xy 103.79075 -343.658952)
			)
		)
	)
	(zone
		(layer "Cmts.User")
		(hatch none 0.5)
		(connect_pads
			(clearance 0)
		)
		(min_thickness 0.25)
		(keepout
			(tracks allowed)
			(vias allowed)
			(pads allowed)
			(copperpour allowed)
			(footprints allowed)
		)
		(placement
			(enabled no)
			(sheetname "")
		)
		(fill
			(thermal_gap 0.5)
			(thermal_bridge_width 0.5)
			(island_removal_mode 0)
		)
		(polygon
			(pts
				(xy 370.538502 -399.507456) (xy 389.18896 -399.507456) (xy 389.18896 -402.229574) (xy 389.18896 -402.52396)
				(xy 370.05133 -402.52396) (xy 370.05133 -399.507456)
			)
		)
	)
	(zone
		(layer "Cmts.User")
		(hatch none 0.5)
		(connect_pads
			(clearance 0)
		)
		(min_thickness 0.25)
		(keepout
			(tracks allowed)
			(vias allowed)
			(pads allowed)
			(copperpour allowed)
			(footprints allowed)
		)
		(placement
			(enabled no)
			(sheetname "")
		)
		(fill
			(thermal_gap 0.5)
			(thermal_bridge_width 0.5)
			(island_removal_mode 0)
		)
		(polygon
			(pts
				(xy 83.128104 -336.937096) (xy 83.128104 -336.306414) (xy 83.740498 -336.306414) (xy 83.740498 -336.937096)
			)
		)
	)
	(zone
		(layer "Cmts.User")
		(hatch none 0.5)
		(connect_pads
			(clearance 0)
		)
		(min_thickness 0.25)
		(keepout
			(tracks allowed)
			(vias allowed)
			(pads allowed)
			(copperpour allowed)
			(footprints allowed)
		)
		(placement
			(enabled no)
			(sheetname "")
		)
		(fill
			(thermal_gap 0.5)
			(thermal_bridge_width 0.5)
			(island_removal_mode 0)
		)
		(polygon
			(pts
				(xy 401.667218 -175.229012) (xy 401.286218 -175.229012) (xy 401.159218 -175.356012) (xy 401.159218 -176.346612)
				(xy 401.286218 -176.473612) (xy 401.743418 -176.473612) (xy 401.845018 -176.372012) (xy 401.845018 -175.406812)
			)
		)
	)
	(zone
		(layer "Cmts.User")
		(hatch none 0.5)
		(connect_pads
			(clearance 0)
		)
		(min_thickness 0.25)
		(keepout
			(tracks allowed)
			(vias allowed)
			(pads allowed)
			(copperpour allowed)
			(footprints allowed)
		)
		(placement
			(enabled no)
			(sheetname "")
		)
		(fill
			(thermal_gap 0.5)
			(thermal_bridge_width 0.5)
			(island_removal_mode 0)
		)
		(polygon
			(pts
				(xy 46.344586 -384.68808) (xy 46.344586 -382.701546) (xy 66.466466 -382.701546) (xy 66.466466 -384.68808)
				(xy 66.466466 -386.122672) (xy 47.23638 -386.122672) (xy 47.23638 -384.68808)
			)
		)
	)
	(zone
		(layer "Cmts.User")
		(hatch none 0.5)
		(connect_pads
			(clearance 0)
		)
		(min_thickness 0.25)
		(keepout
			(tracks allowed)
			(vias allowed)
			(pads allowed)
			(copperpour allowed)
			(footprints allowed)
		)
		(placement
			(enabled no)
			(sheetname "")
		)
		(fill
			(thermal_gap 0.5)
			(thermal_bridge_width 0.5)
			(island_removal_mode 0)
		)
		(polygon
			(pts
				(xy 302.344328 -393.07008) (xy 302.344328 -391.083546) (xy 322.466208 -391.083546) (xy 322.466208 -393.07008)
				(xy 322.466208 -394.504672) (xy 303.236122 -394.504672) (xy 303.236122 -393.07008)
			)
		)
	)
	(zone
		(layer "Cmts.User")
		(hatch none 0.5)
		(connect_pads
			(clearance 0)
		)
		(min_thickness 0.25)
		(keepout
			(tracks allowed)
			(vias allowed)
			(pads allowed)
			(copperpour allowed)
			(footprints allowed)
		)
		(placement
			(enabled no)
			(sheetname "")
		)
		(fill
			(thermal_gap 0.5)
			(thermal_bridge_width 0.5)
			(island_removal_mode 0)
		)
		(polygon
			(pts
				(xy 451.914768 -18.930366) (xy 451.914768 -18.299684) (xy 452.527162 -18.299684) (xy 452.527162 -18.930366)
			)
		)
	)
	(zone
		(layer "Cmts.User")
		(hatch none 0.5)
		(connect_pads
			(clearance 0)
		)
		(min_thickness 0.25)
		(keepout
			(tracks allowed)
			(vias allowed)
			(pads allowed)
			(copperpour allowed)
			(footprints allowed)
		)
		(placement
			(enabled no)
			(sheetname "")
		)
		(fill
			(thermal_gap 0.5)
			(thermal_bridge_width 0.5)
			(island_removal_mode 0)
		)
		(polygon
			(pts
				(xy 190.52794 -141.9352) (xy 190.52794 -140.60932) (xy 191.38138 -140.60932) (xy 191.38138 -141.9352)
			)
		)
	)
	(zone
		(layer "Cmts.User")
		(hatch none 0.5)
		(connect_pads
			(clearance 0)
		)
		(min_thickness 0.25)
		(keepout
			(tracks allowed)
			(vias allowed)
			(pads allowed)
			(copperpour allowed)
			(footprints allowed)
		)
		(placement
			(enabled no)
			(sheetname "")
		)
		(fill
			(thermal_gap 0.5)
			(thermal_bridge_width 0.5)
			(island_removal_mode 0)
		)
		(polygon
			(pts
				(xy 406.671018 -163.824412) (xy 406.086818 -163.824412) (xy 405.883618 -164.027612) (xy 405.883618 -164.916612)
				(xy 406.264618 -165.297612) (xy 407.052018 -165.297612) (xy 407.407618 -164.942012) (xy 407.407618 -164.561012)
			)
		)
	)
	(zone
		(layer "Cmts.User")
		(hatch none 0.5)
		(connect_pads
			(clearance 0)
		)
		(min_thickness 0.25)
		(keepout
			(tracks allowed)
			(vias allowed)
			(pads allowed)
			(copperpour allowed)
			(footprints allowed)
		)
		(placement
			(enabled no)
			(sheetname "")
		)
		(fill
			(thermal_gap 0.5)
			(thermal_bridge_width 0.5)
			(island_removal_mode 0)
		)
		(polygon
			(pts
				(xy 422.596818 -361.309412) (xy 422.317418 -361.309412) (xy 422.190418 -361.436412) (xy 422.190418 -362.858812)
				(xy 422.368218 -363.036612) (xy 422.520618 -363.036612) (xy 422.825418 -362.731812) (xy 422.825418 -361.538012)
			)
		)
	)
	(zone
		(layer "Cmts.User")
		(hatch none 0.5)
		(connect_pads
			(clearance 0)
		)
		(min_thickness 0.25)
		(keepout
			(tracks allowed)
			(vias allowed)
			(pads allowed)
			(copperpour allowed)
			(footprints allowed)
		)
		(placement
			(enabled no)
			(sheetname "")
		)
		(fill
			(thermal_gap 0.5)
			(thermal_bridge_width 0.5)
			(island_removal_mode 0)
		)
		(polygon
			(pts
				(xy 431.740818 -354.527612) (xy 431.258218 -354.527612) (xy 430.801018 -354.984812) (xy 431.588418 -355.772212)
				(xy 431.944018 -355.772212) (xy 432.172618 -355.543612) (xy 432.172618 -354.959412)
			)
		)
	)
	(zone
		(layer "Cmts.User")
		(hatch none 0.5)
		(connect_pads
			(clearance 0)
		)
		(min_thickness 0.25)
		(keepout
			(tracks allowed)
			(vias allowed)
			(pads allowed)
			(copperpour allowed)
			(footprints allowed)
		)
		(placement
			(enabled no)
			(sheetname "")
		)
		(fill
			(thermal_gap 0.5)
			(thermal_bridge_width 0.5)
			(island_removal_mode 0)
		)
		(polygon
			(pts
				(xy 421.809418 -354.807012) (xy 421.631618 -354.807012) (xy 421.530018 -354.908612) (xy 421.530018 -355.645212)
				(xy 421.657018 -355.772212) (xy 421.707818 -355.772212) (xy 421.809418 -355.670612)
			)
		)
	)
	(zone
		(layer "Cmts.User")
		(hatch none 0.5)
		(connect_pads
			(clearance 0)
		)
		(min_thickness 0.25)
		(keepout
			(tracks allowed)
			(vias allowed)
			(pads allowed)
			(copperpour allowed)
			(footprints allowed)
		)
		(placement
			(enabled no)
			(sheetname "")
		)
		(fill
			(thermal_gap 0.5)
			(thermal_bridge_width 0.5)
			(island_removal_mode 0)
		)
		(polygon
			(pts
				(xy 347.483938 -342.41613) (xy 347.483938 -340.35873) (xy 348.424754 -340.35873) (xy 348.424754 -342.41613)
			)
		)
	)
	(zone
		(layer "Cmts.User")
		(hatch none 0.5)
		(connect_pads
			(clearance 0)
		)
		(min_thickness 0.25)
		(keepout
			(tracks allowed)
			(vias allowed)
			(pads allowed)
			(copperpour allowed)
			(footprints allowed)
		)
		(placement
			(enabled no)
			(sheetname "")
		)
		(fill
			(thermal_gap 0.5)
			(thermal_bridge_width 0.5)
			(island_removal_mode 0)
		)
		(polygon
			(pts
				(xy 307.57495 -351.343214) (xy 307.57495 -350.151446) (xy 308.955186 -350.151446) (xy 308.955186 -351.343214)
			)
		)
	)
	(zone
		(layer "Cmts.User")
		(hatch none 0.5)
		(connect_pads
			(clearance 0)
		)
		(min_thickness 0.25)
		(keepout
			(tracks allowed)
			(vias allowed)
			(pads allowed)
			(copperpour allowed)
			(footprints allowed)
		)
		(placement
			(enabled no)
			(sheetname "")
		)
		(fill
			(thermal_gap 0.5)
			(thermal_bridge_width 0.5)
			(island_removal_mode 0)
		)
		(polygon
			(pts
				(xy 108.131864 -336.662776) (xy 108.131864 -330.042012) (xy 114.67973 -330.042012) (xy 114.67973 -336.662776)
			)
		)
	)
	(zone
		(layer "Cmts.User")
		(hatch none 0.5)
		(connect_pads
			(clearance 0)
		)
		(min_thickness 0.25)
		(keepout
			(tracks allowed)
			(vias allowed)
			(pads allowed)
			(copperpour allowed)
			(footprints allowed)
		)
		(placement
			(enabled no)
			(sheetname "")
		)
		(fill
			(thermal_gap 0.5)
			(thermal_bridge_width 0.5)
			(island_removal_mode 0)
		)
		(polygon
			(pts
				(xy 93.703902 -179.160424) (xy 93.703902 -178.613816) (xy 94.268544 -178.613816) (xy 94.268544 -179.160424)
			)
		)
	)
	(zone
		(layer "Cmts.User")
		(hatch none 0.5)
		(connect_pads
			(clearance 0)
		)
		(min_thickness 0.25)
		(keepout
			(tracks allowed)
			(vias allowed)
			(pads allowed)
			(copperpour allowed)
			(footprints allowed)
		)
		(placement
			(enabled no)
			(sheetname "")
		)
		(fill
			(thermal_gap 0.5)
			(thermal_bridge_width 0.5)
			(island_removal_mode 0)
		)
		(polygon
			(pts
				(xy 100.447094 -144.202912) (xy 100.269294 -144.202912) (xy 99.685094 -144.787112) (xy 99.685094 -145.193512)
				(xy 99.862894 -145.371312) (xy 100.015294 -145.371312) (xy 100.624894 -144.761712) (xy 100.624894 -144.380712)
			)
		)
	)
	(zone
		(layer "Cmts.User")
		(hatch none 0.5)
		(connect_pads
			(clearance 0)
		)
		(min_thickness 0.25)
		(keepout
			(tracks allowed)
			(vias allowed)
			(pads allowed)
			(copperpour allowed)
			(footprints allowed)
		)
		(placement
			(enabled no)
			(sheetname "")
		)
		(fill
			(thermal_gap 0.5)
			(thermal_bridge_width 0.5)
			(island_removal_mode 0)
		)
		(polygon
			(pts
				(xy 69.513958 -166.960804) (xy 69.158358 -166.960804) (xy 69.056758 -167.062404) (xy 69.056758 -168.129204)
				(xy 69.132958 -168.205404) (xy 69.539358 -168.205404) (xy 69.615558 -168.129204) (xy 69.615558 -167.062404)
			)
		)
	)
	(zone
		(layer "Cmts.User")
		(hatch none 0.5)
		(connect_pads
			(clearance 0)
		)
		(min_thickness 0.25)
		(keepout
			(tracks allowed)
			(vias allowed)
			(pads allowed)
			(copperpour allowed)
			(footprints allowed)
		)
		(placement
			(enabled no)
			(sheetname "")
		)
		(fill
			(thermal_gap 0.5)
			(thermal_bridge_width 0.5)
			(island_removal_mode 0)
		)
		(polygon
			(pts
				(xy 356.683818 -164.840412) (xy 355.998018 -164.840412) (xy 355.845618 -164.992812) (xy 355.845618 -165.754812)
				(xy 356.226618 -166.135812) (xy 356.785418 -166.135812) (xy 357.242618 -165.678612) (xy 357.242618 -165.399212)
			)
		)
	)
	(zone
		(layer "Cmts.User")
		(hatch none 0.5)
		(connect_pads
			(clearance 0)
		)
		(min_thickness 0.25)
		(keepout
			(tracks allowed)
			(vias allowed)
			(pads allowed)
			(copperpour allowed)
			(footprints allowed)
		)
		(placement
			(enabled no)
			(sheetname "")
		)
		(fill
			(thermal_gap 0.5)
			(thermal_bridge_width 0.5)
			(island_removal_mode 0)
		)
		(polygon
			(pts
				(xy 114.538506 -391.125456) (xy 133.188964 -391.125456) (xy 133.188964 -393.847574) (xy 133.188964 -394.14196)
				(xy 114.051334 -394.14196) (xy 114.051334 -391.125456)
			)
		)
	)
	(zone
		(layer "Cmts.User")
		(hatch none 0.5)
		(connect_pads
			(clearance 0)
		)
		(min_thickness 0.25)
		(keepout
			(tracks allowed)
			(vias allowed)
			(pads allowed)
			(copperpour allowed)
			(footprints allowed)
		)
		(placement
			(enabled no)
			(sheetname "")
		)
		(fill
			(thermal_gap 0.5)
			(thermal_bridge_width 0.5)
			(island_removal_mode 0)
		)
		(polygon
			(pts
				(xy 41.571926 -350.806766) (xy 41.571926 -350.176084) (xy 42.18432 -350.176084) (xy 42.18432 -350.806766)
			)
		)
	)
	(zone
		(layer "Cmts.User")
		(hatch none 0.5)
		(connect_pads
			(clearance 0)
		)
		(min_thickness 0.25)
		(keepout
			(tracks allowed)
			(vias allowed)
			(pads allowed)
			(copperpour allowed)
			(footprints allowed)
		)
		(placement
			(enabled no)
			(sheetname "")
		)
		(fill
			(thermal_gap 0.5)
			(thermal_bridge_width 0.5)
			(island_removal_mode 0)
		)
		(polygon
			(pts
				(xy 359.04297 -166.217854) (xy 359.04297 -165.58133) (xy 359.643426 -165.58133) (xy 359.643426 -166.217854)
			)
		)
	)
	(zone
		(layer "Cmts.User")
		(hatch none 0.5)
		(connect_pads
			(clearance 0)
		)
		(min_thickness 0.25)
		(keepout
			(tracks allowed)
			(vias allowed)
			(pads allowed)
			(copperpour allowed)
			(footprints allowed)
		)
		(placement
			(enabled no)
			(sheetname "")
		)
		(fill
			(thermal_gap 0.5)
			(thermal_bridge_width 0.5)
			(island_removal_mode 0)
		)
		(polygon
			(pts
				(xy 76.10983 -172.855382) (xy 75.75423 -172.855382) (xy 75.65263 -172.956982) (xy 75.65263 -174.023782)
				(xy 75.72883 -174.099982) (xy 76.13523 -174.099982) (xy 76.21143 -174.023782) (xy 76.21143 -172.956982)
			)
		)
	)
	(zone
		(layer "Cmts.User")
		(hatch none 0.5)
		(connect_pads
			(clearance 0)
		)
		(min_thickness 0.25)
		(keepout
			(tracks allowed)
			(vias allowed)
			(pads allowed)
			(copperpour allowed)
			(footprints allowed)
		)
		(placement
			(enabled no)
			(sheetname "")
		)
		(fill
			(thermal_gap 0.5)
			(thermal_bridge_width 0.5)
			(island_removal_mode 0)
		)
		(polygon
			(pts
				(xy 428.362618 -351.936812) (xy 428.159418 -351.936812) (xy 428.108618 -351.987612) (xy 428.108618 -352.851212)
				(xy 428.210218 -352.952812) (xy 428.413418 -352.952812) (xy 428.489618 -352.876612) (xy 428.489618 -352.063812)
			)
		)
	)
	(zone
		(layer "Cmts.User")
		(hatch none 0.5)
		(connect_pads
			(clearance 0)
		)
		(min_thickness 0.25)
		(keepout
			(tracks allowed)
			(vias allowed)
			(pads allowed)
			(copperpour allowed)
			(footprints allowed)
		)
		(placement
			(enabled no)
			(sheetname "")
		)
		(fill
			(thermal_gap 0.5)
			(thermal_bridge_width 0.5)
			(island_removal_mode 0)
		)
		(polygon
			(pts
				(xy 115.530376 -404.239222) (xy 160.90265 -404.239222) (xy 160.90265 -404.75789) (xy 115.530376 -404.75789)
				(xy 115.384072 -404.75789) (xy 115.342416 -404.716234) (xy 115.342416 -404.262082) (xy 115.365276 -404.239222)
			)
		)
	)
	(zone
		(layer "Cmts.User")
		(hatch none 0.5)
		(connect_pads
			(clearance 0)
		)
		(min_thickness 0.25)
		(keepout
			(tracks allowed)
			(vias allowed)
			(pads allowed)
			(copperpour allowed)
			(footprints allowed)
		)
		(placement
			(enabled no)
			(sheetname "")
		)
		(fill
			(thermal_gap 0.5)
			(thermal_bridge_width 0.5)
			(island_removal_mode 0)
		)
		(polygon
			(pts
				(xy 48.430434 -412.863538) (xy 48.430434 -412.34487) (xy 95.565722 -412.34487) (xy 95.565722 -412.863538)
			)
		)
	)
	(zone
		(layer "Cmts.User")
		(hatch none 0.5)
		(connect_pads
			(clearance 0)
		)
		(min_thickness 0.25)
		(keepout
			(tracks allowed)
			(vias allowed)
			(pads allowed)
			(copperpour allowed)
			(footprints allowed)
		)
		(placement
			(enabled no)
			(sheetname "")
		)
		(fill
			(thermal_gap 0.5)
			(thermal_bridge_width 0.5)
			(island_removal_mode 0)
		)
		(polygon
			(pts
				(xy 450.34962 -14.844268) (xy 450.34962 -14.213586) (xy 450.962014 -14.213586) (xy 450.962014 -14.844268)
			)
		)
	)
	(zone
		(layer "Cmts.User")
		(hatch none 0.5)
		(connect_pads
			(clearance 0)
		)
		(min_thickness 0.25)
		(keepout
			(tracks allowed)
			(vias allowed)
			(pads allowed)
			(copperpour allowed)
			(footprints allowed)
		)
		(placement
			(enabled no)
			(sheetname "")
		)
		(fill
			(thermal_gap 0.5)
			(thermal_bridge_width 0.5)
			(island_removal_mode 0)
		)
		(polygon
			(pts
				(xy 25.599898 -392.385296) (xy 25.599898 -392.998452) (xy 24.32558 -392.998452) (xy 24.32558 -392.385296)
			)
		)
	)
	(zone
		(layer "Cmts.User")
		(hatch none 0.5)
		(connect_pads
			(clearance 0)
		)
		(min_thickness 0.25)
		(keepout
			(tracks allowed)
			(vias allowed)
			(pads allowed)
			(copperpour allowed)
			(footprints allowed)
		)
		(placement
			(enabled no)
			(sheetname "")
		)
		(fill
			(thermal_gap 0.5)
			(thermal_bridge_width 0.5)
			(island_removal_mode 0)
		)
		(polygon
			(pts
				(xy 299.24375 -351.343214) (xy 299.24375 -350.151446) (xy 300.623986 -350.151446) (xy 300.623986 -351.343214)
			)
		)
	)
	(zone
		(layer "Cmts.User")
		(hatch none 0.5)
		(connect_pads
			(clearance 0)
		)
		(min_thickness 0.25)
		(keepout
			(tracks allowed)
			(vias allowed)
			(pads allowed)
			(copperpour allowed)
			(footprints allowed)
		)
		(placement
			(enabled no)
			(sheetname "")
		)
		(fill
			(thermal_gap 0.5)
			(thermal_bridge_width 0.5)
			(island_removal_mode 0)
		)
		(polygon
			(pts
				(xy 402.68017 -398.808702) (xy 402.68017 -396.509494) (xy 422.066212 -396.509494) (xy 422.066212 -398.808702)
			)
		)
	)
	(zone
		(layer "Cmts.User")
		(hatch none 0.5)
		(connect_pads
			(clearance 0)
		)
		(min_thickness 0.25)
		(keepout
			(tracks allowed)
			(vias allowed)
			(pads allowed)
			(copperpour allowed)
			(footprints allowed)
		)
		(placement
			(enabled no)
			(sheetname "")
		)
		(fill
			(thermal_gap 0.5)
			(thermal_bridge_width 0.5)
			(island_removal_mode 0)
		)
		(polygon
			(pts
				(xy 124.678694 -160.611312) (xy 123.916694 -160.611312) (xy 123.789694 -160.738312) (xy 123.789694 -161.424112)
				(xy 124.094494 -161.728912) (xy 124.881894 -161.728912) (xy 125.161294 -161.449512) (xy 125.161294 -161.093912)
			)
		)
	)
	(zone
		(layer "Cmts.User")
		(hatch none 0.5)
		(connect_pads
			(clearance 0)
		)
		(min_thickness 0.25)
		(keepout
			(tracks allowed)
			(vias allowed)
			(pads allowed)
			(copperpour allowed)
			(footprints allowed)
		)
		(placement
			(enabled no)
			(sheetname "")
		)
		(fill
			(thermal_gap 0.5)
			(thermal_bridge_width 0.5)
			(island_removal_mode 0)
		)
		(polygon
			(pts
				(xy 86.84641 -338.563712) (xy 86.31301 -338.563712) (xy 85.99551 -338.881212) (xy 86.57463 -339.460332)
				(xy 87.16899 -339.460332) (xy 87.16899 -338.886292)
			)
		)
	)
	(zone
		(layer "Cmts.User")
		(hatch none 0.5)
		(connect_pads
			(clearance 0)
		)
		(min_thickness 0.25)
		(keepout
			(tracks allowed)
			(vias allowed)
			(pads allowed)
			(copperpour allowed)
			(footprints allowed)
		)
		(placement
			(enabled no)
			(sheetname "")
		)
		(fill
			(thermal_gap 0.5)
			(thermal_bridge_width 0.5)
			(island_removal_mode 0)
		)
		(polygon
			(pts
				(xy 47.052484 -390.426702) (xy 47.052484 -388.127494) (xy 66.438526 -388.127494) (xy 66.438526 -390.426702)
			)
		)
	)
	(zone
		(layer "Cmts.User")
		(hatch none 0.5)
		(connect_pads
			(clearance 0)
		)
		(min_thickness 0.25)
		(keepout
			(tracks allowed)
			(vias allowed)
			(pads allowed)
			(copperpour allowed)
			(footprints allowed)
		)
		(placement
			(enabled no)
			(sheetname "")
		)
		(fill
			(thermal_gap 0.5)
			(thermal_bridge_width 0.5)
			(island_removal_mode 0)
		)
		(polygon
			(pts
				(xy 101.132894 -178.111912) (xy 100.929694 -178.111912) (xy 100.853494 -178.188112) (xy 100.853494 -178.950112)
				(xy 100.955094 -179.051712) (xy 101.132894 -179.051712) (xy 101.209094 -178.975512) (xy 101.209094 -178.188112)
			)
		)
	)
	(zone
		(layer "Cmts.User")
		(hatch none 0.5)
		(connect_pads
			(clearance 0)
		)
		(min_thickness 0.25)
		(keepout
			(tracks allowed)
			(vias allowed)
			(pads allowed)
			(copperpour allowed)
			(footprints allowed)
		)
		(placement
			(enabled no)
			(sheetname "")
		)
		(fill
			(thermal_gap 0.5)
			(thermal_bridge_width 0.5)
			(island_removal_mode 0)
		)
		(polygon
			(pts
				(xy 322.519294 -337.469734) (xy 322.519294 -335.412334) (xy 323.46011 -335.412334) (xy 323.46011 -337.469734)
			)
		)
	)
	(zone
		(layer "Cmts.User")
		(hatch none 0.5)
		(connect_pads
			(clearance 0)
		)
		(min_thickness 0.25)
		(keepout
			(tracks allowed)
			(vias allowed)
			(pads allowed)
			(copperpour allowed)
			(footprints allowed)
		)
		(placement
			(enabled no)
			(sheetname "")
		)
		(fill
			(thermal_gap 0.5)
			(thermal_bridge_width 0.5)
			(island_removal_mode 0)
		)
		(polygon
			(pts
				(xy 304.430176 -421.245538) (xy 304.430176 -420.72687) (xy 351.565464 -420.72687) (xy 351.565464 -421.245538)
			)
		)
	)
	(zone
		(layer "Cmts.User")
		(hatch none 0.5)
		(connect_pads
			(clearance 0)
		)
		(min_thickness 0.25)
		(keepout
			(tracks allowed)
			(vias allowed)
			(pads allowed)
			(copperpour allowed)
			(footprints allowed)
		)
		(placement
			(enabled no)
			(sheetname "")
		)
		(fill
			(thermal_gap 0.5)
			(thermal_bridge_width 0.5)
			(island_removal_mode 0)
		)
		(polygon
			(pts
				(xy 28.23337 -350.242632) (xy 27.72537 -350.242632) (xy 27.42819 -350.539812) (xy 28.12161 -351.233232)
				(xy 28.67533 -351.233232) (xy 28.67533 -350.684592)
			)
		)
	)
	(zone
		(layer "Cmts.User")
		(hatch none 0.5)
		(connect_pads
			(clearance 0.5)
		)
		(min_thickness 0.25)
		(fill
			(thermal_gap 0.5)
			(thermal_bridge_width 0.5)
			(island_removal_mode 0)
		)
		(polygon
			(pts
				(xy 548.00246 -183.36768) (xy -9.35228 -183.36768) (xy -9.35228 -477.48444) (xy 548.00246 -477.48444)
			)
		)
	)
	(zone
		(layer "Cmts.User")
		(hatch none 0.5)
		(connect_pads
			(clearance 0)
		)
		(min_thickness 0.25)
		(keepout
			(tracks allowed)
			(vias allowed)
			(pads allowed)
			(copperpour allowed)
			(footprints allowed)
		)
		(placement
			(enabled no)
			(sheetname "")
		)
		(fill
			(thermal_gap 0.5)
			(thermal_bridge_width 0.5)
			(island_removal_mode 0)
		)
		(polygon
			(pts
				(xy 303.052226 -398.808702) (xy 303.052226 -396.509494) (xy 322.438268 -396.509494) (xy 322.438268 -398.808702)
			)
		)
	)
	(zone
		(layer "Cmts.User")
		(hatch none 0.5)
		(connect_pads
			(clearance 0)
		)
		(min_thickness 0.25)
		(keepout
			(tracks allowed)
			(vias allowed)
			(pads allowed)
			(copperpour allowed)
			(footprints allowed)
		)
		(placement
			(enabled no)
			(sheetname "")
		)
		(fill
			(thermal_gap 0.5)
			(thermal_bridge_width 0.5)
			(island_removal_mode 0)
		)
		(polygon
			(pts
				(xy 36.58743 -350.268032) (xy 36.08451 -350.268032) (xy 35.77717 -350.575372) (xy 36.35121 -351.149412)
				(xy 36.98113 -351.149412) (xy 36.98113 -350.661732)
			)
		)
	)
	(zone
		(layer "Cmts.User")
		(hatch none 0.5)
		(connect_pads
			(clearance 0)
		)
		(min_thickness 0.25)
		(keepout
			(tracks allowed)
			(vias allowed)
			(pads allowed)
			(copperpour allowed)
			(footprints allowed)
		)
		(placement
			(enabled no)
			(sheetname "")
		)
		(fill
			(thermal_gap 0.5)
			(thermal_bridge_width 0.5)
			(island_removal_mode 0)
		)
		(polygon
			(pts
				(xy 58.259726 -350.806766) (xy 58.259726 -350.176084) (xy 58.87212 -350.176084) (xy 58.87212 -350.806766)
			)
		)
	)
	(zone
		(layer "Cmts.User")
		(hatch none 0.5)
		(connect_pads
			(clearance 0)
		)
		(min_thickness 0.25)
		(keepout
			(tracks allowed)
			(vias allowed)
			(pads allowed)
			(copperpour allowed)
			(footprints allowed)
		)
		(placement
			(enabled no)
			(sheetname "")
		)
		(fill
			(thermal_gap 0.5)
			(thermal_bridge_width 0.5)
			(island_removal_mode 0)
		)
		(polygon
			(pts
				(xy 75.14971 -339.07857) (xy 75.14971 -338.447888) (xy 75.762104 -338.447888) (xy 75.762104 -339.07857)
			)
		)
	)
	(zone
		(layer "Cmts.User")
		(hatch none 0.5)
		(connect_pads
			(clearance 0)
		)
		(min_thickness 0.25)
		(keepout
			(tracks allowed)
			(vias allowed)
			(pads allowed)
			(copperpour allowed)
			(footprints allowed)
		)
		(placement
			(enabled no)
			(sheetname "")
		)
		(fill
			(thermal_gap 0.5)
			(thermal_bridge_width 0.5)
			(island_removal_mode 0)
		)
		(polygon
			(pts
				(xy 116.59362 -58.81624) (xy 116.59362 -58.03138) (xy 118.13794 -58.03138) (xy 118.13794 -58.81624)
			)
		)
	)
	(zone
		(layer "Cmts.User")
		(hatch none 0.5)
		(connect_pads
			(clearance 0)
		)
		(min_thickness 0.25)
		(keepout
			(tracks allowed)
			(vias allowed)
			(pads allowed)
			(copperpour allowed)
			(footprints allowed)
		)
		(placement
			(enabled no)
			(sheetname "")
		)
		(fill
			(thermal_gap 0.5)
			(thermal_bridge_width 0.5)
			(island_removal_mode 0)
		)
		(polygon
			(pts
				(xy 61.64707 -350.283272) (xy 61.16955 -350.283272) (xy 60.77839 -350.674432) (xy 61.23051 -351.126552)
				(xy 61.85027 -351.126552) (xy 61.85027 -350.486472)
			)
		)
	)
	(zone
		(layer "Cmts.User")
		(hatch none 0.5)
		(connect_pads
			(clearance 0)
		)
		(min_thickness 0.25)
		(keepout
			(tracks allowed)
			(vias allowed)
			(pads allowed)
			(copperpour allowed)
			(footprints allowed)
		)
		(placement
			(enabled no)
			(sheetname "")
		)
		(fill
			(thermal_gap 0.5)
			(thermal_bridge_width 0.5)
			(island_removal_mode 0)
		)
		(polygon
			(pts
				(xy 373.320818 -178.124612) (xy 372.635018 -178.124612) (xy 372.457218 -178.302412) (xy 372.457218 -178.988212)
				(xy 372.812818 -179.343812) (xy 373.498618 -179.343812) (xy 373.879618 -178.962812) (xy 373.879618 -178.683412)
			)
		)
	)
	(zone
		(layer "Cmts.User")
		(hatch none 0.5)
		(connect_pads
			(clearance 0)
		)
		(min_thickness 0.25)
		(keepout
			(tracks allowed)
			(vias allowed)
			(pads allowed)
			(copperpour allowed)
			(footprints allowed)
		)
		(placement
			(enabled no)
			(sheetname "")
		)
		(fill
			(thermal_gap 0.5)
			(thermal_bridge_width 0.5)
			(island_removal_mode 0)
		)
		(polygon
			(pts
				(xy 44.92625 -350.229932) (xy 44.43857 -350.229932) (xy 44.09567 -350.572832) (xy 44.71543 -351.192592)
				(xy 45.20311 -351.192592) (xy 45.20311 -350.506792)
			)
		)
	)
	(zone
		(layer "Cmts.User")
		(hatch none 0.5)
		(connect_pads
			(clearance 0)
		)
		(min_thickness 0.25)
		(keepout
			(tracks allowed)
			(vias allowed)
			(pads allowed)
			(copperpour allowed)
			(footprints allowed)
		)
		(placement
			(enabled no)
			(sheetname "")
		)
		(fill
			(thermal_gap 0.5)
			(thermal_bridge_width 0.5)
			(island_removal_mode 0)
		)
		(polygon
			(pts
				(xy 187.721494 -352.013012) (xy 187.492894 -352.013012) (xy 187.365894 -352.140012) (xy 187.365894 -353.029012)
				(xy 187.492894 -353.156012) (xy 187.670694 -353.156012) (xy 187.746894 -353.079812) (xy 187.746894 -352.038412)
			)
		)
	)
	(zone
		(layer "Cmts.User")
		(hatch none 0.5)
		(connect_pads
			(clearance 0)
		)
		(min_thickness 0.25)
		(keepout
			(tracks allowed)
			(vias allowed)
			(pads allowed)
			(copperpour allowed)
			(footprints allowed)
		)
		(placement
			(enabled no)
			(sheetname "")
		)
		(fill
			(thermal_gap 0.5)
			(thermal_bridge_width 0.5)
			(island_removal_mode 0)
		)
		(polygon
			(pts
				(xy 41.192704 -348.67977) (xy 41.192704 -348.049088) (xy 41.805098 -348.049088) (xy 41.805098 -348.67977)
			)
		)
	)
	(zone
		(layer "Cmts.User")
		(hatch none 0.5)
		(connect_pads
			(clearance 0)
		)
		(min_thickness 0.25)
		(keepout
			(tracks allowed)
			(vias allowed)
			(pads allowed)
			(copperpour allowed)
			(footprints allowed)
		)
		(placement
			(enabled no)
			(sheetname "")
		)
		(fill
			(thermal_gap 0.5)
			(thermal_bridge_width 0.5)
			(island_removal_mode 0)
		)
		(polygon
			(pts
				(xy 119.551958 -169.955718) (xy 119.196358 -169.955718) (xy 119.094758 -170.057318) (xy 119.094758 -171.124118)
				(xy 119.170958 -171.200318) (xy 119.577358 -171.200318) (xy 119.653558 -171.124118) (xy 119.653558 -170.057318)
			)
		)
	)
	(zone
		(layer "Cmts.User")
		(hatch none 0.5)
		(connect_pads
			(clearance 0)
		)
		(min_thickness 0.25)
		(keepout
			(tracks allowed)
			(vias allowed)
			(pads allowed)
			(copperpour allowed)
			(footprints allowed)
		)
		(placement
			(enabled no)
			(sheetname "")
		)
		(fill
			(thermal_gap 0.5)
			(thermal_bridge_width 0.5)
			(island_removal_mode 0)
		)
		(polygon
			(pts
				(xy 312.01233 -356.249478) (xy 311.33161 -356.249478) (xy 311.33161 -355.636322) (xy 312.01233 -355.636322)
			)
		)
	)
	(zone
		(layer "Cmts.User")
		(hatch none 0.5)
		(connect_pads
			(clearance 0)
		)
		(min_thickness 0.25)
		(keepout
			(tracks allowed)
			(vias allowed)
			(pads allowed)
			(copperpour allowed)
			(footprints allowed)
		)
		(placement
			(enabled no)
			(sheetname "")
		)
		(fill
			(thermal_gap 0.5)
			(thermal_bridge_width 0.5)
			(island_removal_mode 0)
		)
		(polygon
			(pts
				(xy 401.972272 -393.07008) (xy 401.972272 -391.083546) (xy 422.094152 -391.083546) (xy 422.094152 -393.07008)
				(xy 422.094152 -394.504672) (xy 402.864066 -394.504672) (xy 402.864066 -393.07008)
			)
		)
	)
	(zone
		(layer "Cmts.User")
		(hatch none 0.5)
		(connect_pads
			(clearance 0)
		)
		(min_thickness 0.25)
		(keepout
			(tracks allowed)
			(vias allowed)
			(pads allowed)
			(copperpour allowed)
			(footprints allowed)
		)
		(placement
			(enabled no)
			(sheetname "")
		)
		(fill
			(thermal_gap 0.5)
			(thermal_bridge_width 0.5)
			(island_removal_mode 0)
		)
		(polygon
			(pts
				(xy 90.522044 -337.348068) (xy 90.522044 -336.717386) (xy 91.134438 -336.717386) (xy 91.134438 -337.348068)
			)
		)
	)
	(zone
		(layer "Cmts.User")
		(hatch none 0.5)
		(connect_pads
			(clearance 0)
		)
		(min_thickness 0.25)
		(keepout
			(tracks allowed)
			(vias allowed)
			(pads allowed)
			(copperpour allowed)
			(footprints allowed)
		)
		(placement
			(enabled no)
			(sheetname "")
		)
		(fill
			(thermal_gap 0.5)
			(thermal_bridge_width 0.5)
			(island_removal_mode 0)
		)
		(polygon
			(pts
				(xy 325.580248 -339.615018) (xy 325.580248 -338.42325) (xy 326.960484 -338.42325) (xy 326.960484 -339.615018)
			)
		)
	)
	(zone
		(layer "Cmts.User")
		(hatch none 0.5)
		(connect_pads
			(clearance 0)
		)
		(min_thickness 0.25)
		(keepout
			(tracks allowed)
			(vias allowed)
			(pads allowed)
			(copperpour allowed)
			(footprints allowed)
		)
		(placement
			(enabled no)
			(sheetname "")
		)
		(fill
			(thermal_gap 0.5)
			(thermal_bridge_width 0.5)
			(island_removal_mode 0)
		)
		(polygon
			(pts
				(xy 368.037618 -175.737012) (xy 367.910618 -175.737012) (xy 367.682018 -175.965612) (xy 367.682018 -176.905412)
				(xy 367.834418 -177.057812) (xy 368.139218 -177.057812) (xy 368.317018 -176.880012) (xy 368.317018 -176.016412)
			)
		)
	)
	(zone
		(layer "Cmts.User")
		(hatch none 0.5)
		(connect_pads
			(clearance 0)
		)
		(min_thickness 0.25)
		(keepout
			(tracks allowed)
			(vias allowed)
			(pads allowed)
			(copperpour allowed)
			(footprints allowed)
		)
		(placement
			(enabled no)
			(sheetname "")
		)
		(fill
			(thermal_gap 0.5)
			(thermal_bridge_width 0.5)
			(island_removal_mode 0)
		)
		(polygon
			(pts
				(xy 111.322358 -176.229518) (xy 110.966758 -176.229518) (xy 110.865158 -176.331118) (xy 110.865158 -177.397918)
				(xy 110.941358 -177.474118) (xy 111.347758 -177.474118) (xy 111.423958 -177.397918) (xy 111.423958 -176.331118)
			)
		)
	)
	(zone
		(layer "Cmts.User")
		(hatch none 0.5)
		(connect_pads
			(clearance 0)
		)
		(min_thickness 0.25)
		(keepout
			(tracks allowed)
			(vias allowed)
			(pads allowed)
			(copperpour allowed)
			(footprints allowed)
		)
		(placement
			(enabled no)
			(sheetname "")
		)
		(fill
			(thermal_gap 0.5)
			(thermal_bridge_width 0.5)
			(island_removal_mode 0)
		)
		(polygon
			(pts
				(xy 49.549304 -348.67977) (xy 49.549304 -348.049088) (xy 50.161698 -348.049088) (xy 50.161698 -348.67977)
			)
		)
	)
	(zone
		(layer "Cmts.User")
		(hatch none 0.5)
		(connect_pads
			(clearance 0)
		)
		(min_thickness 0.25)
		(keepout
			(tracks allowed)
			(vias allowed)
			(pads allowed)
			(copperpour allowed)
			(footprints allowed)
		)
		(placement
			(enabled no)
			(sheetname "")
		)
		(fill
			(thermal_gap 0.5)
			(thermal_bridge_width 0.5)
			(island_removal_mode 0)
		)
		(polygon
			(pts
				(xy 380.521718 -441.239148) (xy 380.521718 -425.547282) (xy 380.521718 -424.043348) (xy 396.726918 -424.043348)
				(xy 396.726918 -441.239148) (xy 394.349478 -441.239148)
			)
		)
	)
	(zone
		(layer "Cmts.User")
		(hatch none 0.5)
		(connect_pads
			(clearance 0)
		)
		(min_thickness 0.25)
		(keepout
			(tracks allowed)
			(vias allowed)
			(pads allowed)
			(copperpour allowed)
			(footprints allowed)
		)
		(placement
			(enabled no)
			(sheetname "")
		)
		(fill
			(thermal_gap 0.5)
			(thermal_bridge_width 0.5)
			(island_removal_mode 0)
		)
		(polygon
			(pts
				(xy 79.580232 -390.426702) (xy 79.580232 -388.127494) (xy 98.966274 -388.127494) (xy 98.966274 -390.426702)
			)
		)
	)
	(zone
		(layer "Cmts.User")
		(hatch none 0.5)
		(connect_pads
			(clearance 0)
		)
		(min_thickness 0.25)
		(keepout
			(tracks allowed)
			(vias allowed)
			(pads allowed)
			(copperpour allowed)
			(footprints allowed)
		)
		(placement
			(enabled no)
			(sheetname "")
		)
		(fill
			(thermal_gap 0.5)
			(thermal_bridge_width 0.5)
			(island_removal_mode 0)
		)
		(polygon
			(pts
				(xy 115.915694 -167.291512) (xy 115.687094 -167.291512) (xy 115.534694 -167.443912) (xy 115.534694 -167.748712)
				(xy 115.687094 -167.901112) (xy 115.687094 -168.383712) (xy 115.788694 -168.485312) (xy 116.093494 -168.485312)
				(xy 116.322094 -168.256712) (xy 116.728494 -168.256712) (xy 116.906294 -168.078912) (xy 116.906294 -167.901112)
				(xy 116.703094 -167.697912) (xy 116.322094 -167.697912)
			)
		)
	)
	(zone
		(layer "Cmts.User")
		(hatch none 0.5)
		(connect_pads
			(clearance 0)
		)
		(min_thickness 0.25)
		(keepout
			(tracks allowed)
			(vias allowed)
			(pads allowed)
			(copperpour allowed)
			(footprints allowed)
		)
		(placement
			(enabled no)
			(sheetname "")
		)
		(fill
			(thermal_gap 0.5)
			(thermal_bridge_width 0.5)
			(island_removal_mode 0)
		)
		(polygon
			(pts
				(xy 390.710674 -315.461904) (xy 390.029954 -315.461904) (xy 390.029954 -314.848748) (xy 390.710674 -314.848748)
			)
		)
	)
	(zone
		(layer "Cmts.User")
		(hatch none 0.5)
		(connect_pads
			(clearance 0)
		)
		(min_thickness 0.25)
		(keepout
			(tracks allowed)
			(vias allowed)
			(pads allowed)
			(copperpour allowed)
			(footprints allowed)
		)
		(placement
			(enabled no)
			(sheetname "")
		)
		(fill
			(thermal_gap 0.5)
			(thermal_bridge_width 0.5)
			(island_removal_mode 0)
		)
		(polygon
			(pts
				(xy 248.89206 -41.235884) (xy 248.89206 -40.605202) (xy 249.504454 -40.605202) (xy 249.504454 -41.235884)
			)
		)
	)
	(zone
		(layer "Cmts.User")
		(hatch none 0.5)
		(connect_pads
			(clearance 0)
		)
		(min_thickness 0.25)
		(keepout
			(tracks allowed)
			(vias allowed)
			(pads allowed)
			(copperpour allowed)
			(footprints allowed)
		)
		(placement
			(enabled no)
			(sheetname "")
		)
		(fill
			(thermal_gap 0.5)
			(thermal_bridge_width 0.5)
			(island_removal_mode 0)
		)
		(polygon
			(pts
				(xy 371.642132 -418.18687) (xy 418.77742 -418.18687) (xy 418.77742 -418.705538) (xy 371.642132 -418.705538)
				(xy 371.495828 -418.705538) (xy 371.454172 -418.663882) (xy 371.454172 -418.20973) (xy 371.477032 -418.18687)
			)
		)
	)
	(zone
		(layer "Cmts.User")
		(hatch none 0.5)
		(connect_pads
			(clearance 0)
		)
		(min_thickness 0.25)
		(keepout
			(tracks allowed)
			(vias allowed)
			(pads allowed)
			(copperpour allowed)
			(footprints allowed)
		)
		(placement
			(enabled no)
			(sheetname "")
		)
		(fill
			(thermal_gap 0.5)
			(thermal_bridge_width 0.5)
			(island_removal_mode 0)
		)
		(polygon
			(pts
				(xy 375.7041 -179.256944) (xy 375.7041 -178.680364) (xy 376.268488 -178.680364) (xy 376.268488 -179.256944)
			)
		)
	)
	(zone
		(layer "Cmts.User")
		(hatch none 0.5)
		(connect_pads
			(clearance 0)
		)
		(min_thickness 0.25)
		(keepout
			(tracks allowed)
			(vias allowed)
			(pads allowed)
			(copperpour allowed)
			(footprints allowed)
		)
		(placement
			(enabled no)
			(sheetname "")
		)
		(fill
			(thermal_gap 0.5)
			(thermal_bridge_width 0.5)
			(island_removal_mode 0)
		)
		(polygon
			(pts
				(xy 415.129218 -159.023812) (xy 414.418018 -159.023812) (xy 414.214818 -159.227012) (xy 414.214818 -159.938212)
				(xy 414.697418 -160.420812) (xy 415.332418 -160.420812) (xy 415.738818 -160.014412) (xy 415.738818 -159.633412)
			)
		)
	)
	(zone
		(layer "Cmts.User")
		(hatch none 0.5)
		(connect_pads
			(clearance 0)
		)
		(min_thickness 0.25)
		(keepout
			(tracks allowed)
			(vias allowed)
			(pads allowed)
			(copperpour allowed)
			(footprints allowed)
		)
		(placement
			(enabled no)
			(sheetname "")
		)
		(fill
			(thermal_gap 0.5)
			(thermal_bridge_width 0.5)
			(island_removal_mode 0)
		)
		(polygon
			(pts
				(xy 287.826196 -349.19793) (xy 287.826196 -347.14053) (xy 288.767012 -347.14053) (xy 288.767012 -349.19793)
			)
		)
	)
	(zone
		(layer "Cmts.User")
		(hatch none 0.5)
		(connect_pads
			(clearance 0)
		)
		(min_thickness 0.25)
		(keepout
			(tracks allowed)
			(vias allowed)
			(pads allowed)
			(copperpour allowed)
			(footprints allowed)
		)
		(placement
			(enabled no)
			(sheetname "")
		)
		(fill
			(thermal_gap 0.5)
			(thermal_bridge_width 0.5)
			(island_removal_mode 0)
		)
		(polygon
			(pts
				(xy 330.421742 -441.239148) (xy 330.421742 -425.547282) (xy 330.421742 -424.043348) (xy 346.626942 -424.043348)
				(xy 346.626942 -441.239148) (xy 344.249502 -441.239148)
			)
		)
	)
	(zone
		(layer "Cmts.User")
		(hatch none 0.5)
		(connect_pads
			(clearance 0)
		)
		(min_thickness 0.25)
		(keepout
			(tracks allowed)
			(vias allowed)
			(pads allowed)
			(copperpour allowed)
			(footprints allowed)
		)
		(placement
			(enabled no)
			(sheetname "")
		)
		(fill
			(thermal_gap 0.5)
			(thermal_bridge_width 0.5)
			(island_removal_mode 0)
		)
		(polygon
			(pts
				(xy 342.269064 -339.65134) (xy 342.269064 -338.459572) (xy 343.6493 -338.459572) (xy 343.6493 -339.65134)
			)
		)
	)
	(zone
		(layer "Cmts.User")
		(hatch none 0.5)
		(connect_pads
			(clearance 0)
		)
		(min_thickness 0.25)
		(keepout
			(tracks allowed)
			(vias allowed)
			(pads allowed)
			(copperpour allowed)
			(footprints allowed)
		)
		(placement
			(enabled no)
			(sheetname "")
		)
		(fill
			(thermal_gap 0.5)
			(thermal_bridge_width 0.5)
			(island_removal_mode 0)
		)
		(polygon
			(pts
				(xy 131.75361 -24.400764) (xy 131.75361 -25.138888) (xy 130.371596 -25.138888) (xy 130.371596 -24.400764)
			)
		)
	)
	(zone
		(layer "Cmts.User")
		(hatch none 0.5)
		(connect_pads
			(clearance 0)
		)
		(min_thickness 0.25)
		(keepout
			(tracks allowed)
			(vias allowed)
			(pads allowed)
			(copperpour allowed)
			(footprints allowed)
		)
		(placement
			(enabled no)
			(sheetname "")
		)
		(fill
			(thermal_gap 0.5)
			(thermal_bridge_width 0.5)
			(island_removal_mode 0)
		)
		(polygon
			(pts
				(xy 200.000362 -378.4981) (xy 200.000362 -377.867418) (xy 200.612756 -377.867418) (xy 200.612756 -378.4981)
			)
		)
	)
	(zone
		(layer "Cmts.User")
		(hatch none 0.5)
		(connect_pads
			(clearance 0)
		)
		(min_thickness 0.25)
		(keepout
			(tracks allowed)
			(vias allowed)
			(pads allowed)
			(copperpour allowed)
			(footprints allowed)
		)
		(placement
			(enabled no)
			(sheetname "")
		)
		(fill
			(thermal_gap 0.5)
			(thermal_bridge_width 0.5)
			(island_removal_mode 0)
		)
		(polygon
			(pts
				(xy 384.928618 -180.664612) (xy 384.446018 -180.664612) (xy 384.319018 -180.791612) (xy 384.319018 -182.061612)
				(xy 384.446018 -182.188612) (xy 384.928618 -182.188612) (xy 385.131818 -181.985412) (xy 385.131818 -180.867812)
			)
		)
	)
	(zone
		(layer "Cmts.User")
		(hatch none 0.5)
		(connect_pads
			(clearance 0)
		)
		(min_thickness 0.25)
		(keepout
			(tracks allowed)
			(vias allowed)
			(pads allowed)
			(copperpour allowed)
			(footprints allowed)
		)
		(placement
			(enabled no)
			(sheetname "")
		)
		(fill
			(thermal_gap 0.5)
			(thermal_bridge_width 0.5)
			(island_removal_mode 0)
		)
		(polygon
			(pts
				(xy 347.311218 -156.763212) (xy 347.311218 -157.576012) (xy 347.565218 -157.830012) (xy 348.555818 -157.830012)
				(xy 349.063818 -157.322012) (xy 349.063818 -157.042612) (xy 348.428818 -156.407612) (xy 347.666818 -156.407612)
			)
		)
	)
	(zone
		(layer "Cmts.User")
		(hatch none 0.5)
		(connect_pads
			(clearance 0)
		)
		(min_thickness 0.25)
		(keepout
			(tracks allowed)
			(vias allowed)
			(pads allowed)
			(copperpour allowed)
			(footprints allowed)
		)
		(placement
			(enabled no)
			(sheetname "")
		)
		(fill
			(thermal_gap 0.5)
			(thermal_bridge_width 0.5)
			(island_removal_mode 0)
		)
		(polygon
			(pts
				(xy 173.8122 -367.938558) (xy 173.8122 -367.307876) (xy 174.424594 -367.307876) (xy 174.424594 -367.938558)
			)
		)
	)
	(zone
		(layer "Cmts.User")
		(hatch none 0.5)
		(connect_pads
			(clearance 0)
		)
		(min_thickness 0.25)
		(keepout
			(tracks allowed)
			(vias allowed)
			(pads allowed)
			(copperpour allowed)
			(footprints allowed)
		)
		(placement
			(enabled no)
			(sheetname "")
		)
		(fill
			(thermal_gap 0.5)
			(thermal_bridge_width 0.5)
			(island_removal_mode 0)
		)
		(polygon
			(pts
				(xy 369.444524 -393.07008) (xy 369.444524 -391.083546) (xy 389.566404 -391.083546) (xy 389.566404 -393.07008)
				(xy 389.566404 -394.504672) (xy 370.336318 -394.504672) (xy 370.336318 -393.07008)
			)
		)
	)
	(zone
		(layer "Cmts.User")
		(hatch none 0.5)
		(connect_pads
			(clearance 0)
		)
		(min_thickness 0.25)
		(keepout
			(tracks allowed)
			(vias allowed)
			(pads allowed)
			(copperpour allowed)
			(footprints allowed)
		)
		(placement
			(enabled no)
			(sheetname "")
		)
		(fill
			(thermal_gap 0.5)
			(thermal_bridge_width 0.5)
			(island_removal_mode 0)
		)
		(polygon
			(pts
				(xy 140.57884 -18.35404) (xy 140.57884 -17.58696) (xy 142.047722 -17.58696) (xy 142.047722 -18.35404)
			)
		)
	)
	(zone
		(layer "Cmts.User")
		(hatch none 0.5)
		(connect_pads
			(clearance 0)
		)
		(min_thickness 0.25)
		(keepout
			(tracks allowed)
			(vias allowed)
			(pads allowed)
			(copperpour allowed)
			(footprints allowed)
		)
		(placement
			(enabled no)
			(sheetname "")
		)
		(fill
			(thermal_gap 0.5)
			(thermal_bridge_width 0.5)
			(island_removal_mode 0)
		)
		(polygon
			(pts
				(xy 74.422 -441.239148) (xy 74.422 -425.547282) (xy 74.422 -424.043348) (xy 90.6272 -424.043348)
				(xy 90.6272 -441.239148) (xy 88.24976 -441.239148)
			)
		)
	)
	(zone
		(layer "Cmts.User")
		(hatch none 0.5)
		(connect_pads
			(clearance 0)
		)
		(min_thickness 0.25)
		(keepout
			(tracks allowed)
			(vias allowed)
			(pads allowed)
			(copperpour allowed)
			(footprints allowed)
		)
		(placement
			(enabled no)
			(sheetname "")
		)
		(fill
			(thermal_gap 0.5)
			(thermal_bridge_width 0.5)
			(island_removal_mode 0)
		)
		(polygon
			(pts
				(xy 48.586644 -349.090742) (xy 48.586644 -348.46006) (xy 49.199038 -348.46006) (xy 49.199038 -349.090742)
			)
		)
	)
	(zone
		(layer "Cmts.User")
		(hatch none 0.5)
		(connect_pads
			(clearance 0)
		)
		(min_thickness 0.25)
		(keepout
			(tracks allowed)
			(vias allowed)
			(pads allowed)
			(copperpour allowed)
			(footprints allowed)
		)
		(placement
			(enabled no)
			(sheetname "")
		)
		(fill
			(thermal_gap 0.5)
			(thermal_bridge_width 0.5)
			(island_removal_mode 0)
		)
		(polygon
			(pts
				(xy 403.06625 -399.507456) (xy 421.716708 -399.507456) (xy 421.716708 -402.229574) (xy 421.716708 -402.52396)
				(xy 402.579078 -402.52396) (xy 402.579078 -399.507456)
			)
		)
	)
	(zone
		(layer "Cmts.User")
		(hatch none 0.5)
		(connect_pads
			(clearance 0)
		)
		(min_thickness 0.25)
		(keepout
			(tracks allowed)
			(vias allowed)
			(pads allowed)
			(copperpour allowed)
			(footprints allowed)
		)
		(placement
			(enabled no)
			(sheetname "")
		)
		(fill
			(thermal_gap 0.5)
			(thermal_bridge_width 0.5)
			(island_removal_mode 0)
		)
		(polygon
			(pts
				(xy 58.1406 -441.239148) (xy 58.1406 -416.982148) (xy 73.2536 -416.982148) (xy 73.2536 -441.239148)
			)
		)
	)
	(zone
		(layer "Cmts.User")
		(hatch none 0.5)
		(connect_pads
			(clearance 0)
		)
		(min_thickness 0.25)
		(keepout
			(tracks allowed)
			(vias allowed)
			(pads allowed)
			(copperpour allowed)
			(footprints allowed)
		)
		(placement
			(enabled no)
			(sheetname "")
		)
		(fill
			(thermal_gap 0.5)
			(thermal_bridge_width 0.5)
			(island_removal_mode 0)
		)
		(polygon
			(pts
				(xy 441.066174 -18.280126) (xy 442.569346 -18.280126) (xy 442.569346 -21.315172) (xy 441.066174 -21.315172)
			)
		)
	)
	(zone
		(layer "Cmts.User")
		(hatch none 0.5)
		(connect_pads
			(clearance 0)
		)
		(min_thickness 0.25)
		(keepout
			(tracks allowed)
			(vias allowed)
			(pads allowed)
			(copperpour allowed)
			(footprints allowed)
		)
		(placement
			(enabled no)
			(sheetname "")
		)
		(fill
			(thermal_gap 0.5)
			(thermal_bridge_width 0.5)
			(island_removal_mode 0)
		)
		(polygon
			(pts
				(xy 376.495818 -180.639212) (xy 376.089418 -180.639212) (xy 375.911618 -180.817012) (xy 375.911618 -181.960012)
				(xy 376.089418 -182.137812) (xy 376.597418 -182.137812) (xy 376.800618 -181.934612) (xy 376.800618 -180.944012)
			)
		)
	)
	(zone
		(layer "Cmts.User")
		(hatch none 0.5)
		(connect_pads
			(clearance 0)
		)
		(min_thickness 0.25)
		(keepout
			(tracks allowed)
			(vias allowed)
			(pads allowed)
			(copperpour allowed)
			(footprints allowed)
		)
		(placement
			(enabled no)
			(sheetname "")
		)
		(fill
			(thermal_gap 0.5)
			(thermal_bridge_width 0.5)
			(island_removal_mode 0)
		)
		(polygon
			(pts
				(xy 169.316654 -350.996758) (xy 168.635934 -350.996758) (xy 168.635934 -350.383602) (xy 169.316654 -350.383602)
			)
		)
	)
	(zone
		(layer "Cmts.User")
		(hatch none 0.5)
		(connect_pads
			(clearance 0)
		)
		(min_thickness 0.25)
		(keepout
			(tracks allowed)
			(vias allowed)
			(pads allowed)
			(copperpour allowed)
			(footprints allowed)
		)
		(placement
			(enabled no)
			(sheetname "")
		)
		(fill
			(thermal_gap 0.5)
			(thermal_bridge_width 0.5)
			(island_removal_mode 0)
		)
		(polygon
			(pts
				(xy 146.680174 -390.426702) (xy 146.680174 -388.127494) (xy 166.066216 -388.127494) (xy 166.066216 -390.426702)
			)
		)
	)
	(zone
		(layer "Cmts.User")
		(hatch none 0.5)
		(connect_pads
			(clearance 0)
		)
		(min_thickness 0.25)
		(keepout
			(tracks allowed)
			(vias allowed)
			(pads allowed)
			(copperpour allowed)
			(footprints allowed)
		)
		(placement
			(enabled no)
			(sheetname "")
		)
		(fill
			(thermal_gap 0.5)
			(thermal_bridge_width 0.5)
			(island_removal_mode 0)
		)
		(polygon
			(pts
				(xy 86.150958 -180.776118) (xy 85.795358 -180.776118) (xy 85.693758 -180.877718) (xy 85.693758 -181.944518)
				(xy 85.769958 -182.020718) (xy 86.176358 -182.020718) (xy 86.252558 -181.944518) (xy 86.252558 -180.877718)
			)
		)
	)
	(zone
		(layer "Cmts.User")
		(hatch none 0.5)
		(connect_pads
			(clearance 0)
		)
		(min_thickness 0.25)
		(keepout
			(tracks allowed)
			(vias allowed)
			(pads allowed)
			(copperpour allowed)
			(footprints allowed)
		)
		(placement
			(enabled no)
			(sheetname "")
		)
		(fill
			(thermal_gap 0.5)
			(thermal_bridge_width 0.5)
			(island_removal_mode 0)
		)
		(polygon
			(pts
				(xy 304.430176 -412.621222) (xy 349.80245 -412.621222) (xy 349.80245 -413.13989) (xy 304.430176 -413.13989)
				(xy 304.283872 -413.13989) (xy 304.242216 -413.098234) (xy 304.242216 -412.644082) (xy 304.265076 -412.621222)
			)
		)
	)
	(zone
		(layer "Cmts.User")
		(hatch none 0.5)
		(connect_pads
			(clearance 0)
		)
		(min_thickness 0.25)
		(keepout
			(tracks allowed)
			(vias allowed)
			(pads allowed)
			(copperpour allowed)
			(footprints allowed)
		)
		(placement
			(enabled no)
			(sheetname "")
		)
		(fill
			(thermal_gap 0.5)
			(thermal_bridge_width 0.5)
			(island_removal_mode 0)
		)
		(polygon
			(pts
				(xy 377.130818 -137.256012) (xy 376.546618 -137.256012) (xy 375.987818 -137.814812) (xy 375.987818 -138.551412)
				(xy 376.140218 -138.703812) (xy 376.318018 -138.703812) (xy 377.308618 -137.713212) (xy 377.308618 -137.433812)
			)
		)
	)
	(zone
		(layer "Cmts.User")
		(hatch none 0.5)
		(connect_pads
			(clearance 0)
		)
		(min_thickness 0.25)
		(keepout
			(tracks allowed)
			(vias allowed)
			(pads allowed)
			(copperpour allowed)
			(footprints allowed)
		)
		(placement
			(enabled no)
			(sheetname "")
		)
		(fill
			(thermal_gap 0.5)
			(thermal_bridge_width 0.5)
			(island_removal_mode 0)
		)
		(polygon
			(pts
				(xy 78.872334 -384.68808) (xy 78.872334 -382.701546) (xy 98.994214 -382.701546) (xy 98.994214 -384.68808)
				(xy 98.994214 -386.122672) (xy 79.764128 -386.122672) (xy 79.764128 -384.68808)
			)
		)
	)
	(zone
		(layer "Cmts.User")
		(hatch none 0.5)
		(connect_pads
			(clearance 0)
		)
		(min_thickness 0.25)
		(keepout
			(tracks allowed)
			(vias allowed)
			(pads allowed)
			(copperpour allowed)
			(footprints allowed)
		)
		(placement
			(enabled no)
			(sheetname "")
		)
		(fill
			(thermal_gap 0.5)
			(thermal_bridge_width 0.5)
			(island_removal_mode 0)
		)
		(polygon
			(pts
				(xy 82.164428 -337.362546) (xy 82.164428 -336.731864) (xy 82.776822 -336.731864) (xy 82.776822 -337.362546)
			)
		)
	)
	(zone
		(layer "Cmts.User")
		(hatch none 0.5)
		(connect_pads
			(clearance 0)
		)
		(min_thickness 0.25)
		(keepout
			(tracks allowed)
			(vias allowed)
			(pads allowed)
			(copperpour allowed)
			(footprints allowed)
		)
		(placement
			(enabled no)
			(sheetname "")
		)
		(fill
			(thermal_gap 0.5)
			(thermal_bridge_width 0.5)
			(island_removal_mode 0)
		)
		(polygon
			(pts
				(xy 423.485818 -354.578412) (xy 422.977818 -354.578412) (xy 422.596818 -354.959412) (xy 423.333418 -355.696012)
				(xy 423.536618 -355.696012) (xy 423.790618 -355.442012) (xy 423.790618 -354.883212)
			)
		)
	)
	(zone
		(layer "Cmts.User")
		(hatch none 0.5)
		(connect_pads
			(clearance 0)
		)
		(min_thickness 0.25)
		(keepout
			(tracks allowed)
			(vias allowed)
			(pads allowed)
			(copperpour allowed)
			(footprints allowed)
		)
		(placement
			(enabled no)
			(sheetname "")
		)
		(fill
			(thermal_gap 0.5)
			(thermal_bridge_width 0.5)
			(island_removal_mode 0)
		)
		(polygon
			(pts
				(xy 335.966054 -399.507456) (xy 354.616512 -399.507456) (xy 354.616512 -402.229574) (xy 354.616512 -402.52396)
				(xy 335.478882 -402.52396) (xy 335.478882 -399.507456)
			)
		)
	)
	(zone
		(layer "Cmts.User")
		(hatch none 0.5)
		(connect_pads
			(clearance 0)
		)
		(min_thickness 0.25)
		(keepout
			(tracks allowed)
			(vias allowed)
			(pads allowed)
			(copperpour allowed)
			(footprints allowed)
		)
		(placement
			(enabled no)
			(sheetname "")
		)
		(fill
			(thermal_gap 0.5)
			(thermal_bridge_width 0.5)
			(island_removal_mode 0)
		)
		(polygon
			(pts
				(xy 384.08737 -179.23891) (xy 384.08737 -178.680364) (xy 384.658108 -178.680364) (xy 384.658108 -179.23891)
			)
		)
	)
	(zone
		(layer "Cmts.User")
		(hatch none 0.5)
		(connect_pads
			(clearance 0)
		)
		(min_thickness 0.25)
		(keepout
			(tracks allowed)
			(vias allowed)
			(pads allowed)
			(copperpour allowed)
			(footprints allowed)
		)
		(placement
			(enabled no)
			(sheetname "")
		)
		(fill
			(thermal_gap 0.5)
			(thermal_bridge_width 0.5)
			(island_removal_mode 0)
		)
		(polygon
			(pts
				(xy 304.541936 -418.18687) (xy 351.677224 -418.18687) (xy 351.677224 -418.705538) (xy 304.541936 -418.705538)
				(xy 304.395632 -418.705538) (xy 304.353976 -418.663882) (xy 304.353976 -418.20973) (xy 304.376836 -418.18687)
			)
		)
	)
	(zone
		(layer "Cmts.User")
		(hatch none 0.5)
		(connect_pads
			(clearance 0)
		)
		(min_thickness 0.25)
		(keepout
			(tracks allowed)
			(vias allowed)
			(pads allowed)
			(copperpour allowed)
			(footprints allowed)
		)
		(placement
			(enabled no)
			(sheetname "")
		)
		(fill
			(thermal_gap 0.5)
			(thermal_bridge_width 0.5)
			(island_removal_mode 0)
		)
		(polygon
			(pts
				(xy 113.444528 -384.68808) (xy 113.444528 -382.701546) (xy 133.566408 -382.701546) (xy 133.566408 -384.68808)
				(xy 133.566408 -386.122672) (xy 114.336322 -386.122672) (xy 114.336322 -384.68808)
			)
		)
	)
	(zone
		(layer "Cmts.User")
		(hatch none 0.5)
		(connect_pads
			(clearance 0)
		)
		(min_thickness 0.25)
		(keepout
			(tracks allowed)
			(vias allowed)
			(pads allowed)
			(copperpour allowed)
			(footprints allowed)
		)
		(placement
			(enabled no)
			(sheetname "")
		)
		(fill
			(thermal_gap 0.5)
			(thermal_bridge_width 0.5)
			(island_removal_mode 0)
		)
		(polygon
			(pts
				(xy 147.066254 -391.125456) (xy 165.716712 -391.125456) (xy 165.716712 -393.847574) (xy 165.716712 -394.14196)
				(xy 146.579082 -394.14196) (xy 146.579082 -391.125456)
			)
		)
	)
	(zone
		(layer "Cmts.User")
		(hatch none 0.5)
		(connect_pads
			(clearance 0)
		)
		(min_thickness 0.25)
		(keepout
			(tracks allowed)
			(vias allowed)
			(pads allowed)
			(copperpour allowed)
			(footprints allowed)
		)
		(placement
			(enabled no)
			(sheetname "")
		)
		(fill
			(thermal_gap 0.5)
			(thermal_bridge_width 0.5)
			(island_removal_mode 0)
		)
		(polygon
			(pts
				(xy 48.542194 -406.779222) (xy 95.677482 -406.779222) (xy 95.677482 -407.29789) (xy 48.542194 -407.29789)
				(xy 48.39589 -407.29789) (xy 48.354234 -407.256234) (xy 48.354234 -406.802082) (xy 48.377094 -406.779222)
			)
		)
	)
	(zone
		(layer "Cmts.User")
		(hatch none 0.5)
		(connect_pads
			(clearance 0)
		)
		(min_thickness 0.25)
		(keepout
			(tracks allowed)
			(vias allowed)
			(pads allowed)
			(copperpour allowed)
			(footprints allowed)
		)
		(placement
			(enabled no)
			(sheetname "")
		)
		(fill
			(thermal_gap 0.5)
			(thermal_bridge_width 0.5)
			(island_removal_mode 0)
		)
		(polygon
			(pts
				(xy 136.286494 -154.566112) (xy 135.930894 -154.566112) (xy 135.829294 -154.667712) (xy 135.829294 -155.734512)
				(xy 135.905494 -155.810712) (xy 136.311894 -155.810712) (xy 136.388094 -155.734512) (xy 136.388094 -154.667712)
			)
		)
	)
	(zone
		(layer "Cmts.User")
		(hatch none 0.5)
		(connect_pads
			(clearance 0)
		)
		(min_thickness 0.25)
		(keepout
			(tracks allowed)
			(vias allowed)
			(pads allowed)
			(copperpour allowed)
			(footprints allowed)
		)
		(placement
			(enabled no)
			(sheetname "")
		)
		(fill
			(thermal_gap 0.5)
			(thermal_bridge_width 0.5)
			(island_removal_mode 0)
		)
		(polygon
			(pts
				(xy 117.744494 -167.316912) (xy 117.541294 -167.316912) (xy 117.465094 -167.393112) (xy 117.465094 -168.129712)
				(xy 117.592094 -168.256712) (xy 117.719094 -168.256712) (xy 117.820694 -168.155112) (xy 117.820694 -167.393112)
			)
		)
	)
	(zone
		(layer "Cmts.User")
		(hatch none 0.5)
		(connect_pads
			(clearance 0)
		)
		(min_thickness 0.25)
		(keepout
			(tracks allowed)
			(vias allowed)
			(pads allowed)
			(copperpour allowed)
			(footprints allowed)
		)
		(placement
			(enabled no)
			(sheetname "")
		)
		(fill
			(thermal_gap 0.5)
			(thermal_bridge_width 0.5)
			(island_removal_mode 0)
		)
		(polygon
			(pts
				(xy 175.708056 -124.695966) (xy 175.708056 -105.407968) (xy 195.2498 -105.407968) (xy 195.2498 -124.695966)
			)
		)
	)
	(zone
		(layer "Cmts.User")
		(hatch none 0.5)
		(connect_pads
			(clearance 0)
		)
		(min_thickness 0.25)
		(keepout
			(tracks allowed)
			(vias allowed)
			(pads allowed)
			(copperpour allowed)
			(footprints allowed)
		)
		(placement
			(enabled no)
			(sheetname "")
		)
		(fill
			(thermal_gap 0.5)
			(thermal_bridge_width 0.5)
			(island_removal_mode 0)
		)
		(polygon
			(pts
				(xy 371.530372 -421.245538) (xy 371.530372 -420.72687) (xy 418.66566 -420.72687) (xy 418.66566 -421.245538)
			)
		)
	)
	(zone
		(layer "Cmts.User")
		(hatch none 0.5)
		(connect_pads
			(clearance 0)
		)
		(min_thickness 0.25)
		(keepout
			(tracks allowed)
			(vias allowed)
			(pads allowed)
			(copperpour allowed)
			(footprints allowed)
		)
		(placement
			(enabled no)
			(sheetname "")
		)
		(fill
			(thermal_gap 0.5)
			(thermal_bridge_width 0.5)
			(island_removal_mode 0)
		)
		(polygon
			(pts
				(xy 124.521722 -441.239148) (xy 124.521722 -425.547282) (xy 124.521722 -424.043348) (xy 140.726922 -424.043348)
				(xy 140.726922 -441.239148) (xy 138.349482 -441.239148)
			)
		)
	)
	(zone
		(layer "Cmts.User")
		(hatch none 0.5)
		(connect_pads
			(clearance 0)
		)
		(min_thickness 0.25)
		(keepout
			(tracks allowed)
			(vias allowed)
			(pads allowed)
			(copperpour allowed)
			(footprints allowed)
		)
		(placement
			(enabled no)
			(sheetname "")
		)
		(fill
			(thermal_gap 0.5)
			(thermal_bridge_width 0.5)
			(island_removal_mode 0)
		)
		(polygon
			(pts
				(xy 24.606504 -348.67977) (xy 24.606504 -348.049088) (xy 25.218898 -348.049088) (xy 25.218898 -348.67977)
			)
		)
	)
	(zone
		(layer "Cmts.User")
		(hatch none 0.5)
		(connect_pads
			(clearance 0)
		)
		(min_thickness 0.25)
		(keepout
			(tracks allowed)
			(vias allowed)
			(pads allowed)
			(copperpour allowed)
			(footprints allowed)
		)
		(placement
			(enabled no)
			(sheetname "")
		)
		(fill
			(thermal_gap 0.5)
			(thermal_bridge_width 0.5)
			(island_removal_mode 0)
		)
		(polygon
			(pts
				(xy 94.548198 -180.708046) (xy 94.192598 -180.708046) (xy 94.090998 -180.809646) (xy 94.090998 -181.876446)
				(xy 94.167198 -181.952646) (xy 94.573598 -181.952646) (xy 94.649798 -181.876446) (xy 94.649798 -180.809646)
			)
		)
	)
	(zone
		(layer "Cmts.User")
		(hatch none 0.5)
		(connect_pads
			(clearance 0)
		)
		(min_thickness 0.25)
		(keepout
			(tracks allowed)
			(vias allowed)
			(pads allowed)
			(copperpour allowed)
			(footprints allowed)
		)
		(placement
			(enabled no)
			(sheetname "")
		)
		(fill
			(thermal_gap 0.5)
			(thermal_bridge_width 0.5)
			(island_removal_mode 0)
		)
		(polygon
			(pts
				(xy 366.412018 -173.019212) (xy 366.158018 -173.019212) (xy 365.980218 -173.197012) (xy 365.980218 -174.060612)
				(xy 366.132618 -174.213012) (xy 366.386618 -174.213012) (xy 366.539018 -174.060612) (xy 366.539018 -173.146212)
			)
		)
	)
	(zone
		(layer "Cmts.User")
		(hatch none 0.5)
		(connect_pads
			(clearance 0)
		)
		(min_thickness 0.25)
		(keepout
			(tracks allowed)
			(vias allowed)
			(pads allowed)
			(copperpour allowed)
			(footprints allowed)
		)
		(placement
			(enabled no)
			(sheetname "")
		)
		(fill
			(thermal_gap 0.5)
			(thermal_bridge_width 0.5)
			(island_removal_mode 0)
		)
		(polygon
			(pts
				(xy 134.483094 -151.873712) (xy 134.356094 -151.873712) (xy 134.229094 -152.000712) (xy 134.229094 -152.788112)
				(xy 134.305294 -152.864312) (xy 134.457694 -152.864312) (xy 134.533894 -152.788112) (xy 134.533894 -151.924512)
			)
		)
	)
	(zone
		(layer "Cmts.User")
		(hatch none 0.5)
		(connect_pads
			(clearance 0)
		)
		(min_thickness 0.25)
		(keepout
			(tracks allowed)
			(vias allowed)
			(pads allowed)
			(copperpour allowed)
			(footprints allowed)
		)
		(placement
			(enabled no)
			(sheetname "")
		)
		(fill
			(thermal_gap 0.5)
			(thermal_bridge_width 0.5)
			(island_removal_mode 0)
		)
		(polygon
			(pts
				(xy 314.216796 -360.72191) (xy 313.536076 -360.72191) (xy 313.536076 -360.108754) (xy 314.216796 -360.108754)
			)
		)
	)
	(zone
		(layer "Cmts.User")
		(hatch none 0.5)
		(connect_pads
			(clearance 0)
		)
		(min_thickness 0.25)
		(keepout
			(tracks allowed)
			(vias allowed)
			(pads allowed)
			(copperpour allowed)
			(footprints allowed)
		)
		(placement
			(enabled no)
			(sheetname "")
		)
		(fill
			(thermal_gap 0.5)
			(thermal_bridge_width 0.5)
			(island_removal_mode 0)
		)
		(polygon
			(pts
				(xy 290.88715 -351.343214) (xy 290.88715 -350.151446) (xy 292.267386 -350.151446) (xy 292.267386 -351.343214)
			)
		)
	)
	(zone
		(layer "Cmts.User")
		(hatch none 0.5)
		(connect_pads
			(clearance 0)
		)
		(min_thickness 0.25)
		(keepout
			(tracks allowed)
			(vias allowed)
			(pads allowed)
			(copperpour allowed)
			(footprints allowed)
		)
		(placement
			(enabled no)
			(sheetname "")
		)
		(fill
			(thermal_gap 0.5)
			(thermal_bridge_width 0.5)
			(island_removal_mode 0)
		)
		(polygon
			(pts
				(xy 85.307424 -179.244752) (xy 85.307424 -178.710336) (xy 85.86597 -178.710336) (xy 85.86597 -179.244752)
			)
		)
	)
	(zone
		(layer "Cmts.User")
		(hatch none 0.5)
		(connect_pads
			(clearance 0)
		)
		(min_thickness 0.25)
		(keepout
			(tracks allowed)
			(vias allowed)
			(pads allowed)
			(copperpour allowed)
			(footprints allowed)
		)
		(placement
			(enabled no)
			(sheetname "")
		)
		(fill
			(thermal_gap 0.5)
			(thermal_bridge_width 0.5)
			(island_removal_mode 0)
		)
		(polygon
			(pts
				(xy 46.99762 -363.38764) (xy 46.99762 -362.756958) (xy 47.610014 -362.756958) (xy 47.610014 -363.38764)
			)
		)
	)
	(zone
		(layer "Cmts.User")
		(hatch none 0.5)
		(connect_pads
			(clearance 0)
		)
		(min_thickness 0.25)
		(keepout
			(tracks allowed)
			(vias allowed)
			(pads allowed)
			(copperpour allowed)
			(footprints allowed)
		)
		(placement
			(enabled no)
			(sheetname "")
		)
		(fill
			(thermal_gap 0.5)
			(thermal_bridge_width 0.5)
			(island_removal_mode 0)
		)
		(polygon
			(pts
				(xy 350.544892 -344.561414) (xy 350.544892 -343.369646) (xy 351.925128 -343.369646) (xy 351.925128 -344.561414)
			)
		)
	)
	(zone
		(layer "Cmts.User")
		(hatch none 0.5)
		(connect_pads
			(clearance 0)
		)
		(min_thickness 0.25)
		(keepout
			(tracks allowed)
			(vias allowed)
			(pads allowed)
			(copperpour allowed)
			(footprints allowed)
		)
		(placement
			(enabled no)
			(sheetname "")
		)
		(fill
			(thermal_gap 0.5)
			(thermal_bridge_width 0.5)
			(island_removal_mode 0)
		)
		(polygon
			(pts
				(xy 48.430434 -404.239222) (xy 93.802708 -404.239222) (xy 93.802708 -404.75789) (xy 48.430434 -404.75789)
				(xy 48.28413 -404.75789) (xy 48.242474 -404.716234) (xy 48.242474 -404.262082) (xy 48.265334 -404.239222)
			)
		)
	)
	(zone
		(layer "Cmts.User")
		(hatch none 0.5)
		(connect_pads
			(clearance 0)
		)
		(min_thickness 0.25)
		(keepout
			(tracks allowed)
			(vias allowed)
			(pads allowed)
			(copperpour allowed)
			(footprints allowed)
		)
		(placement
			(enabled no)
			(sheetname "")
		)
		(fill
			(thermal_gap 0.5)
			(thermal_bridge_width 0.5)
			(island_removal_mode 0)
		)
		(polygon
			(pts
				(xy 79.966312 -391.125456) (xy 98.61677 -391.125456) (xy 98.61677 -393.847574) (xy 98.61677 -394.14196)
				(xy 79.47914 -394.14196) (xy 79.47914 -391.125456)
			)
		)
	)
	(zone
		(layer "Cmts.User")
		(hatch none 0.5)
		(connect_pads
			(clearance 0)
		)
		(min_thickness 0.25)
		(keepout
			(tracks allowed)
			(vias allowed)
			(pads allowed)
			(copperpour allowed)
			(footprints allowed)
		)
		(placement
			(enabled no)
			(sheetname "")
		)
		(fill
			(thermal_gap 0.5)
			(thermal_bridge_width 0.5)
			(island_removal_mode 0)
		)
		(polygon
			(pts
				(xy 418.304218 -161.767012) (xy 418.024818 -161.767012) (xy 417.897818 -161.894012) (xy 417.897818 -162.986212)
				(xy 417.999418 -163.087812) (xy 418.482018 -163.087812) (xy 418.558218 -163.011612) (xy 418.558218 -162.021012)
			)
		)
	)
	(zone
		(layer "Cmts.User")
		(hatch none 0.5)
		(connect_pads
			(clearance 0)
		)
		(min_thickness 0.25)
		(keepout
			(tracks allowed)
			(vias allowed)
			(pads allowed)
			(copperpour allowed)
			(footprints allowed)
		)
		(placement
			(enabled no)
			(sheetname "")
		)
		(fill
			(thermal_gap 0.5)
			(thermal_bridge_width 0.5)
			(island_removal_mode 0)
		)
		(polygon
			(pts
				(xy 53.30063 -350.235012) (xy 52.90439 -350.235012) (xy 52.55387 -350.585532) (xy 53.04917 -351.080832)
				(xy 53.49875 -351.080832) (xy 53.49875 -350.433132)
			)
		)
	)
	(zone
		(layer "Cmts.User")
		(hatch none 0.5)
		(connect_pads
			(clearance 0)
		)
		(min_thickness 0.25)
		(keepout
			(tracks allowed)
			(vias allowed)
			(pads allowed)
			(copperpour allowed)
			(footprints allowed)
		)
		(placement
			(enabled no)
			(sheetname "")
		)
		(fill
			(thermal_gap 0.5)
			(thermal_bridge_width 0.5)
			(island_removal_mode 0)
		)
		(polygon
			(pts
				(xy 125.974094 -160.585912) (xy 125.821694 -160.585912) (xy 125.745494 -160.662112) (xy 125.745494 -161.449512)
				(xy 125.847094 -161.551112) (xy 125.974094 -161.551112) (xy 126.075694 -161.449512) (xy 126.075694 -160.687512)
			)
		)
	)
	(zone
		(layer "Cmts.User")
		(hatch none 0.5)
		(connect_pads
			(clearance 0)
		)
		(min_thickness 0.25)
		(keepout
			(tracks allowed)
			(vias allowed)
			(pads allowed)
			(copperpour allowed)
			(footprints allowed)
		)
		(placement
			(enabled no)
			(sheetname "")
		)
		(fill
			(thermal_gap 0.5)
			(thermal_bridge_width 0.5)
			(island_removal_mode 0)
		)
		(polygon
			(pts
				(xy 133.99516 -25.90038) (xy 133.257036 -25.90038) (xy 133.257036 -24.518366) (xy 133.99516 -24.518366)
			)
		)
	)
	(zone
		(layer "Cmts.User")
		(hatch none 0.5)
		(connect_pads
			(clearance 0)
		)
		(min_thickness 0.25)
		(keepout
			(tracks allowed)
			(vias allowed)
			(pads allowed)
			(copperpour allowed)
			(footprints allowed)
		)
		(placement
			(enabled no)
			(sheetname "")
		)
		(fill
			(thermal_gap 0.5)
			(thermal_bridge_width 0.5)
			(island_removal_mode 0)
		)
		(polygon
			(pts
				(xy 397.521938 -441.239148) (xy 397.521938 -425.547282) (xy 397.521938 -424.043348) (xy 413.727138 -424.043348)
				(xy 413.727138 -441.239148) (xy 411.349698 -441.239148)
			)
		)
	)
	(zone
		(layer "Cmts.User")
		(hatch none 0.5)
		(connect_pads
			(clearance 0)
		)
		(min_thickness 0.25)
		(keepout
			(tracks allowed)
			(vias allowed)
			(pads allowed)
			(copperpour allowed)
			(footprints allowed)
		)
		(placement
			(enabled no)
			(sheetname "")
		)
		(fill
			(thermal_gap 0.5)
			(thermal_bridge_width 0.5)
			(island_removal_mode 0)
		)
		(polygon
			(pts
				(xy 289.058858 -350.817434) (xy 288.378138 -350.817434) (xy 288.378138 -350.204278) (xy 289.058858 -350.204278)
			)
		)
	)
	(zone
		(layer "Cmts.User")
		(hatch none 0.5)
		(connect_pads
			(clearance 0)
		)
		(min_thickness 0.25)
		(keepout
			(tracks allowed)
			(vias allowed)
			(pads allowed)
			(copperpour allowed)
			(footprints allowed)
		)
		(placement
			(enabled no)
			(sheetname "")
		)
		(fill
			(thermal_gap 0.5)
			(thermal_bridge_width 0.5)
			(island_removal_mode 0)
		)
		(polygon
			(pts
				(xy 407.210514 -135.259572) (xy 407.210514 -134.586218) (xy 408.121866 -134.586218) (xy 408.121866 -135.259572)
			)
		)
	)
	(zone
		(layer "Cmts.User")
		(hatch none 0.5)
		(connect_pads
			(clearance 0)
		)
		(min_thickness 0.25)
		(keepout
			(tracks allowed)
			(vias allowed)
			(pads allowed)
			(copperpour allowed)
			(footprints allowed)
		)
		(placement
			(enabled no)
			(sheetname "")
		)
		(fill
			(thermal_gap 0.5)
			(thermal_bridge_width 0.5)
			(island_removal_mode 0)
		)
		(polygon
			(pts
				(xy 189.12967 -403.98573) (xy 189.12967 -401.005802) (xy 191.107568 -401.005802) (xy 191.107568 -404.596346)
				(xy 191.299338 -404.788116) (xy 194.813174 -404.788116) (xy 195.80987 -403.79142) (xy 195.80987 -402.820124)
				(xy 195.899278 -402.730716) (xy 197.292214 -402.730716) (xy 197.330568 -402.76907) (xy 197.330568 -403.855174)
				(xy 195.37553 -405.810212) (xy 190.864744 -405.810212) (xy 190.558166 -405.503634) (xy 190.558166 -405.414226)
			)
		)
	)
	(zone
		(layer "Cmts.User")
		(hatch none 0.5)
		(connect_pads
			(clearance 0)
		)
		(min_thickness 0.25)
		(keepout
			(tracks allowed)
			(vias allowed)
			(pads allowed)
			(copperpour allowed)
			(footprints allowed)
		)
		(placement
			(enabled no)
			(sheetname "")
		)
		(fill
			(thermal_gap 0.5)
			(thermal_bridge_width 0.5)
			(island_removal_mode 0)
		)
		(polygon
			(pts
				(xy 179.390294 -352.038412) (xy 179.085494 -352.038412) (xy 179.009294 -352.114612) (xy 179.009294 -353.105212)
				(xy 179.136294 -353.232212) (xy 179.288694 -353.232212) (xy 179.441094 -353.079812) (xy 179.441094 -352.089212)
			)
		)
	)
	(zone
		(layer "Cmts.User")
		(hatch none 0.5)
		(connect_pads
			(clearance 0)
		)
		(min_thickness 0.25)
		(keepout
			(tracks allowed)
			(vias allowed)
			(pads allowed)
			(copperpour allowed)
			(footprints allowed)
		)
		(placement
			(enabled no)
			(sheetname "")
		)
		(fill
			(thermal_gap 0.5)
			(thermal_bridge_width 0.5)
			(island_removal_mode 0)
		)
		(polygon
			(pts
				(xy 371.642132 -415.161222) (xy 418.77742 -415.161222) (xy 418.77742 -415.67989) (xy 371.642132 -415.67989)
				(xy 371.495828 -415.67989) (xy 371.454172 -415.638234) (xy 371.454172 -415.184082) (xy 371.477032 -415.161222)
			)
		)
	)
	(zone
		(layer "Cmts.User")
		(hatch none 0.5)
		(connect_pads
			(clearance 0)
		)
		(min_thickness 0.25)
		(keepout
			(tracks allowed)
			(vias allowed)
			(pads allowed)
			(copperpour allowed)
			(footprints allowed)
		)
		(placement
			(enabled no)
			(sheetname "")
		)
		(fill
			(thermal_gap 0.5)
			(thermal_bridge_width 0.5)
			(island_removal_mode 0)
		)
		(polygon
			(pts
				(xy 255.02997 -39.679372) (xy 255.02997 -39.04869) (xy 255.642364 -39.04869) (xy 255.642364 -39.679372)
			)
		)
	)
	(zone
		(layer "Cmts.User")
		(hatch none 0.5)
		(connect_pads
			(clearance 0)
		)
		(min_thickness 0.25)
		(keepout
			(tracks allowed)
			(vias allowed)
			(pads allowed)
			(copperpour allowed)
			(footprints allowed)
		)
		(placement
			(enabled no)
			(sheetname "")
		)
		(fill
			(thermal_gap 0.5)
			(thermal_bridge_width 0.5)
			(island_removal_mode 0)
		)
		(polygon
			(pts
				(xy 91.459304 -336.987896) (xy 91.459304 -336.357214) (xy 92.071698 -336.357214) (xy 92.071698 -336.987896)
			)
		)
	)
	(zone
		(layer "Cmts.User")
		(hatch none 0.5)
		(connect_pads
			(clearance 0)
		)
		(min_thickness 0.25)
		(keepout
			(tracks allowed)
			(vias allowed)
			(pads allowed)
			(copperpour allowed)
			(footprints allowed)
		)
		(placement
			(enabled no)
			(sheetname "")
		)
		(fill
			(thermal_gap 0.5)
			(thermal_bridge_width 0.5)
			(island_removal_mode 0)
		)
		(polygon
			(pts
				(xy 392.452098 -315.505592) (xy 391.771378 -315.505592) (xy 391.771378 -314.892436) (xy 392.452098 -314.892436)
			)
		)
	)
	(zone
		(layer "Cmts.User")
		(hatch none 0.5)
		(connect_pads
			(clearance 0)
		)
		(min_thickness 0.25)
		(keepout
			(tracks allowed)
			(vias allowed)
			(pads allowed)
			(copperpour allowed)
			(footprints allowed)
		)
		(placement
			(enabled no)
			(sheetname "")
		)
		(fill
			(thermal_gap 0.5)
			(thermal_bridge_width 0.5)
			(island_removal_mode 0)
		)
		(polygon
			(pts
				(xy 95.16999 -338.553552) (xy 94.71533 -338.553552) (xy 94.31147 -338.957412) (xy 94.91091 -339.556852)
				(xy 95.49257 -339.556852) (xy 95.49257 -338.876132)
			)
		)
	)
	(zone
		(layer "Cmts.User")
		(hatch none 0.5)
		(connect_pads
			(clearance 0)
		)
		(min_thickness 0.25)
		(keepout
			(tracks allowed)
			(vias allowed)
			(pads allowed)
			(copperpour allowed)
			(footprints allowed)
		)
		(placement
			(enabled no)
			(sheetname "")
		)
		(fill
			(thermal_gap 0.5)
			(thermal_bridge_width 0.5)
			(island_removal_mode 0)
		)
		(polygon
			(pts
				(xy 304.513996 -349.19793) (xy 304.513996 -347.14053) (xy 305.454812 -347.14053) (xy 305.454812 -349.19793)
			)
		)
	)
	(zone
		(layer "Cmts.User")
		(hatch none 0.5)
		(connect_pads
			(clearance 0)
		)
		(min_thickness 0.25)
		(keepout
			(tracks allowed)
			(vias allowed)
			(pads allowed)
			(copperpour allowed)
			(footprints allowed)
		)
		(placement
			(enabled no)
			(sheetname "")
		)
		(fill
			(thermal_gap 0.5)
			(thermal_bridge_width 0.5)
			(island_removal_mode 0)
		)
		(polygon
			(pts
				(xy 102.749604 -31.74746) (xy 103.487728 -31.74746) (xy 103.487728 -33.129474) (xy 102.749604 -33.129474)
			)
		)
	)
	(zone
		(layer "Cmts.User")
		(hatch none 0.5)
		(connect_pads
			(clearance 0)
		)
		(min_thickness 0.25)
		(keepout
			(tracks allowed)
			(vias allowed)
			(pads allowed)
			(copperpour allowed)
			(footprints allowed)
		)
		(placement
			(enabled no)
			(sheetname "")
		)
		(fill
			(thermal_gap 0.5)
			(thermal_bridge_width 0.5)
			(island_removal_mode 0)
		)
		(polygon
			(pts
				(xy 181.463188 -105.997756) (xy 199.757538 -105.997756) (xy 199.757538 -124.354336) (xy 194.358768 -124.354336)
				(xy 193.929508 -124.783596) (xy 193.393568 -124.783596) (xy 192.964308 -124.354336) (xy 181.463188 -124.354336)
			)
		)
	)
	(zone
		(layer "Cmts.User")
		(hatch none 0.5)
		(connect_pads
			(clearance 0)
		)
		(min_thickness 0.25)
		(keepout
			(tracks allowed)
			(vias allowed)
			(pads allowed)
			(copperpour allowed)
			(footprints allowed)
		)
		(placement
			(enabled no)
			(sheetname "")
		)
		(fill
			(thermal_gap 0.5)
			(thermal_bridge_width 0.5)
			(island_removal_mode 0)
		)
		(polygon
			(pts
				(xy 49.928526 -350.806766) (xy 49.928526 -350.176084) (xy 50.54092 -350.176084) (xy 50.54092 -350.806766)
			)
		)
	)
	(zone
		(layer "Cmts.User")
		(hatch none 0.5)
		(connect_pads
			(clearance 0)
		)
		(min_thickness 0.25)
		(keepout
			(tracks allowed)
			(vias allowed)
			(pads allowed)
			(copperpour allowed)
			(footprints allowed)
		)
		(placement
			(enabled no)
			(sheetname "")
		)
		(fill
			(thermal_gap 0.5)
			(thermal_bridge_width 0.5)
			(island_removal_mode 0)
		)
		(polygon
			(pts
				(xy 70.17131 -338.472272) (xy 69.65061 -338.472272) (xy 69.27469 -338.848192) (xy 69.89445 -339.467952)
				(xy 70.44309 -339.467952) (xy 70.44309 -338.744052)
			)
		)
	)
	(zone
		(layer "Cmts.User")
		(hatch none 0.5)
		(connect_pads
			(clearance 0)
		)
		(min_thickness 0.25)
		(keepout
			(tracks allowed)
			(vias allowed)
			(pads allowed)
			(copperpour allowed)
			(footprints allowed)
		)
		(placement
			(enabled no)
			(sheetname "")
		)
		(fill
			(thermal_gap 0.5)
			(thermal_bridge_width 0.5)
			(island_removal_mode 0)
		)
		(polygon
			(pts
				(xy 82.463894 -178.111912) (xy 82.209894 -178.111912) (xy 82.108294 -178.213512) (xy 82.108294 -178.594512)
				(xy 82.260694 -178.746912) (xy 82.260694 -179.127912) (xy 82.489294 -179.356512) (xy 83.098894 -179.356512)
				(xy 83.454494 -179.000912) (xy 83.454494 -178.645312) (xy 83.327494 -178.518312) (xy 82.870294 -178.518312)
			)
		)
	)
	(zone
		(layer "Cmts.User")
		(hatch none 0.5)
		(connect_pads
			(clearance 0)
		)
		(min_thickness 0.25)
		(keepout
			(tracks allowed)
			(vias allowed)
			(pads allowed)
			(copperpour allowed)
			(footprints allowed)
		)
		(placement
			(enabled no)
			(sheetname "")
		)
		(fill
			(thermal_gap 0.5)
			(thermal_bridge_width 0.5)
			(island_removal_mode 0)
		)
		(polygon
			(pts
				(xy 371.530372 -412.621222) (xy 416.902646 -412.621222) (xy 416.902646 -413.13989) (xy 371.530372 -413.13989)
				(xy 371.384068 -413.13989) (xy 371.342412 -413.098234) (xy 371.342412 -412.644082) (xy 371.365272 -412.621222)
			)
		)
	)
	(zone
		(layer "Cmts.User")
		(hatch none 0.5)
		(connect_pads
			(clearance 0)
		)
		(min_thickness 0.25)
		(keepout
			(tracks allowed)
			(vias allowed)
			(pads allowed)
			(copperpour allowed)
			(footprints allowed)
		)
		(placement
			(enabled no)
			(sheetname "")
		)
		(fill
			(thermal_gap 0.5)
			(thermal_bridge_width 0.5)
			(island_removal_mode 0)
		)
		(polygon
			(pts
				(xy 143.53794 -58.47334) (xy 143.53794 -56.20766) (xy 145.96364 -56.20766) (xy 145.96364 -58.47334)
			)
		)
	)
	(zone
		(layer "Cmts.User")
		(hatch none 0.5)
		(connect_pads
			(clearance 0)
		)
		(min_thickness 0.25)
		(keepout
			(tracks allowed)
			(vias allowed)
			(pads allowed)
			(copperpour allowed)
			(footprints allowed)
		)
		(placement
			(enabled no)
			(sheetname "")
		)
		(fill
			(thermal_gap 0.5)
			(thermal_bridge_width 0.5)
			(island_removal_mode 0)
		)
		(polygon
			(pts
				(xy 450.605906 -18.903696) (xy 450.605906 -18.273014) (xy 451.2183 -18.273014) (xy 451.2183 -18.903696)
			)
		)
	)
	(zone
		(layer "Cmts.User")
		(hatch none 0.5)
		(connect_pads
			(clearance 0)
		)
		(min_thickness 0.25)
		(keepout
			(tracks allowed)
			(vias allowed)
			(pads allowed)
			(copperpour allowed)
			(footprints allowed)
		)
		(placement
			(enabled no)
			(sheetname "")
		)
		(fill
			(thermal_gap 0.5)
			(thermal_bridge_width 0.5)
			(island_removal_mode 0)
		)
		(polygon
			(pts
				(xy 108.117894 -173.539912) (xy 107.381294 -173.539912) (xy 107.254294 -173.666912) (xy 107.254294 -174.047912)
				(xy 107.432094 -174.225712) (xy 107.432094 -174.530512) (xy 107.635294 -174.733712) (xy 108.270294 -174.733712)
				(xy 108.651294 -174.352712) (xy 108.651294 -174.073312)
			)
		)
	)
	(zone
		(layer "Cmts.User")
		(hatch none 0.5)
		(connect_pads
			(clearance 0)
		)
		(min_thickness 0.25)
		(keepout
			(tracks allowed)
			(vias allowed)
			(pads allowed)
			(copperpour allowed)
			(footprints allowed)
		)
		(placement
			(enabled no)
			(sheetname "")
		)
		(fill
			(thermal_gap 0.5)
			(thermal_bridge_width 0.5)
			(island_removal_mode 0)
		)
		(polygon
			(pts
				(xy 419.980618 -351.936812) (xy 419.879018 -351.936812) (xy 419.777418 -352.038412) (xy 419.777418 -352.775012)
				(xy 419.929818 -352.927412) (xy 420.006018 -352.927412) (xy 420.133018 -352.800412) (xy 420.133018 -352.089212)
			)
		)
	)
	(zone
		(layer "Cmts.User")
		(hatch none 0.5)
		(connect_pads
			(clearance 0)
		)
		(min_thickness 0.25)
		(keepout
			(tracks allowed)
			(vias allowed)
			(pads allowed)
			(copperpour allowed)
			(footprints allowed)
		)
		(placement
			(enabled no)
			(sheetname "")
		)
		(fill
			(thermal_gap 0.5)
			(thermal_bridge_width 0.5)
			(island_removal_mode 0)
		)
		(polygon
			(pts
				(xy 98.161094 -140.951712) (xy 97.627694 -140.418312) (xy 96.941894 -140.418312) (xy 96.713294 -140.189712)
				(xy 95.697294 -140.189712) (xy 95.519494 -140.011912) (xy 95.214694 -140.011912) (xy 95.087694 -140.138912)
				(xy 95.087694 -140.367512) (xy 95.748094 -141.027912) (xy 96.027494 -141.027912) (xy 96.256094 -140.799312)
				(xy 97.018094 -140.799312) (xy 97.145094 -140.926312) (xy 97.348294 -140.926312) (xy 97.754694 -141.332712)
				(xy 98.008694 -141.332712) (xy 98.161094 -141.180312)
			)
		)
	)
	(zone
		(layer "Cmts.User")
		(hatch none 0.5)
		(connect_pads
			(clearance 0)
		)
		(min_thickness 0.25)
		(keepout
			(tracks allowed)
			(vias allowed)
			(pads allowed)
			(copperpour allowed)
			(footprints allowed)
		)
		(placement
			(enabled no)
			(sheetname "")
		)
		(fill
			(thermal_gap 0.5)
			(thermal_bridge_width 0.5)
			(island_removal_mode 0)
		)
		(polygon
			(pts
				(xy 187.631578 -355.406452) (xy 187.631578 -354.77577) (xy 188.243972 -354.77577) (xy 188.243972 -355.406452)
			)
		)
	)
	(zone
		(layer "Cmts.User")
		(hatch none 0.5)
		(connect_pads
			(clearance 0)
		)
		(min_thickness 0.25)
		(keepout
			(tracks allowed)
			(vias allowed)
			(pads allowed)
			(copperpour allowed)
			(footprints allowed)
		)
		(placement
			(enabled no)
			(sheetname "")
		)
		(fill
			(thermal_gap 0.5)
			(thermal_bridge_width 0.5)
			(island_removal_mode 0)
		)
		(polygon
			(pts
				(xy 335.579974 -398.808702) (xy 335.579974 -396.509494) (xy 354.966016 -396.509494) (xy 354.966016 -398.808702)
			)
		)
	)
	(zone
		(layer "Cmts.User")
		(hatch none 0.5)
		(connect_pads
			(clearance 0)
		)
		(min_thickness 0.25)
		(keepout
			(tracks allowed)
			(vias allowed)
			(pads allowed)
			(copperpour allowed)
			(footprints allowed)
		)
		(placement
			(enabled no)
			(sheetname "")
		)
		(fill
			(thermal_gap 0.5)
			(thermal_bridge_width 0.5)
			(island_removal_mode 0)
		)
		(polygon
			(pts
				(xy 73.808844 -337.369658) (xy 73.808844 -336.738976) (xy 74.421238 -336.738976) (xy 74.421238 -337.369658)
			)
		)
	)
	(zone
		(layer "Cmts.User")
		(hatch none 0.5)
		(connect_pads
			(clearance 0)
		)
		(min_thickness 0.25)
		(keepout
			(tracks allowed)
			(vias allowed)
			(pads allowed)
			(copperpour allowed)
			(footprints allowed)
		)
		(placement
			(enabled no)
			(sheetname "")
		)
		(fill
			(thermal_gap 0.5)
			(thermal_bridge_width 0.5)
			(island_removal_mode 0)
		)
		(polygon
			(pts
				(xy 305.746658 -350.817434) (xy 305.065938 -350.817434) (xy 305.065938 -350.204278) (xy 305.746658 -350.204278)
			)
		)
	)
	(zone
		(layer "Cmts.User")
		(hatch none 0.5)
		(connect_pads
			(clearance 0)
		)
		(min_thickness 0.25)
		(keepout
			(tracks allowed)
			(vias allowed)
			(pads allowed)
			(copperpour allowed)
			(footprints allowed)
		)
		(placement
			(enabled no)
			(sheetname "")
		)
		(fill
			(thermal_gap 0.5)
			(thermal_bridge_width 0.5)
			(island_removal_mode 0)
		)
		(polygon
			(pts
				(xy 271.239996 -349.19793) (xy 271.239996 -347.14053) (xy 272.180812 -347.14053) (xy 272.180812 -349.19793)
			)
		)
	)
	(zone
		(layer "Cmts.User")
		(hatch none 0.5)
		(connect_pads
			(clearance 0)
		)
		(min_thickness 0.25)
		(keepout
			(tracks allowed)
			(vias allowed)
			(pads allowed)
			(copperpour allowed)
			(footprints allowed)
		)
		(placement
			(enabled no)
			(sheetname "")
		)
		(fill
			(thermal_gap 0.5)
			(thermal_bridge_width 0.5)
			(island_removal_mode 0)
		)
		(polygon
			(pts
				(xy 32.000444 -349.090742) (xy 32.000444 -348.46006) (xy 32.612838 -348.46006) (xy 32.612838 -349.090742)
			)
		)
	)
	(zone
		(layer "Cmts.User")
		(hatch none 0.5)
		(connect_pads
			(clearance 0)
		)
		(min_thickness 0.25)
		(keepout
			(tracks allowed)
			(vias allowed)
			(pads allowed)
			(copperpour allowed)
			(footprints allowed)
		)
		(placement
			(enabled no)
			(sheetname "")
		)
		(fill
			(thermal_gap 0.5)
			(thermal_bridge_width 0.5)
			(island_removal_mode 0)
		)
		(polygon
			(pts
				(xy 65.725294 -164.345112) (xy 65.572894 -164.345112) (xy 65.471294 -164.446712) (xy 65.471294 -164.776912)
				(xy 65.649094 -164.954712) (xy 65.649094 -165.411912) (xy 65.750694 -165.513512) (xy 66.487294 -165.513512)
				(xy 66.817494 -165.183312) (xy 66.817494 -164.802312) (xy 66.741294 -164.726112) (xy 66.106294 -164.726112)
			)
		)
	)
	(zone
		(layer "Cmts.User")
		(hatch none 0.5)
		(connect_pads
			(clearance 0)
		)
		(min_thickness 0.25)
		(keepout
			(tracks allowed)
			(vias allowed)
			(pads allowed)
			(copperpour allowed)
			(footprints allowed)
		)
		(placement
			(enabled no)
			(sheetname "")
		)
		(fill
			(thermal_gap 0.5)
			(thermal_bridge_width 0.5)
			(island_removal_mode 0)
		)
		(polygon
			(pts
				(xy 74.770488 -336.951574) (xy 74.770488 -336.320892) (xy 75.382882 -336.320892) (xy 75.382882 -336.951574)
			)
		)
	)
	(zone
		(layer "Cmts.User")
		(hatch none 0.5)
		(connect_pads
			(clearance 0)
		)
		(min_thickness 0.25)
		(keepout
			(tracks allowed)
			(vias allowed)
			(pads allowed)
			(copperpour allowed)
			(footprints allowed)
		)
		(placement
			(enabled no)
			(sheetname "")
		)
		(fill
			(thermal_gap 0.5)
			(thermal_bridge_width 0.5)
			(island_removal_mode 0)
		)
		(polygon
			(pts
				(xy 83.507326 -339.064092) (xy 83.507326 -338.43341) (xy 84.11972 -338.43341) (xy 84.11972 -339.064092)
			)
		)
	)
	(zone
		(layer "Cmts.User")
		(hatch none 0.5)
		(connect_pads
			(clearance 0)
		)
		(min_thickness 0.25)
		(keepout
			(tracks allowed)
			(vias allowed)
			(pads allowed)
			(copperpour allowed)
			(footprints allowed)
		)
		(placement
			(enabled no)
			(sheetname "")
		)
		(fill
			(thermal_gap 0.5)
			(thermal_bridge_width 0.5)
			(island_removal_mode 0)
		)
		(polygon
			(pts
				(xy 99.735132 -341.89797) (xy 99.735132 -341.267288) (xy 100.347526 -341.267288) (xy 100.347526 -341.89797)
			)
		)
	)
	(zone
		(layer "Cmts.User")
		(hatch none 0.5)
		(connect_pads
			(clearance 0)
		)
		(min_thickness 0.25)
		(keepout
			(tracks allowed)
			(vias allowed)
			(pads allowed)
			(copperpour allowed)
			(footprints allowed)
		)
		(placement
			(enabled no)
			(sheetname "")
		)
		(fill
			(thermal_gap 0.5)
			(thermal_bridge_width 0.5)
			(island_removal_mode 0)
		)
		(polygon
			(pts
				(xy 94.554294 -140.189712) (xy 93.462094 -140.189712) (xy 93.335094 -140.316712) (xy 93.335094 -140.697712)
				(xy 93.868494 -141.231112) (xy 94.173294 -141.231112) (xy 94.732094 -140.672312) (xy 94.732094 -140.367512)
			)
		)
	)
	(zone
		(layer "Cmts.User")
		(hatch none 0.5)
		(connect_pads
			(clearance 0)
		)
		(min_thickness 0.25)
		(keepout
			(tracks allowed)
			(vias allowed)
			(pads allowed)
			(copperpour allowed)
			(footprints allowed)
		)
		(placement
			(enabled no)
			(sheetname "")
		)
		(fill
			(thermal_gap 0.5)
			(thermal_bridge_width 0.5)
			(island_removal_mode 0)
		)
		(polygon
			(pts
				(xy 114.152426 -390.426702) (xy 114.152426 -388.127494) (xy 133.538468 -388.127494) (xy 133.538468 -390.426702)
			)
		)
	)
	(zone
		(layer "Cmts.User")
		(hatch none 0.5)
		(connect_pads
			(clearance 0)
		)
		(min_thickness 0.25)
		(keepout
			(tracks allowed)
			(vias allowed)
			(pads allowed)
			(copperpour allowed)
			(footprints allowed)
		)
		(placement
			(enabled no)
			(sheetname "")
		)
		(fill
			(thermal_gap 0.5)
			(thermal_bridge_width 0.5)
			(island_removal_mode 0)
		)
		(polygon
			(pts
				(xy 313.421776 -441.239148) (xy 313.421776 -425.547282) (xy 313.421776 -424.043348) (xy 329.626976 -424.043348)
				(xy 329.626976 -441.239148) (xy 327.249536 -441.239148)
			)
		)
	)
	(zone
		(layer "Cmts.User")
		(hatch none 0.5)
		(connect_pads
			(clearance 0)
		)
		(min_thickness 0.25)
		(keepout
			(tracks allowed)
			(vias allowed)
			(pads allowed)
			(copperpour allowed)
			(footprints allowed)
		)
		(placement
			(enabled no)
			(sheetname "")
		)
		(fill
			(thermal_gap 0.5)
			(thermal_bridge_width 0.5)
			(island_removal_mode 0)
		)
		(polygon
			(pts
				(xy 378.172218 -137.560812) (xy 377.943618 -137.560812) (xy 377.791218 -137.713212) (xy 377.791218 -137.967212)
				(xy 378.451618 -138.627612) (xy 378.731018 -138.627612) (xy 378.858018 -138.500612) (xy 378.858018 -138.246612)
			)
		)
	)
	(zone
		(layer "Cmts.User")
		(hatch none 0.5)
		(connect_pads
			(clearance 0)
		)
		(min_thickness 0.25)
		(keepout
			(tracks allowed)
			(vias allowed)
			(pads allowed)
			(copperpour allowed)
			(footprints allowed)
		)
		(placement
			(enabled no)
			(sheetname "")
		)
		(fill
			(thermal_gap 0.5)
			(thermal_bridge_width 0.5)
			(island_removal_mode 0)
		)
		(polygon
			(pts
				(xy 137.141712 -18.419064) (xy 137.141712 -17.68094) (xy 138.523726 -17.68094) (xy 138.523726 -18.419064)
			)
		)
	)
	(zone
		(layer "Cmts.User")
		(hatch none 0.5)
		(connect_pads
			(clearance 0)
		)
		(min_thickness 0.25)
		(keepout
			(tracks allowed)
			(vias allowed)
			(pads allowed)
			(copperpour allowed)
			(footprints allowed)
		)
		(placement
			(enabled no)
			(sheetname "")
		)
		(fill
			(thermal_gap 0.5)
			(thermal_bridge_width 0.5)
			(island_removal_mode 0)
		)
		(polygon
			(pts
				(xy 339.20811 -337.506056) (xy 339.20811 -335.448656) (xy 340.148926 -335.448656) (xy 340.148926 -337.506056)
			)
		)
	)
	(zone
		(layer "Cmts.User")
		(hatch none 0.5)
		(connect_pads
			(clearance 0)
		)
		(min_thickness 0.25)
		(keepout
			(tracks allowed)
			(vias allowed)
			(pads allowed)
			(copperpour allowed)
			(footprints allowed)
		)
		(placement
			(enabled no)
			(sheetname "")
		)
		(fill
			(thermal_gap 0.5)
			(thermal_bridge_width 0.5)
			(island_removal_mode 0)
		)
		(polygon
			(pts
				(xy 62.0522 -7.61492) (xy 62.0522 -6.36016) (xy 63.76162 -6.36016) (xy 63.76162 -7.61492)
			)
		)
	)
	(zone
		(layer "Cmts.User")
		(hatch none 0.5)
		(connect_pads
			(clearance 0)
		)
		(min_thickness 0.25)
		(keepout
			(tracks allowed)
			(vias allowed)
			(pads allowed)
			(copperpour allowed)
			(footprints allowed)
		)
		(placement
			(enabled no)
			(sheetname "")
		)
		(fill
			(thermal_gap 0.5)
			(thermal_bridge_width 0.5)
			(island_removal_mode 0)
		)
		(polygon
			(pts
				(xy 351.705418 -159.125412) (xy 351.248218 -159.125412) (xy 351.045018 -159.328612) (xy 351.045018 -160.395412)
				(xy 351.197418 -160.547812) (xy 351.705418 -160.547812) (xy 351.883218 -160.370012) (xy 351.883218 -159.303212)
			)
		)
	)
	(zone
		(layer "Cmts.User")
		(hatch none 0.5)
		(connect_pads
			(clearance 0)
		)
		(min_thickness 0.25)
		(keepout
			(tracks allowed)
			(vias allowed)
			(pads allowed)
			(copperpour allowed)
			(footprints allowed)
		)
		(placement
			(enabled no)
			(sheetname "")
		)
		(fill
			(thermal_gap 0.5)
			(thermal_bridge_width 0.5)
			(island_removal_mode 0)
		)
		(polygon
			(pts
				(xy 84.343494 -178.162712) (xy 84.140294 -178.162712) (xy 84.089494 -178.213512) (xy 84.089494 -179.000912)
				(xy 84.140294 -179.051712) (xy 84.343494 -179.051712) (xy 84.394294 -179.000912) (xy 84.394294 -178.213512)
			)
		)
	)
	(zone
		(layer "Cmts.User")
		(hatch none 0.5)
		(connect_pads
			(clearance 0)
		)
		(min_thickness 0.25)
		(keepout
			(tracks allowed)
			(vias allowed)
			(pads allowed)
			(copperpour allowed)
			(footprints allowed)
		)
		(placement
			(enabled no)
			(sheetname "")
		)
		(fill
			(thermal_gap 0.5)
			(thermal_bridge_width 0.5)
			(island_removal_mode 0)
		)
		(polygon
			(pts
				(xy 304.541936 -415.161222) (xy 351.677224 -415.161222) (xy 351.677224 -415.67989) (xy 304.541936 -415.67989)
				(xy 304.395632 -415.67989) (xy 304.353976 -415.638234) (xy 304.353976 -415.184082) (xy 304.376836 -415.161222)
			)
		)
	)
	(zone
		(layer "Cmts.User")
		(hatch none 0.5)
		(connect_pads
			(clearance 0)
		)
		(min_thickness 0.25)
		(keepout
			(tracks allowed)
			(vias allowed)
			(pads allowed)
			(copperpour allowed)
			(footprints allowed)
		)
		(placement
			(enabled no)
			(sheetname "")
		)
		(fill
			(thermal_gap 0.5)
			(thermal_bridge_width 0.5)
			(island_removal_mode 0)
		)
		(polygon
			(pts
				(xy 453.277986 -401.469352) (xy 453.277986 -400.83867) (xy 453.89038 -400.83867) (xy 453.89038 -401.469352)
			)
		)
	)
	(zone
		(layer "Cmts.User")
		(hatch none 0.5)
		(connect_pads
			(clearance 0)
		)
		(min_thickness 0.25)
		(keepout
			(tracks allowed)
			(vias allowed)
			(pads allowed)
			(copperpour allowed)
			(footprints allowed)
		)
		(placement
			(enabled no)
			(sheetname "")
		)
		(fill
			(thermal_gap 0.5)
			(thermal_bridge_width 0.5)
			(island_removal_mode 0)
		)
		(polygon
			(pts
				(xy 305.766724 -362.881418) (xy 305.086004 -362.881418) (xy 305.086004 -362.268262) (xy 305.766724 -362.268262)
			)
		)
	)
	(zone
		(layer "Cmts.User")
		(hatch none 0.5)
		(connect_pads
			(clearance 0)
		)
		(min_thickness 0.25)
		(keepout
			(tracks allowed)
			(vias allowed)
			(pads allowed)
			(copperpour allowed)
			(footprints allowed)
		)
		(placement
			(enabled no)
			(sheetname "")
		)
		(fill
			(thermal_gap 0.5)
			(thermal_bridge_width 0.5)
			(island_removal_mode 0)
		)
		(polygon
			(pts
				(xy 354.084636 -335.869534) (xy 354.084636 -329.249024) (xy 360.59618 -329.249024) (xy 360.59618 -335.869534)
			)
		)
	)
	(zone
		(layer "Cmts.User")
		(hatch none 0.5)
		(connect_pads
			(clearance 0)
		)
		(min_thickness 0.25)
		(keepout
			(tracks allowed)
			(vias allowed)
			(pads allowed)
			(copperpour allowed)
			(footprints allowed)
		)
		(placement
			(enabled no)
			(sheetname "")
		)
		(fill
			(thermal_gap 0.5)
			(thermal_bridge_width 0.5)
			(island_removal_mode 0)
		)
		(polygon
			(pts
				(xy 243.64188 -52.683918) (xy 243.64188 -51.433476) (xy 245.4656 -51.433476) (xy 245.4656 -52.683918)
			)
		)
	)
	(zone
		(layer "Cmts.User")
		(hatch none 0.5)
		(connect_pads
			(clearance 0)
		)
		(min_thickness 0.25)
		(keepout
			(tracks allowed)
			(vias allowed)
			(pads allowed)
			(copperpour allowed)
			(footprints allowed)
		)
		(placement
			(enabled no)
			(sheetname "")
		)
		(fill
			(thermal_gap 0.5)
			(thermal_bridge_width 0.5)
			(island_removal_mode 0)
		)
		(polygon
			(pts
				(xy 127.832358 -163.224718) (xy 127.476758 -163.224718) (xy 127.375158 -163.326318) (xy 127.375158 -164.393118)
				(xy 127.451358 -164.469318) (xy 127.857758 -164.469318) (xy 127.933958 -164.393118) (xy 127.933958 -163.326318)
			)
		)
	)
	(zone
		(layer "Cmts.User")
		(hatch none 0.5)
		(connect_pads
			(clearance 0)
		)
		(min_thickness 0.25)
		(keepout
			(tracks allowed)
			(vias allowed)
			(pads allowed)
			(copperpour allowed)
			(footprints allowed)
		)
		(placement
			(enabled no)
			(sheetname "")
		)
		(fill
			(thermal_gap 0.5)
			(thermal_bridge_width 0.5)
			(island_removal_mode 0)
		)
		(polygon
			(pts
				(xy 16.604996 -392.512804) (xy 16.604996 -393.12596) (xy 15.330678 -393.12596) (xy 15.330678 -392.512804)
			)
		)
	)
	(zone
		(layer "Cmts.User")
		(hatch none 0.5)
		(connect_pads
			(clearance 0)
		)
		(min_thickness 0.25)
		(keepout
			(tracks allowed)
			(vias allowed)
			(pads allowed)
			(copperpour allowed)
			(footprints allowed)
		)
		(placement
			(enabled no)
			(sheetname "")
		)
		(fill
			(thermal_gap 0.5)
			(thermal_bridge_width 0.5)
			(island_removal_mode 0)
		)
		(polygon
			(pts
				(xy 32.886904 -348.67977) (xy 32.886904 -348.049088) (xy 33.499298 -348.049088) (xy 33.499298 -348.67977)
			)
		)
	)
	(zone
		(layer "Cmts.User")
		(hatch none 0.5)
		(connect_pads
			(clearance 0)
		)
		(min_thickness 0.25)
		(keepout
			(tracks allowed)
			(vias allowed)
			(pads allowed)
			(copperpour allowed)
			(footprints allowed)
		)
		(placement
			(enabled no)
			(sheetname "")
		)
		(fill
			(thermal_gap 0.5)
			(thermal_bridge_width 0.5)
			(island_removal_mode 0)
		)
		(polygon
			(pts
				(xy 102.965758 -180.725318) (xy 102.610158 -180.725318) (xy 102.508558 -180.826918) (xy 102.508558 -181.893718)
				(xy 102.584758 -181.969918) (xy 102.991158 -181.969918) (xy 103.067358 -181.893718) (xy 103.067358 -180.826918)
			)
		)
	)
	(zone
		(layer "Cmts.User")
		(hatch none 0.5)
		(connect_pads
			(clearance 0)
		)
		(min_thickness 0.25)
		(keepout
			(tracks allowed)
			(vias allowed)
			(pads allowed)
			(copperpour allowed)
			(footprints allowed)
		)
		(placement
			(enabled no)
			(sheetname "")
		)
		(fill
			(thermal_gap 0.5)
			(thermal_bridge_width 0.5)
			(island_removal_mode 0)
		)
		(polygon
			(pts
				(xy 370.152422 -398.808702) (xy 370.152422 -396.509494) (xy 389.538464 -396.509494) (xy 389.538464 -398.808702)
			)
		)
	)
	(zone
		(layer "Cmts.User")
		(hatch none 0.5)
		(connect_pads
			(clearance 0)
		)
		(min_thickness 0.25)
		(keepout
			(tracks allowed)
			(vias allowed)
			(pads allowed)
			(copperpour allowed)
			(footprints allowed)
		)
		(placement
			(enabled no)
			(sheetname "")
		)
		(fill
			(thermal_gap 0.5)
			(thermal_bridge_width 0.5)
			(island_removal_mode 0)
		)
		(polygon
			(pts
				(xy 191.099694 -354.807012) (xy 190.464694 -354.807012) (xy 190.083694 -355.188012) (xy 190.769494 -355.873812)
				(xy 191.277494 -355.873812) (xy 191.404494 -355.746812) (xy 191.404494 -355.264212) (xy 191.099694 -354.959412)
			)
		)
	)
	(zone
		(layer "Cmts.User")
		(hatch none 0.5)
		(connect_pads
			(clearance 0)
		)
		(min_thickness 0.25)
		(keepout
			(tracks allowed)
			(vias allowed)
			(pads allowed)
			(copperpour allowed)
			(footprints allowed)
		)
		(placement
			(enabled no)
			(sheetname "")
		)
		(fill
			(thermal_gap 0.5)
			(thermal_bridge_width 0.5)
			(island_removal_mode 0)
		)
		(polygon
			(pts
				(xy 115.530376 -412.863538) (xy 115.530376 -412.34487) (xy 162.665664 -412.34487) (xy 162.665664 -412.863538)
			)
		)
	)
	(zone
		(layer "Cmts.User")
		(hatch none 0.5)
		(connect_pads
			(clearance 0)
		)
		(min_thickness 0.25)
		(keepout
			(tracks allowed)
			(vias allowed)
			(pads allowed)
			(copperpour allowed)
			(footprints allowed)
		)
		(placement
			(enabled no)
			(sheetname "")
		)
		(fill
			(thermal_gap 0.5)
			(thermal_bridge_width 0.5)
			(island_removal_mode 0)
		)
		(polygon
			(pts
				(xy 364.888018 -173.120812) (xy 364.303818 -173.120812) (xy 364.126018 -173.298612) (xy 364.126018 -174.009812)
				(xy 364.532418 -174.416212) (xy 365.065818 -174.416212) (xy 365.472218 -174.009812) (xy 365.472218 -173.705012)
			)
		)
	)
	(zone
		(layer "Cmts.User")
		(hatch none 0.5)
		(connect_pads
			(clearance 0)
		)
		(min_thickness 0.25)
		(keepout
			(tracks allowed)
			(vias allowed)
			(pads allowed)
			(copperpour allowed)
			(footprints allowed)
		)
		(placement
			(enabled no)
			(sheetname "")
		)
		(fill
			(thermal_gap 0.5)
			(thermal_bridge_width 0.5)
			(island_removal_mode 0)
		)
		(polygon
			(pts
				(xy 47.438564 -391.125456) (xy 66.089022 -391.125456) (xy 66.089022 -393.847574) (xy 66.089022 -394.14196)
				(xy 46.951392 -394.14196) (xy 46.951392 -391.125456)
			)
		)
	)
	(zone
		(layer "Cmts.User")
		(hatch none 0.5)
		(connect_pads
			(clearance 0)
		)
		(min_thickness 0.25)
		(keepout
			(tracks allowed)
			(vias allowed)
			(pads allowed)
			(copperpour allowed)
			(footprints allowed)
		)
		(placement
			(enabled no)
			(sheetname "")
		)
		(fill
			(thermal_gap 0.5)
			(thermal_bridge_width 0.5)
			(island_removal_mode 0)
		)
		(polygon
			(pts
				(xy 90.769694 -178.061112) (xy 90.668094 -178.061112) (xy 90.464894 -178.264312) (xy 90.464894 -178.924712)
				(xy 90.820494 -179.280312) (xy 91.506294 -179.280312) (xy 91.887294 -178.899312) (xy 91.887294 -178.569112)
				(xy 91.785694 -178.467512) (xy 91.176094 -178.467512)
			)
		)
	)
	(zone
		(layer "Cmts.User")
		(hatch none 0.5)
		(connect_pads
			(clearance 0)
		)
		(min_thickness 0.25)
		(keepout
			(tracks allowed)
			(vias allowed)
			(pads allowed)
			(copperpour allowed)
			(footprints allowed)
		)
		(placement
			(enabled no)
			(sheetname "")
		)
		(fill
			(thermal_gap 0.5)
			(thermal_bridge_width 0.5)
			(island_removal_mode 0)
		)
		(polygon
			(pts
				(xy 77.827378 -175.658018) (xy 77.471778 -175.658018) (xy 77.370178 -175.759618) (xy 77.370178 -176.826418)
				(xy 77.446378 -176.902618) (xy 77.852778 -176.902618) (xy 77.928978 -176.826418) (xy 77.928978 -175.759618)
			)
		)
	)
	(zone
		(layer "Cmts.User")
		(hatch none 0.5)
		(connect_pads
			(clearance 0)
		)
		(min_thickness 0.25)
		(keepout
			(tracks allowed)
			(vias allowed)
			(pads allowed)
			(copperpour allowed)
			(footprints allowed)
		)
		(placement
			(enabled no)
			(sheetname "")
		)
		(fill
			(thermal_gap 0.5)
			(thermal_bridge_width 0.5)
			(island_removal_mode 0)
		)
		(polygon
			(pts
				(xy 359.858818 -167.558212) (xy 359.579418 -167.558212) (xy 359.452418 -167.685212) (xy 359.452418 -168.625012)
				(xy 359.554018 -168.726612) (xy 359.909618 -168.726612) (xy 359.985818 -168.650412) (xy 359.985818 -167.685212)
			)
		)
	)
	(zone
		(layer "Cmts.User")
		(hatch none 0.5)
		(connect_pads
			(clearance 0)
		)
		(min_thickness 0.25)
		(keepout
			(tracks allowed)
			(vias allowed)
			(pads allowed)
			(copperpour allowed)
			(footprints allowed)
		)
		(placement
			(enabled no)
			(sheetname "")
		)
		(fill
			(thermal_gap 0.5)
			(thermal_bridge_width 0.5)
			(island_removal_mode 0)
		)
		(polygon
			(pts
				(xy 428.352204 -355.24821) (xy 428.352204 -354.641658) (xy 428.982632 -354.641658) (xy 428.982632 -355.24821)
			)
		)
	)
	(zone
		(layer "Cmts.User")
		(hatch none 0.5)
		(connect_pads
			(clearance 0)
		)
		(min_thickness 0.25)
		(keepout
			(tracks allowed)
			(vias allowed)
			(pads allowed)
			(copperpour allowed)
			(footprints allowed)
		)
		(placement
			(enabled no)
			(sheetname "")
		)
		(fill
			(thermal_gap 0.5)
			(thermal_bridge_width 0.5)
			(island_removal_mode 0)
		)
		(polygon
			(pts
				(xy 451.384162 -23.29053) (xy 451.384162 -22.659848) (xy 451.996556 -22.659848) (xy 451.996556 -23.29053)
			)
		)
	)
	(zone
		(layer "Cmts.User")
		(hatch none 0.5)
		(connect_pads
			(clearance 0)
		)
		(min_thickness 0.25)
		(keepout
			(tracks allowed)
			(vias allowed)
			(pads allowed)
			(copperpour allowed)
			(footprints allowed)
		)
		(placement
			(enabled no)
			(sheetname "")
		)
		(fill
			(thermal_gap 0.5)
			(thermal_bridge_width 0.5)
			(island_removal_mode 0)
		)
		(polygon
			(pts
				(xy 416.627818 -158.846012) (xy 416.272218 -158.846012) (xy 416.094418 -159.023812) (xy 416.094418 -160.166812)
				(xy 416.297618 -160.370012) (xy 416.729418 -160.370012) (xy 416.881818 -160.217612) (xy 416.881818 -159.100012)
			)
		)
	)
	(zone
		(layer "Cmts.User")
		(hatch none 0.5)
		(connect_pads
			(clearance 0)
		)
		(min_thickness 0.25)
		(keepout
			(tracks allowed)
			(vias allowed)
			(pads allowed)
			(copperpour allowed)
			(footprints allowed)
		)
		(placement
			(enabled no)
			(sheetname "")
		)
		(fill
			(thermal_gap 0.5)
			(thermal_bridge_width 0.5)
			(island_removal_mode 0)
		)
		(polygon
			(pts
				(xy 393.259818 -180.740812) (xy 392.828018 -180.740812) (xy 392.726418 -180.842412) (xy 392.726418 -182.010812)
				(xy 392.853418 -182.137812) (xy 393.285218 -182.137812) (xy 393.463018 -181.960012) (xy 393.463018 -180.944012)
			)
		)
	)
	(zone
		(layer "Cmts.User")
		(hatch none 0.5)
		(connect_pads
			(clearance 0)
		)
		(min_thickness 0.25)
		(keepout
			(tracks allowed)
			(vias allowed)
			(pads allowed)
			(copperpour allowed)
			(footprints allowed)
		)
		(placement
			(enabled no)
			(sheetname "")
		)
		(fill
			(thermal_gap 0.5)
			(thermal_bridge_width 0.5)
			(island_removal_mode 0)
		)
		(polygon
			(pts
				(xy 145.972276 -384.68808) (xy 145.972276 -382.701546) (xy 166.094156 -382.701546) (xy 166.094156 -384.68808)
				(xy 166.094156 -386.122672) (xy 146.86407 -386.122672) (xy 146.86407 -384.68808)
			)
		)
	)
	(zone
		(layer "Cmts.User")
		(hatch none 0.5)
		(connect_pads
			(clearance 0)
		)
		(min_thickness 0.25)
		(keepout
			(tracks allowed)
			(vias allowed)
			(pads allowed)
			(copperpour allowed)
			(footprints allowed)
		)
		(placement
			(enabled no)
			(sheetname "")
		)
		(fill
			(thermal_gap 0.5)
			(thermal_bridge_width 0.5)
			(island_removal_mode 0)
		)
		(polygon
			(pts
				(xy 67.79641 -164.158168) (xy 67.44081 -164.158168) (xy 67.33921 -164.259768) (xy 67.33921 -165.326568)
				(xy 67.41541 -165.402768) (xy 67.82181 -165.402768) (xy 67.89801 -165.326568) (xy 67.89801 -164.259768)
			)
		)
	)
	(zone
		(layer "Cmts.User")
		(hatch none 0.5)
		(connect_pads
			(clearance 0)
		)
		(min_thickness 0.25)
		(keepout
			(tracks allowed)
			(vias allowed)
			(pads allowed)
			(copperpour allowed)
			(footprints allowed)
		)
		(placement
			(enabled no)
			(sheetname "")
		)
		(fill
			(thermal_gap 0.5)
			(thermal_bridge_width 0.5)
			(island_removal_mode 0)
		)
		(polygon
			(pts
				(xy 74.056494 -173.031912) (xy 73.929494 -173.031912) (xy 73.777094 -173.184312) (xy 73.777094 -173.463712)
				(xy 73.954894 -173.641512) (xy 73.954894 -174.047912) (xy 74.056494 -174.149512) (xy 74.869294 -174.149512)
				(xy 75.174094 -173.844712) (xy 75.174094 -173.539912) (xy 75.047094 -173.412912) (xy 74.437494 -173.412912)
			)
		)
	)
	(zone
		(layer "Cmts.User")
		(hatch none 0.5)
		(connect_pads
			(clearance 0)
		)
		(min_thickness 0.25)
		(keepout
			(tracks allowed)
			(vias allowed)
			(pads allowed)
			(copperpour allowed)
			(footprints allowed)
		)
		(placement
			(enabled no)
			(sheetname "")
		)
		(fill
			(thermal_gap 0.5)
			(thermal_bridge_width 0.5)
			(island_removal_mode 0)
		)
		(polygon
			(pts
				(xy 410.049218 -166.618412) (xy 409.592018 -166.618412) (xy 409.490418 -166.720012) (xy 409.490418 -167.837612)
				(xy 409.592018 -167.939212) (xy 410.125418 -167.939212) (xy 410.201618 -167.863012) (xy 410.201618 -166.770812)
			)
		)
	)
	(zone
		(layer "Cmts.User")
		(hatch none 0.5)
		(connect_pads
			(clearance 0)
		)
		(min_thickness 0.25)
		(keepout
			(tracks allowed)
			(vias allowed)
			(pads allowed)
			(copperpour allowed)
			(footprints allowed)
		)
		(placement
			(enabled no)
			(sheetname "")
		)
		(fill
			(thermal_gap 0.5)
			(thermal_bridge_width 0.5)
			(island_removal_mode 0)
		)
		(polygon
			(pts
				(xy 109.489494 -173.666912) (xy 109.337094 -173.666912) (xy 109.286294 -173.717712) (xy 109.286294 -174.352712)
				(xy 109.413294 -174.479712) (xy 109.565694 -174.327312) (xy 109.565694 -173.743112)
			)
		)
	)
	(zone
		(layer "Cmts.User")
		(hatch none 0.5)
		(connect_pads
			(clearance 0)
		)
		(min_thickness 0.25)
		(keepout
			(tracks allowed)
			(vias allowed)
			(pads allowed)
			(copperpour allowed)
			(footprints allowed)
		)
		(placement
			(enabled no)
			(sheetname "")
		)
		(fill
			(thermal_gap 0.5)
			(thermal_bridge_width 0.5)
			(island_removal_mode 0)
		)
		(polygon
			(pts
				(xy 330.87691 -337.455256) (xy 330.87691 -335.397856) (xy 331.817726 -335.397856) (xy 331.817726 -337.455256)
			)
		)
	)
	(zone
		(layer "Cmts.User")
		(hatch none 0.5)
		(connect_pads
			(clearance 0)
		)
		(min_thickness 0.25)
		(keepout
			(tracks allowed)
			(vias allowed)
			(pads allowed)
			(copperpour allowed)
			(footprints allowed)
		)
		(placement
			(enabled no)
			(sheetname "")
		)
		(fill
			(thermal_gap 0.5)
			(thermal_bridge_width 0.5)
			(island_removal_mode 0)
		)
		(polygon
			(pts
				(xy 189.397894 -355.010212) (xy 189.169294 -355.010212) (xy 189.093094 -355.086412) (xy 189.093094 -355.848412)
				(xy 189.194694 -355.950012) (xy 189.372494 -355.950012) (xy 189.474094 -355.848412) (xy 189.474094 -355.086412)
			)
		)
	)
	(zone
		(layer "Cmts.User")
		(hatch none 0.5)
		(connect_pads
			(clearance 0)
		)
		(min_thickness 0.25)
		(keepout
			(tracks allowed)
			(vias allowed)
			(pads allowed)
			(copperpour allowed)
			(footprints allowed)
		)
		(placement
			(enabled no)
			(sheetname "")
		)
		(fill
			(thermal_gap 0.5)
			(thermal_bridge_width 0.5)
			(island_removal_mode 0)
		)
		(polygon
			(pts
				(xy 381.728218 -178.10734) (xy 381.067818 -178.10734) (xy 380.864618 -178.31054) (xy 380.864618 -178.92014)
				(xy 381.271018 -179.32654) (xy 381.931418 -179.32654) (xy 382.261618 -178.99634) (xy 382.261618 -178.64074)
			)
		)
	)
	(zone
		(layer "Cmts.User")
		(hatch none 0.5)
		(connect_pads
			(clearance 0)
		)
		(min_thickness 0.25)
		(keepout
			(tracks allowed)
			(vias allowed)
			(pads allowed)
			(copperpour allowed)
			(footprints allowed)
		)
		(placement
			(enabled no)
			(sheetname "")
		)
		(fill
			(thermal_gap 0.5)
			(thermal_bridge_width 0.5)
			(island_removal_mode 0)
		)
		(polygon
			(pts
				(xy 91.838526 -339.114892) (xy 91.838526 -338.48421) (xy 92.45092 -338.48421) (xy 92.45092 -339.114892)
			)
		)
	)
	(zone
		(layer "Cmts.User")
		(hatch none 0.5)
		(connect_pads
			(clearance 0)
		)
		(min_thickness 0.25)
		(keepout
			(tracks allowed)
			(vias allowed)
			(pads allowed)
			(copperpour allowed)
			(footprints allowed)
		)
		(placement
			(enabled no)
			(sheetname "")
		)
		(fill
			(thermal_gap 0.5)
			(thermal_bridge_width 0.5)
			(island_removal_mode 0)
		)
		(polygon
			(pts
				(xy 297.415458 -350.817434) (xy 296.734738 -350.817434) (xy 296.734738 -350.204278) (xy 297.415458 -350.204278)
			)
		)
	)
	(zone
		(layer "Cmts.User")
		(hatch none 0.5)
		(connect_pads
			(clearance 0)
		)
		(min_thickness 0.25)
		(keepout
			(tracks allowed)
			(vias allowed)
			(pads allowed)
			(copperpour allowed)
			(footprints allowed)
		)
		(placement
			(enabled no)
			(sheetname "")
		)
		(fill
			(thermal_gap 0.5)
			(thermal_bridge_width 0.5)
			(island_removal_mode 0)
		)
		(polygon
			(pts
				(xy 185.020204 -405.53894) (xy 185.020204 -406.915874) (xy 184.015888 -406.915874) (xy 182.658766 -405.558752)
				(xy 182.658766 -396.763748) (xy 183.88584 -395.536674) (xy 185.16346 -395.536674) (xy 185.763916 -396.13713)
				(xy 185.763916 -399.319242) (xy 185.020204 -400.062954)
			)
		)
	)
	(zone
		(layer "Cmts.User")
		(hatch none 0.5)
		(connect_pads
			(clearance 0)
		)
		(min_thickness 0.25)
		(keepout
			(tracks allowed)
			(vias allowed)
			(pads allowed)
			(copperpour allowed)
			(footprints allowed)
		)
		(placement
			(enabled no)
			(sheetname "")
		)
		(fill
			(thermal_gap 0.5)
			(thermal_bridge_width 0.5)
			(island_removal_mode 0)
		)
		(polygon
			(pts
				(xy 398.416018 -172.460412) (xy 397.730218 -172.460412) (xy 397.552418 -172.638212) (xy 397.552418 -173.476412)
				(xy 397.958818 -173.882812) (xy 398.543018 -173.882812) (xy 399.051018 -173.374812) (xy 399.051018 -173.095412)
			)
		)
	)
	(zone
		(layer "Cmts.User")
		(hatch none 0.5)
		(connect_pads
			(clearance 0)
		)
		(min_thickness 0.25)
		(keepout
			(tracks allowed)
			(vias allowed)
			(pads allowed)
			(copperpour allowed)
			(footprints allowed)
		)
		(placement
			(enabled no)
			(sheetname "")
		)
		(fill
			(thermal_gap 0.5)
			(thermal_bridge_width 0.5)
			(island_removal_mode 0)
		)
		(polygon
			(pts
				(xy 33.266126 -350.806766) (xy 33.266126 -350.176084) (xy 33.87852 -350.176084) (xy 33.87852 -350.806766)
			)
		)
	)
	(zone
		(layer "Cmts.User")
		(hatch none 0.5)
		(connect_pads
			(clearance 0)
		)
		(min_thickness 0.25)
		(keepout
			(tracks allowed)
			(vias allowed)
			(pads allowed)
			(copperpour allowed)
			(footprints allowed)
		)
		(placement
			(enabled no)
			(sheetname "")
		)
		(fill
			(thermal_gap 0.5)
			(thermal_bridge_width 0.5)
			(island_removal_mode 0)
		)
		(polygon
			(pts
				(xy 78.54569 -338.538312) (xy 78.00975 -338.538312) (xy 77.62875 -338.919312) (xy 78.23073 -339.521292)
				(xy 78.86065 -339.521292) (xy 78.86065 -338.853272)
			)
		)
	)
	(zone
		(layer "Cmts.User")
		(hatch none 0.5)
		(connect_pads
			(clearance 0)
		)
		(min_thickness 0.25)
		(keepout
			(tracks allowed)
			(vias allowed)
			(pads allowed)
			(copperpour allowed)
			(footprints allowed)
		)
		(placement
			(enabled no)
			(sheetname "")
		)
		(fill
			(thermal_gap 0.5)
			(thermal_bridge_width 0.5)
			(island_removal_mode 0)
		)
		(polygon
			(pts
				(xy 282.58135 -351.343214) (xy 282.58135 -350.151446) (xy 283.961586 -350.151446) (xy 283.961586 -351.343214)
			)
		)
	)
	(zone
		(layer "Cmts.User")
		(hatch none 0.5)
		(connect_pads
			(clearance 0)
		)
		(min_thickness 0.25)
		(keepout
			(tracks allowed)
			(vias allowed)
			(pads allowed)
			(copperpour allowed)
			(footprints allowed)
		)
		(placement
			(enabled no)
			(sheetname "")
		)
		(fill
			(thermal_gap 0.5)
			(thermal_bridge_width 0.5)
			(island_removal_mode 0)
		)
		(polygon
			(pts
				(xy 99.710494 -178.086512) (xy 99.024694 -178.086512) (xy 98.872294 -178.238912) (xy 98.872294 -178.950112)
				(xy 99.177094 -179.254912) (xy 99.913694 -179.254912) (xy 100.269294 -178.899312) (xy 100.269294 -178.645312)
			)
		)
	)
	(zone
		(layer "Cmts.User")
		(hatch none 0.5)
		(connect_pads
			(clearance 0)
		)
		(min_thickness 0.25)
		(keepout
			(tracks allowed)
			(vias allowed)
			(pads allowed)
			(copperpour allowed)
			(footprints allowed)
		)
		(placement
			(enabled no)
			(sheetname "")
		)
		(fill
			(thermal_gap 0.5)
			(thermal_bridge_width 0.5)
			(island_removal_mode 0)
		)
		(polygon
			(pts
				(xy 57.880504 -348.67977) (xy 57.880504 -348.049088) (xy 58.492898 -348.049088) (xy 58.492898 -348.67977)
			)
		)
	)
	(zone
		(layer "In9.Cu")
		(hatch none 0.5)
		(connect_pads
			(clearance 0)
		)
		(min_thickness 0.25)
		(keepout
			(tracks not_allowed)
			(vias allowed)
			(pads allowed)
			(copperpour not_allowed)
			(footprints allowed)
		)
		(placement
			(enabled no)
			(sheetname "")
		)
		(fill
			(thermal_gap 0.5)
			(thermal_bridge_width 0.5)
			(island_removal_mode 0)
		)
		(polygon
			(pts
				(arc
					(start 18.270474 -435.600348)
					(mid 12.148678 -430.399053)
					(end 8.004556 -437.280558)
				)
				(xy 8.004556 -440.17819) (xy 8.39724 -440.570874)
				(arc
					(start 11.247374 -440.570874)
					(mid 16.044701 -439.902367)
					(end 18.270474 -435.600348)
				)
			)
		)
	)
	(zone
		(layer "In9.Cu")
		(hatch none 0.5)
		(connect_pads
			(clearance 0)
		)
		(min_thickness 0.25)
		(keepout
			(tracks not_allowed)
			(vias allowed)
			(pads allowed)
			(copperpour not_allowed)
			(footprints allowed)
		)
		(placement
			(enabled no)
			(sheetname "")
		)
		(fill
			(thermal_gap 0.5)
			(thermal_bridge_width 0.5)
			(island_removal_mode 0)
		)
		(polygon
			(pts
				(arc
					(start 464.070446 -435.600348)
					(mid 454.414164 -432.677746)
					(end 460.82839 -440.46521)
				)
				(xy 463.675476 -440.46521) (xy 463.774028 -440.366658)
				(arc
					(start 463.774028 -437.343296)
					(mid 463.995856 -436.484341)
					(end 464.070446 -435.600348)
				)
			)
		)
	)
	(zone
		(layer "In9.Cu")
		(hatch none 0.5)
		(connect_pads
			(clearance 0)
		)
		(min_thickness 0.25)
		(keepout
			(tracks not_allowed)
			(vias allowed)
			(pads allowed)
			(copperpour not_allowed)
			(footprints allowed)
		)
		(placement
			(enabled no)
			(sheetname "")
		)
		(fill
			(thermal_gap 0.5)
			(thermal_bridge_width 0.5)
			(island_removal_mode 0)
		)
		(polygon
			(pts
				(arc
					(start 97.150174 -421.122094)
					(mid 97.165053 -421.158015)
					(end 97.200974 -421.172894)
				)
				(arc
					(start 102.099618 -421.172894)
					(mid 102.135539 -421.158015)
					(end 102.150418 -421.122094)
				)
				(arc
					(start 102.150418 -414.328102)
					(mid 102.135539 -414.292181)
					(end 102.099618 -414.277302)
				)
				(arc
					(start 97.200974 -414.277302)
					(mid 97.165053 -414.292181)
					(end 97.150174 -414.328102)
				)
			)
		)
	)
	(zone
		(layer "In9.Cu")
		(hatch none 0.5)
		(connect_pads
			(clearance 0)
		)
		(min_thickness 0.25)
		(keepout
			(tracks not_allowed)
			(vias allowed)
			(pads allowed)
			(copperpour not_allowed)
			(footprints allowed)
		)
		(placement
			(enabled no)
			(sheetname "")
		)
		(fill
			(thermal_gap 0.5)
			(thermal_bridge_width 0.5)
			(island_removal_mode 0)
		)
		(polygon
			(pts
				(arc
					(start 319.51041 -394.50391)
					(mid 319.622659 -394.639357)
					(end 319.79108 -394.690092)
				)
				(arc
					(start 319.79108 -394.690092)
					(mid 320.006606 -394.600818)
					(end 320.09588 -394.385292)
				)
				(arc
					(start 320.09588 -394.385292)
					(mid 320.086046 -394.308239)
					(end 320.057018 -394.236194)
				)
				(arc
					(start 319.67805 -393.58951)
					(mid 319.259537 -393.417135)
					(end 319.130934 -393.85113)
				)
			)
		)
	)
	(zone
		(layer "In10.Cu")
		(hatch none 0.5)
		(connect_pads
			(clearance 0)
		)
		(min_thickness 0.25)
		(keepout
			(tracks not_allowed)
			(vias allowed)
			(pads allowed)
			(copperpour not_allowed)
			(footprints allowed)
		)
		(placement
			(enabled no)
			(sheetname "")
		)
		(fill
			(thermal_gap 0.5)
			(thermal_bridge_width 0.5)
			(island_removal_mode 0)
		)
		(polygon
			(pts
				(arc
					(start 318.14135 -435.160674)
					(mid 318.163668 -435.214556)
					(end 318.21755 -435.236874)
				)
				(arc
					(start 319.15735 -435.236874)
					(mid 319.211232 -435.214556)
					(end 319.23355 -435.160674)
				)
				(arc
					(start 319.23355 -432.61915)
					(mid 319.211232 -432.565268)
					(end 319.15735 -432.54295)
				)
				(arc
					(start 318.21755 -432.54295)
					(mid 318.163668 -432.565268)
					(end 318.14135 -432.61915)
				)
			)
		)
	)
	(zone
		(layer "In10.Cu")
		(hatch none 0.5)
		(connect_pads
			(clearance 0)
		)
		(min_thickness 0.25)
		(keepout
			(tracks not_allowed)
			(vias allowed)
			(pads allowed)
			(copperpour not_allowed)
			(footprints allowed)
		)
		(placement
			(enabled no)
			(sheetname "")
		)
		(fill
			(thermal_gap 0.5)
			(thermal_bridge_width 0.5)
			(island_removal_mode 0)
		)
		(polygon
			(pts
				(arc
					(start 139.24153 -436.160672)
					(mid 139.263848 -436.214554)
					(end 139.31773 -436.236872)
				)
				(arc
					(start 140.25753 -436.236872)
					(mid 140.311412 -436.214554)
					(end 140.33373 -436.160672)
				)
				(arc
					(start 140.33373 -433.619148)
					(mid 140.311412 -433.565266)
					(end 140.25753 -433.542948)
				)
				(arc
					(start 139.31773 -433.542948)
					(mid 139.263848 -433.565266)
					(end 139.24153 -433.619148)
				)
			)
		)
	)
	(zone
		(layer "In10.Cu")
		(hatch none 0.5)
		(connect_pads
			(clearance 0)
		)
		(min_thickness 0.25)
		(keepout
			(tracks not_allowed)
			(vias allowed)
			(pads allowed)
			(copperpour not_allowed)
			(footprints allowed)
		)
		(placement
			(enabled no)
			(sheetname "")
		)
		(fill
			(thermal_gap 0.5)
			(thermal_bridge_width 0.5)
			(island_removal_mode 0)
		)
		(polygon
			(pts
				(arc
					(start 343.141554 -435.160674)
					(mid 343.163872 -435.214556)
					(end 343.217754 -435.236874)
				)
				(arc
					(start 344.157554 -435.236874)
					(mid 344.211436 -435.214556)
					(end 344.233754 -435.160674)
				)
				(arc
					(start 344.233754 -432.61915)
					(mid 344.211436 -432.565268)
					(end 344.157554 -432.54295)
				)
				(arc
					(start 343.217754 -432.54295)
					(mid 343.163872 -432.565268)
					(end 343.141554 -432.61915)
				)
			)
		)
	)
	(zone
		(layer "In10.Cu")
		(hatch none 0.5)
		(connect_pads
			(clearance 0)
		)
		(min_thickness 0.25)
		(keepout
			(tracks not_allowed)
			(vias allowed)
			(pads allowed)
			(copperpour not_allowed)
			(footprints allowed)
		)
		(placement
			(enabled no)
			(sheetname "")
		)
		(fill
			(thermal_gap 0.5)
			(thermal_bridge_width 0.5)
			(island_removal_mode 0)
		)
		(polygon
			(pts
				(arc
					(start 316.141354 -436.160672)
					(mid 316.163672 -436.214554)
					(end 316.217554 -436.236872)
				)
				(arc
					(start 317.157354 -436.236872)
					(mid 317.211236 -436.214554)
					(end 317.233554 -436.160672)
				)
				(arc
					(start 317.233554 -433.619148)
					(mid 317.211236 -433.565266)
					(end 317.157354 -433.542948)
				)
				(arc
					(start 316.217554 -433.542948)
					(mid 316.163672 -433.565266)
					(end 316.141354 -433.619148)
				)
			)
		)
	)
	(zone
		(layer "In10.Cu")
		(hatch none 0.5)
		(connect_pads
			(clearance 0)
		)
		(min_thickness 0.25)
		(keepout
			(tracks not_allowed)
			(vias allowed)
			(pads allowed)
			(copperpour not_allowed)
			(footprints allowed)
		)
		(placement
			(enabled no)
			(sheetname "")
		)
		(fill
			(thermal_gap 0.5)
			(thermal_bridge_width 0.5)
			(island_removal_mode 0)
		)
		(polygon
			(pts
				(arc
					(start 333.141574 -436.160672)
					(mid 333.163892 -436.214554)
					(end 333.217774 -436.236872)
				)
				(arc
					(start 334.157574 -436.236872)
					(mid 334.211456 -436.214554)
					(end 334.233774 -436.160672)
				)
				(arc
					(start 334.233774 -433.619148)
					(mid 334.211456 -433.565266)
					(end 334.157574 -433.542948)
				)
				(arc
					(start 333.217774 -433.542948)
					(mid 333.163892 -433.565266)
					(end 333.141574 -433.619148)
				)
			)
		)
	)
	(zone
		(layer "In10.Cu")
		(hatch none 0.5)
		(connect_pads
			(clearance 0)
		)
		(min_thickness 0.25)
		(keepout
			(tracks not_allowed)
			(vias allowed)
			(pads allowed)
			(copperpour not_allowed)
			(footprints allowed)
		)
		(placement
			(enabled no)
			(sheetname "")
		)
		(fill
			(thermal_gap 0.5)
			(thermal_bridge_width 0.5)
			(island_removal_mode 0)
		)
		(polygon
			(pts
				(arc
					(start 319.53581 -394.551154)
					(mid 319.645781 -394.652208)
					(end 319.790572 -394.688822)
				)
				(arc
					(start 319.790572 -394.688822)
					(mid 320.006098 -394.599548)
					(end 320.095372 -394.384022)
				)
				(arc
					(start 320.095372 -394.384022)
					(mid 320.085035 -394.305283)
					(end 320.054732 -394.231876)
				)
				(arc
					(start 319.662302 -393.552934)
					(mid 319.549905 -393.431317)
					(end 319.390522 -393.38631)
				)
				(arc
					(start 319.390522 -393.38631)
					(mid 319.174996 -393.475584)
					(end 319.085722 -393.69111)
				)
				(arc
					(start 319.085722 -393.69111)
					(mid 319.0953 -393.767172)
					(end 319.123568 -393.83843)
				)
				(xy 319.520824 -394.525754) (xy 319.533016 -394.54709) (xy 319.535556 -394.551408)
			)
		)
	)
	(zone
		(layer "In10.Cu")
		(hatch none 0.5)
		(connect_pads
			(clearance 0)
		)
		(min_thickness 0.25)
		(keepout
			(tracks not_allowed)
			(vias allowed)
			(pads allowed)
			(copperpour not_allowed)
			(footprints allowed)
		)
		(placement
			(enabled no)
			(sheetname "")
		)
		(fill
			(thermal_gap 0.5)
			(thermal_bridge_width 0.5)
			(island_removal_mode 0)
		)
		(polygon
			(pts
				(arc
					(start 131.241546 -436.160672)
					(mid 131.263864 -436.214554)
					(end 131.317746 -436.236872)
				)
				(arc
					(start 132.257546 -436.236872)
					(mid 132.311428 -436.214554)
					(end 132.333746 -436.160672)
				)
				(arc
					(start 132.333746 -433.619148)
					(mid 132.311428 -433.565266)
					(end 132.257546 -433.542948)
				)
				(arc
					(start 131.317746 -433.542948)
					(mid 131.263864 -433.565266)
					(end 131.241546 -433.619148)
				)
			)
		)
	)
	(zone
		(layer "In10.Cu")
		(hatch none 0.5)
		(connect_pads
			(clearance 0)
		)
		(min_thickness 0.25)
		(keepout
			(tracks not_allowed)
			(vias allowed)
			(pads allowed)
			(copperpour not_allowed)
			(footprints allowed)
		)
		(placement
			(enabled no)
			(sheetname "")
		)
		(fill
			(thermal_gap 0.5)
			(thermal_bridge_width 0.5)
			(island_removal_mode 0)
		)
		(polygon
			(pts
				(arc
					(start 133.241542 -435.160674)
					(mid 133.26386 -435.214556)
					(end 133.317742 -435.236874)
				)
				(arc
					(start 134.257542 -435.236874)
					(mid 134.311424 -435.214556)
					(end 134.333742 -435.160674)
				)
				(arc
					(start 134.333742 -432.61915)
					(mid 134.311424 -432.565268)
					(end 134.257542 -432.54295)
				)
				(arc
					(start 133.317742 -432.54295)
					(mid 133.26386 -432.565268)
					(end 133.241542 -432.61915)
				)
			)
		)
	)
	(zone
		(layer "In10.Cu")
		(hatch none 0.5)
		(connect_pads
			(clearance 0)
		)
		(min_thickness 0.25)
		(keepout
			(tracks not_allowed)
			(vias allowed)
			(pads allowed)
			(copperpour not_allowed)
			(footprints allowed)
		)
		(placement
			(enabled no)
			(sheetname "")
		)
		(fill
			(thermal_gap 0.5)
			(thermal_bridge_width 0.5)
			(island_removal_mode 0)
		)
		(polygon
			(pts
				(arc
					(start 314.735718 -394.551154)
					(mid 314.845689 -394.652208)
					(end 314.99048 -394.688822)
				)
				(arc
					(start 314.99048 -394.688822)
					(mid 315.206006 -394.599548)
					(end 315.29528 -394.384022)
				)
				(arc
					(start 315.29528 -394.384022)
					(mid 315.284943 -394.305283)
					(end 315.25464 -394.231876)
				)
				(arc
					(start 314.86221 -393.552934)
					(mid 314.749813 -393.431317)
					(end 314.59043 -393.38631)
				)
				(arc
					(start 314.59043 -393.38631)
					(mid 314.374904 -393.475584)
					(end 314.28563 -393.69111)
				)
				(arc
					(start 314.28563 -393.69111)
					(mid 314.295208 -393.767172)
					(end 314.323476 -393.83843)
				)
				(xy 314.720732 -394.525754) (xy 314.732924 -394.54709) (xy 314.735464 -394.551408)
			)
		)
	)
	(zone
		(layer "In10.Cu")
		(hatch none 0.5)
		(connect_pads
			(clearance 0)
		)
		(min_thickness 0.25)
		(keepout
			(tracks not_allowed)
			(vias allowed)
			(pads allowed)
			(copperpour not_allowed)
			(footprints allowed)
		)
		(placement
			(enabled no)
			(sheetname "")
		)
		(fill
			(thermal_gap 0.5)
			(thermal_bridge_width 0.5)
			(island_removal_mode 0)
		)
		(polygon
			(pts
				(arc
					(start 381.241554 -435.160674)
					(mid 381.263872 -435.214556)
					(end 381.317754 -435.236874)
				)
				(arc
					(start 382.257554 -435.236874)
					(mid 382.311436 -435.214556)
					(end 382.333754 -435.160674)
				)
				(arc
					(start 382.333754 -432.61915)
					(mid 382.311436 -432.565268)
					(end 382.257554 -432.54295)
				)
				(arc
					(start 381.317754 -432.54295)
					(mid 381.263872 -432.565268)
					(end 381.241554 -432.61915)
				)
			)
		)
	)
	(zone
		(layer "In10.Cu")
		(hatch none 0.5)
		(connect_pads
			(clearance 0)
		)
		(min_thickness 0.25)
		(keepout
			(tracks not_allowed)
			(vias allowed)
			(pads allowed)
			(copperpour not_allowed)
			(footprints allowed)
		)
		(placement
			(enabled no)
			(sheetname "")
		)
		(fill
			(thermal_gap 0.5)
			(thermal_bridge_width 0.5)
			(island_removal_mode 0)
		)
		(polygon
			(pts
				(arc
					(start 395.241526 -436.160672)
					(mid 395.263844 -436.214554)
					(end 395.317726 -436.236872)
				)
				(arc
					(start 396.257526 -436.236872)
					(mid 396.311408 -436.214554)
					(end 396.333726 -436.160672)
				)
				(arc
					(start 396.333726 -433.619148)
					(mid 396.311408 -433.565266)
					(end 396.257526 -433.542948)
				)
				(arc
					(start 395.317726 -433.542948)
					(mid 395.263844 -433.565266)
					(end 395.241526 -433.619148)
				)
			)
		)
	)
	(zone
		(layer "In10.Cu")
		(hatch none 0.5)
		(connect_pads
			(clearance 0)
		)
		(min_thickness 0.25)
		(keepout
			(tracks not_allowed)
			(vias allowed)
			(pads allowed)
			(copperpour not_allowed)
			(footprints allowed)
		)
		(placement
			(enabled no)
			(sheetname "")
		)
		(fill
			(thermal_gap 0.5)
			(thermal_bridge_width 0.5)
			(island_removal_mode 0)
		)
		(polygon
			(pts
				(arc
					(start 324.141338 -436.160672)
					(mid 324.163656 -436.214554)
					(end 324.217538 -436.236872)
				)
				(arc
					(start 325.157338 -436.236872)
					(mid 325.21122 -436.214554)
					(end 325.233538 -436.160672)
				)
				(arc
					(start 325.233538 -433.619148)
					(mid 325.21122 -433.565266)
					(end 325.157338 -433.542948)
				)
				(arc
					(start 324.217538 -433.542948)
					(mid 324.163656 -433.565266)
					(end 324.141338 -433.619148)
				)
			)
		)
	)
	(zone
		(layer "In10.Cu")
		(hatch none 0.5)
		(connect_pads
			(clearance 0)
		)
		(min_thickness 0.25)
		(keepout
			(tracks not_allowed)
			(vias allowed)
			(pads allowed)
			(copperpour not_allowed)
			(footprints allowed)
		)
		(placement
			(enabled no)
			(sheetname "")
		)
		(fill
			(thermal_gap 0.5)
			(thermal_bridge_width 0.5)
			(island_removal_mode 0)
		)
		(polygon
			(pts
				(arc
					(start 391.241534 -436.160672)
					(mid 391.263852 -436.214554)
					(end 391.317734 -436.236872)
				)
				(arc
					(start 392.257534 -436.236872)
					(mid 392.311416 -436.214554)
					(end 392.333734 -436.160672)
				)
				(arc
					(start 392.333734 -433.619148)
					(mid 392.311416 -433.565266)
					(end 392.257534 -433.542948)
				)
				(arc
					(start 391.317734 -433.542948)
					(mid 391.263852 -433.565266)
					(end 391.241534 -433.619148)
				)
			)
		)
	)
	(zone
		(layer "In10.Cu")
		(hatch none 0.5)
		(connect_pads
			(clearance 0)
		)
		(min_thickness 0.25)
		(keepout
			(tracks not_allowed)
			(vias allowed)
			(pads allowed)
			(copperpour not_allowed)
			(footprints allowed)
		)
		(placement
			(enabled no)
			(sheetname "")
		)
		(fill
			(thermal_gap 0.5)
			(thermal_bridge_width 0.5)
			(island_removal_mode 0)
		)
		(polygon
			(pts
				(arc
					(start 314.141358 -435.160674)
					(mid 314.163676 -435.214556)
					(end 314.217558 -435.236874)
				)
				(arc
					(start 315.157358 -435.236874)
					(mid 315.21124 -435.214556)
					(end 315.233558 -435.160674)
				)
				(arc
					(start 315.233558 -432.61915)
					(mid 315.21124 -432.565268)
					(end 315.157358 -432.54295)
				)
				(arc
					(start 314.217558 -432.54295)
					(mid 314.163676 -432.565268)
					(end 314.141358 -432.61915)
				)
			)
		)
	)
	(zone
		(layer "In10.Cu")
		(hatch none 0.5)
		(connect_pads
			(clearance 0)
		)
		(min_thickness 0.25)
		(keepout
			(tracks not_allowed)
			(vias allowed)
			(pads allowed)
			(copperpour not_allowed)
			(footprints allowed)
		)
		(placement
			(enabled no)
			(sheetname "")
		)
		(fill
			(thermal_gap 0.5)
			(thermal_bridge_width 0.5)
			(island_removal_mode 0)
		)
		(polygon
			(pts
				(arc
					(start 125.241558 -435.160674)
					(mid 125.263876 -435.214556)
					(end 125.317758 -435.236874)
				)
				(arc
					(start 126.257558 -435.236874)
					(mid 126.31144 -435.214556)
					(end 126.333758 -435.160674)
				)
				(arc
					(start 126.333758 -432.61915)
					(mid 126.31144 -432.565268)
					(end 126.257558 -432.54295)
				)
				(arc
					(start 125.317758 -432.54295)
					(mid 125.263876 -432.565268)
					(end 125.241558 -432.61915)
				)
			)
		)
	)
	(zone
		(layer "In10.Cu")
		(hatch none 0.5)
		(connect_pads
			(clearance 0)
		)
		(min_thickness 0.25)
		(keepout
			(tracks not_allowed)
			(vias allowed)
			(pads allowed)
			(copperpour not_allowed)
			(footprints allowed)
		)
		(placement
			(enabled no)
			(sheetname "")
		)
		(fill
			(thermal_gap 0.5)
			(thermal_bridge_width 0.5)
			(island_removal_mode 0)
		)
		(polygon
			(pts
				(arc
					(start 335.14157 -435.160674)
					(mid 335.163888 -435.214556)
					(end 335.21777 -435.236874)
				)
				(arc
					(start 336.15757 -435.236874)
					(mid 336.211452 -435.214556)
					(end 336.23377 -435.160674)
				)
				(arc
					(start 336.23377 -432.61915)
					(mid 336.211452 -432.565268)
					(end 336.15757 -432.54295)
				)
				(arc
					(start 335.21777 -432.54295)
					(mid 335.163888 -432.565268)
					(end 335.14157 -432.61915)
				)
			)
		)
	)
	(zone
		(layer "In10.Cu")
		(hatch none 0.5)
		(connect_pads
			(clearance 0)
		)
		(min_thickness 0.25)
		(keepout
			(tracks not_allowed)
			(vias allowed)
			(pads allowed)
			(copperpour not_allowed)
			(footprints allowed)
		)
		(placement
			(enabled no)
			(sheetname "")
		)
		(fill
			(thermal_gap 0.5)
			(thermal_bridge_width 0.5)
			(island_removal_mode 0)
		)
		(polygon
			(pts
				(arc
					(start 326.141334 -435.160674)
					(mid 326.163652 -435.214556)
					(end 326.217534 -435.236874)
				)
				(arc
					(start 327.157334 -435.236874)
					(mid 327.211216 -435.214556)
					(end 327.233534 -435.160674)
				)
				(arc
					(start 327.233534 -432.61915)
					(mid 327.211216 -432.565268)
					(end 327.157334 -432.54295)
				)
				(arc
					(start 326.217534 -432.54295)
					(mid 326.163652 -432.565268)
					(end 326.141334 -432.61915)
				)
			)
		)
	)
	(zone
		(layer "In10.Cu")
		(hatch none 0.5)
		(connect_pads
			(clearance 0)
		)
		(min_thickness 0.25)
		(keepout
			(tracks not_allowed)
			(vias allowed)
			(pads allowed)
			(copperpour not_allowed)
			(footprints allowed)
		)
		(placement
			(enabled no)
			(sheetname "")
		)
		(fill
			(thermal_gap 0.5)
			(thermal_bridge_width 0.5)
			(island_removal_mode 0)
		)
		(polygon
			(pts
				(arc
					(start 339.141562 -435.160674)
					(mid 339.16388 -435.214556)
					(end 339.217762 -435.236874)
				)
				(arc
					(start 340.157562 -435.236874)
					(mid 340.211444 -435.214556)
					(end 340.233762 -435.160674)
				)
				(arc
					(start 340.233762 -432.61915)
					(mid 340.211444 -432.565268)
					(end 340.157562 -432.54295)
				)
				(arc
					(start 339.217762 -432.54295)
					(mid 339.16388 -432.565268)
					(end 339.141562 -432.61915)
				)
			)
		)
	)
	(zone
		(layer "In10.Cu")
		(hatch none 0.5)
		(connect_pads
			(clearance 0)
		)
		(min_thickness 0.25)
		(keepout
			(tracks not_allowed)
			(vias allowed)
			(pads allowed)
			(copperpour not_allowed)
			(footprints allowed)
		)
		(placement
			(enabled no)
			(sheetname "")
		)
		(fill
			(thermal_gap 0.5)
			(thermal_bridge_width 0.5)
			(island_removal_mode 0)
		)
		(polygon
			(pts
				(arc
					(start 383.24155 -436.160672)
					(mid 383.263868 -436.214554)
					(end 383.31775 -436.236872)
				)
				(arc
					(start 384.25755 -436.236872)
					(mid 384.311432 -436.214554)
					(end 384.33375 -436.160672)
				)
				(arc
					(start 384.33375 -433.619148)
					(mid 384.311432 -433.565266)
					(end 384.25755 -433.542948)
				)
				(arc
					(start 383.31775 -433.542948)
					(mid 383.263868 -433.565266)
					(end 383.24155 -433.619148)
				)
			)
		)
	)
	(zone
		(layer "In10.Cu")
		(hatch none 0.5)
		(connect_pads
			(clearance 0)
		)
		(min_thickness 0.25)
		(keepout
			(tracks not_allowed)
			(vias allowed)
			(pads allowed)
			(copperpour not_allowed)
			(footprints allowed)
		)
		(placement
			(enabled no)
			(sheetname "")
		)
		(fill
			(thermal_gap 0.5)
			(thermal_bridge_width 0.5)
			(island_removal_mode 0)
		)
		(polygon
			(pts
				(arc
					(start 321.935602 -394.551154)
					(mid 322.045573 -394.652208)
					(end 322.190364 -394.688822)
				)
				(arc
					(start 322.190364 -394.688822)
					(mid 322.40589 -394.599548)
					(end 322.495164 -394.384022)
				)
				(arc
					(start 322.495164 -394.384022)
					(mid 322.484827 -394.305283)
					(end 322.454524 -394.231876)
				)
				(arc
					(start 322.062094 -393.552934)
					(mid 321.949697 -393.431317)
					(end 321.790314 -393.38631)
				)
				(arc
					(start 321.790314 -393.38631)
					(mid 321.574788 -393.475584)
					(end 321.485514 -393.69111)
				)
				(arc
					(start 321.485514 -393.69111)
					(mid 321.495092 -393.767172)
					(end 321.52336 -393.83843)
				)
				(xy 321.920616 -394.525754) (xy 321.932808 -394.54709) (xy 321.935348 -394.551408)
			)
		)
	)
	(zone
		(layer "In10.Cu")
		(hatch none 0.5)
		(connect_pads
			(clearance 0)
		)
		(min_thickness 0.25)
		(keepout
			(tracks not_allowed)
			(vias allowed)
			(pads allowed)
			(copperpour not_allowed)
			(footprints allowed)
		)
		(placement
			(enabled no)
			(sheetname "")
		)
		(fill
			(thermal_gap 0.5)
			(thermal_bridge_width 0.5)
			(island_removal_mode 0)
		)
		(polygon
			(pts
				(arc
					(start 345.14155 -436.160672)
					(mid 345.163868 -436.214554)
					(end 345.21775 -436.236872)
				)
				(arc
					(start 346.15755 -436.236872)
					(mid 346.211432 -436.214554)
					(end 346.23375 -436.160672)
				)
				(arc
					(start 346.23375 -433.619148)
					(mid 346.211432 -433.565266)
					(end 346.15755 -433.542948)
				)
				(arc
					(start 345.21775 -433.542948)
					(mid 345.163868 -433.565266)
					(end 345.14155 -433.619148)
				)
			)
		)
	)
	(zone
		(layer "In10.Cu")
		(hatch none 0.5)
		(connect_pads
			(clearance 0)
		)
		(min_thickness 0.25)
		(keepout
			(tracks not_allowed)
			(vias allowed)
			(pads allowed)
			(copperpour not_allowed)
			(footprints allowed)
		)
		(placement
			(enabled no)
			(sheetname "")
		)
		(fill
			(thermal_gap 0.5)
			(thermal_bridge_width 0.5)
			(island_removal_mode 0)
		)
		(polygon
			(pts
				(arc
					(start 129.24155 -435.160674)
					(mid 129.263868 -435.214556)
					(end 129.31775 -435.236874)
				)
				(arc
					(start 130.25755 -435.236874)
					(mid 130.311432 -435.214556)
					(end 130.33375 -435.160674)
				)
				(arc
					(start 130.33375 -432.61915)
					(mid 130.311432 -432.565268)
					(end 130.25755 -432.54295)
				)
				(arc
					(start 129.31775 -432.54295)
					(mid 129.263868 -432.565268)
					(end 129.24155 -432.61915)
				)
			)
		)
	)
	(zone
		(layer "In10.Cu")
		(hatch none 0.5)
		(connect_pads
			(clearance 0)
		)
		(min_thickness 0.25)
		(keepout
			(tracks not_allowed)
			(vias allowed)
			(pads allowed)
			(copperpour not_allowed)
			(footprints allowed)
		)
		(placement
			(enabled no)
			(sheetname "")
		)
		(fill
			(thermal_gap 0.5)
			(thermal_bridge_width 0.5)
			(island_removal_mode 0)
		)
		(polygon
			(pts
				(arc
					(start 341.141558 -436.160672)
					(mid 341.163876 -436.214554)
					(end 341.217758 -436.236872)
				)
				(arc
					(start 342.157558 -436.236872)
					(mid 342.21144 -436.214554)
					(end 342.233758 -436.160672)
				)
				(arc
					(start 342.233758 -433.619148)
					(mid 342.21144 -433.565266)
					(end 342.157558 -433.542948)
				)
				(arc
					(start 341.217758 -433.542948)
					(mid 341.163876 -433.565266)
					(end 341.141558 -433.619148)
				)
			)
		)
	)
	(zone
		(layer "In10.Cu")
		(hatch none 0.5)
		(connect_pads
			(clearance 0)
		)
		(min_thickness 0.25)
		(keepout
			(tracks not_allowed)
			(vias allowed)
			(pads allowed)
			(copperpour not_allowed)
			(footprints allowed)
		)
		(placement
			(enabled no)
			(sheetname "")
		)
		(fill
			(thermal_gap 0.5)
			(thermal_bridge_width 0.5)
			(island_removal_mode 0)
		)
		(polygon
			(pts
				(arc
					(start 315.935614 -394.551154)
					(mid 316.045585 -394.652208)
					(end 316.190376 -394.688822)
				)
				(arc
					(start 316.190376 -394.688822)
					(mid 316.405902 -394.599548)
					(end 316.495176 -394.384022)
				)
				(arc
					(start 316.495176 -394.384022)
					(mid 316.484839 -394.305283)
					(end 316.454536 -394.231876)
				)
				(arc
					(start 316.062106 -393.552934)
					(mid 315.949709 -393.431317)
					(end 315.790326 -393.38631)
				)
				(arc
					(start 315.790326 -393.38631)
					(mid 315.5748 -393.475584)
					(end 315.485526 -393.69111)
				)
				(arc
					(start 315.485526 -393.69111)
					(mid 315.495104 -393.767172)
					(end 315.523372 -393.83843)
				)
				(xy 315.920628 -394.525754) (xy 315.93282 -394.54709) (xy 315.93536 -394.551408)
			)
		)
	)
	(zone
		(layer "In10.Cu")
		(hatch none 0.5)
		(connect_pads
			(clearance 0)
		)
		(min_thickness 0.25)
		(keepout
			(tracks not_allowed)
			(vias allowed)
			(pads allowed)
			(copperpour not_allowed)
			(footprints allowed)
		)
		(placement
			(enabled no)
			(sheetname "")
		)
		(fill
			(thermal_gap 0.5)
			(thermal_bridge_width 0.5)
			(island_removal_mode 0)
		)
		(polygon
			(pts
				(arc
					(start 393.24153 -435.160674)
					(mid 393.263848 -435.214556)
					(end 393.31773 -435.236874)
				)
				(arc
					(start 394.25753 -435.236874)
					(mid 394.311412 -435.214556)
					(end 394.33373 -435.160674)
				)
				(arc
					(start 394.33373 -432.61915)
					(mid 394.311412 -432.565268)
					(end 394.25753 -432.54295)
				)
				(arc
					(start 393.31773 -432.54295)
					(mid 393.263848 -432.565268)
					(end 393.24153 -432.61915)
				)
			)
		)
	)
	(zone
		(layer "In10.Cu")
		(hatch none 0.5)
		(connect_pads
			(clearance 0)
		)
		(min_thickness 0.25)
		(keepout
			(tracks not_allowed)
			(vias allowed)
			(pads allowed)
			(copperpour not_allowed)
			(footprints allowed)
		)
		(placement
			(enabled no)
			(sheetname "")
		)
		(fill
			(thermal_gap 0.5)
			(thermal_bridge_width 0.5)
			(island_removal_mode 0)
		)
		(polygon
			(pts
				(arc
					(start 331.141578 -435.160674)
					(mid 331.163896 -435.214556)
					(end 331.217778 -435.236874)
				)
				(arc
					(start 332.157578 -435.236874)
					(mid 332.21146 -435.214556)
					(end 332.233778 -435.160674)
				)
				(arc
					(start 332.233778 -432.61915)
					(mid 332.21146 -432.565268)
					(end 332.157578 -432.54295)
				)
				(arc
					(start 331.217778 -432.54295)
					(mid 331.163896 -432.565268)
					(end 331.141578 -432.61915)
				)
			)
		)
	)
	(zone
		(layer "In10.Cu")
		(hatch none 0.5)
		(connect_pads
			(clearance 0)
		)
		(min_thickness 0.25)
		(keepout
			(tracks not_allowed)
			(vias allowed)
			(pads allowed)
			(copperpour not_allowed)
			(footprints allowed)
		)
		(placement
			(enabled no)
			(sheetname "")
		)
		(fill
			(thermal_gap 0.5)
			(thermal_bridge_width 0.5)
			(island_removal_mode 0)
		)
		(polygon
			(pts
				(arc
					(start 137.241534 -435.160674)
					(mid 137.263852 -435.214556)
					(end 137.317734 -435.236874)
				)
				(arc
					(start 138.257534 -435.236874)
					(mid 138.311416 -435.214556)
					(end 138.333734 -435.160674)
				)
				(arc
					(start 138.333734 -432.61915)
					(mid 138.311416 -432.565268)
					(end 138.257534 -432.54295)
				)
				(arc
					(start 137.317734 -432.54295)
					(mid 137.263852 -432.565268)
					(end 137.241534 -432.61915)
				)
			)
		)
	)
	(zone
		(layer "In10.Cu")
		(hatch none 0.5)
		(connect_pads
			(clearance 0)
		)
		(min_thickness 0.25)
		(keepout
			(tracks not_allowed)
			(vias allowed)
			(pads allowed)
			(copperpour not_allowed)
			(footprints allowed)
		)
		(placement
			(enabled no)
			(sheetname "")
		)
		(fill
			(thermal_gap 0.5)
			(thermal_bridge_width 0.5)
			(island_removal_mode 0)
		)
		(polygon
			(pts
				(arc
					(start 385.241546 -435.160674)
					(mid 385.263864 -435.214556)
					(end 385.317746 -435.236874)
				)
				(arc
					(start 386.257546 -435.236874)
					(mid 386.311428 -435.214556)
					(end 386.333746 -435.160674)
				)
				(arc
					(start 386.333746 -432.61915)
					(mid 386.311428 -432.565268)
					(end 386.257546 -432.54295)
				)
				(arc
					(start 385.317746 -432.54295)
					(mid 385.263864 -432.565268)
					(end 385.241546 -432.61915)
				)
			)
		)
	)
	(zone
		(layer "In10.Cu")
		(hatch none 0.5)
		(connect_pads
			(clearance 0)
		)
		(min_thickness 0.25)
		(keepout
			(tracks not_allowed)
			(vias allowed)
			(pads allowed)
			(copperpour not_allowed)
			(footprints allowed)
		)
		(placement
			(enabled no)
			(sheetname "")
		)
		(fill
			(thermal_gap 0.5)
			(thermal_bridge_width 0.5)
			(island_removal_mode 0)
		)
		(polygon
			(pts
				(arc
					(start 389.241538 -435.160674)
					(mid 389.263856 -435.214556)
					(end 389.317738 -435.236874)
				)
				(arc
					(start 390.257538 -435.236874)
					(mid 390.31142 -435.214556)
					(end 390.333738 -435.160674)
				)
				(arc
					(start 390.333738 -432.61915)
					(mid 390.31142 -432.565268)
					(end 390.257538 -432.54295)
				)
				(arc
					(start 389.317738 -432.54295)
					(mid 389.263856 -432.565268)
					(end 389.241538 -432.61915)
				)
			)
		)
	)
	(zone
		(layer "In10.Cu")
		(hatch none 0.5)
		(connect_pads
			(clearance 0)
		)
		(min_thickness 0.25)
		(keepout
			(tracks not_allowed)
			(vias allowed)
			(pads allowed)
			(copperpour not_allowed)
			(footprints allowed)
		)
		(placement
			(enabled no)
			(sheetname "")
		)
		(fill
			(thermal_gap 0.5)
			(thermal_bridge_width 0.5)
			(island_removal_mode 0)
		)
		(polygon
			(pts
				(arc
					(start 318.33566 -394.551154)
					(mid 318.445631 -394.652208)
					(end 318.590422 -394.688822)
				)
				(arc
					(start 318.590422 -394.688822)
					(mid 318.805948 -394.599548)
					(end 318.895222 -394.384022)
				)
				(arc
					(start 318.895222 -394.384022)
					(mid 318.884885 -394.305283)
					(end 318.854582 -394.231876)
				)
				(arc
					(start 318.462152 -393.552934)
					(mid 318.349755 -393.431317)
					(end 318.190372 -393.38631)
				)
				(arc
					(start 318.190372 -393.38631)
					(mid 317.974846 -393.475584)
					(end 317.885572 -393.69111)
				)
				(arc
					(start 317.885572 -393.69111)
					(mid 317.89515 -393.767172)
					(end 317.923418 -393.83843)
				)
				(xy 318.320674 -394.525754) (xy 318.332866 -394.54709) (xy 318.335406 -394.551408)
			)
		)
	)
	(zone
		(layer "In10.Cu")
		(hatch none 0.5)
		(connect_pads
			(clearance 0)
		)
		(min_thickness 0.25)
		(keepout
			(tracks not_allowed)
			(vias allowed)
			(pads allowed)
			(copperpour not_allowed)
			(footprints allowed)
		)
		(placement
			(enabled no)
			(sheetname "")
		)
		(fill
			(thermal_gap 0.5)
			(thermal_bridge_width 0.5)
			(island_removal_mode 0)
		)
		(polygon
			(pts
				(arc
					(start 387.241542 -436.160672)
					(mid 387.26386 -436.214554)
					(end 387.317742 -436.236872)
				)
				(arc
					(start 388.257542 -436.236872)
					(mid 388.311424 -436.214554)
					(end 388.333742 -436.160672)
				)
				(arc
					(start 388.333742 -433.619148)
					(mid 388.311424 -433.565266)
					(end 388.257542 -433.542948)
				)
				(arc
					(start 387.317742 -433.542948)
					(mid 387.26386 -433.565266)
					(end 387.241542 -433.619148)
				)
			)
		)
	)
	(zone
		(layer "In10.Cu")
		(hatch none 0.5)
		(connect_pads
			(clearance 0)
		)
		(min_thickness 0.25)
		(keepout
			(tracks not_allowed)
			(vias allowed)
			(pads allowed)
			(copperpour not_allowed)
			(footprints allowed)
		)
		(placement
			(enabled no)
			(sheetname "")
		)
		(fill
			(thermal_gap 0.5)
			(thermal_bridge_width 0.5)
			(island_removal_mode 0)
		)
		(polygon
			(pts
				(arc
					(start 320.735706 -394.551154)
					(mid 320.845677 -394.652208)
					(end 320.990468 -394.688822)
				)
				(arc
					(start 320.990468 -394.688822)
					(mid 321.205994 -394.599548)
					(end 321.295268 -394.384022)
				)
				(arc
					(start 321.295268 -394.384022)
					(mid 321.284931 -394.305283)
					(end 321.254628 -394.231876)
				)
				(arc
					(start 320.862198 -393.552934)
					(mid 320.749801 -393.431317)
					(end 320.590418 -393.38631)
				)
				(arc
					(start 320.590418 -393.38631)
					(mid 320.374892 -393.475584)
					(end 320.285618 -393.69111)
				)
				(arc
					(start 320.285618 -393.69111)
					(mid 320.295196 -393.767172)
					(end 320.323464 -393.83843)
				)
				(xy 320.72072 -394.525754) (xy 320.732912 -394.54709) (xy 320.735452 -394.551408)
			)
		)
	)
	(zone
		(layer "In10.Cu")
		(hatch none 0.5)
		(connect_pads
			(clearance 0)
		)
		(min_thickness 0.25)
		(keepout
			(tracks not_allowed)
			(vias allowed)
			(pads allowed)
			(copperpour not_allowed)
			(footprints allowed)
		)
		(placement
			(enabled no)
			(sheetname "")
		)
		(fill
			(thermal_gap 0.5)
			(thermal_bridge_width 0.5)
			(island_removal_mode 0)
		)
		(polygon
			(pts
				(arc
					(start 320.141346 -436.160672)
					(mid 320.163664 -436.214554)
					(end 320.217546 -436.236872)
				)
				(arc
					(start 321.157346 -436.236872)
					(mid 321.211228 -436.214554)
					(end 321.233546 -436.160672)
				)
				(arc
					(start 321.233546 -433.619148)
					(mid 321.211228 -433.565266)
					(end 321.157346 -433.542948)
				)
				(arc
					(start 320.217546 -433.542948)
					(mid 320.163664 -433.565266)
					(end 320.141346 -433.619148)
				)
			)
		)
	)
	(zone
		(layer "In10.Cu")
		(hatch none 0.5)
		(connect_pads
			(clearance 0)
		)
		(min_thickness 0.25)
		(keepout
			(tracks not_allowed)
			(vias allowed)
			(pads allowed)
			(copperpour not_allowed)
			(footprints allowed)
		)
		(placement
			(enabled no)
			(sheetname "")
		)
		(fill
			(thermal_gap 0.5)
			(thermal_bridge_width 0.5)
			(island_removal_mode 0)
		)
		(polygon
			(pts
				(arc
					(start 127.241554 -436.160672)
					(mid 127.263872 -436.214554)
					(end 127.317754 -436.236872)
				)
				(arc
					(start 128.257554 -436.236872)
					(mid 128.311436 -436.214554)
					(end 128.333754 -436.160672)
				)
				(arc
					(start 128.333754 -433.619148)
					(mid 128.311436 -433.565266)
					(end 128.257554 -433.542948)
				)
				(arc
					(start 127.317754 -433.542948)
					(mid 127.263872 -433.565266)
					(end 127.241554 -433.619148)
				)
			)
		)
	)
	(zone
		(layer "In10.Cu")
		(hatch none 0.5)
		(connect_pads
			(clearance 0)
		)
		(min_thickness 0.25)
		(keepout
			(tracks not_allowed)
			(vias allowed)
			(pads allowed)
			(copperpour not_allowed)
			(footprints allowed)
		)
		(placement
			(enabled no)
			(sheetname "")
		)
		(fill
			(thermal_gap 0.5)
			(thermal_bridge_width 0.5)
			(island_removal_mode 0)
		)
		(polygon
			(pts
				(arc
					(start 328.14133 -436.160672)
					(mid 328.163648 -436.214554)
					(end 328.21753 -436.236872)
				)
				(arc
					(start 329.15733 -436.236872)
					(mid 329.211212 -436.214554)
					(end 329.23353 -436.160672)
				)
				(arc
					(start 329.23353 -433.619148)
					(mid 329.211212 -433.565266)
					(end 329.15733 -433.542948)
				)
				(arc
					(start 328.21753 -433.542948)
					(mid 328.163648 -433.565266)
					(end 328.14133 -433.619148)
				)
			)
		)
	)
	(zone
		(layer "In10.Cu")
		(hatch none 0.5)
		(connect_pads
			(clearance 0)
		)
		(min_thickness 0.25)
		(keepout
			(tracks not_allowed)
			(vias allowed)
			(pads allowed)
			(copperpour not_allowed)
			(footprints allowed)
		)
		(placement
			(enabled no)
			(sheetname "")
		)
		(fill
			(thermal_gap 0.5)
			(thermal_bridge_width 0.5)
			(island_removal_mode 0)
		)
		(polygon
			(pts
				(arc
					(start 317.135764 -394.551154)
					(mid 317.245735 -394.652208)
					(end 317.390526 -394.688822)
				)
				(arc
					(start 317.390526 -394.688822)
					(mid 317.606052 -394.599548)
					(end 317.695326 -394.384022)
				)
				(arc
					(start 317.695326 -394.384022)
					(mid 317.684989 -394.305283)
					(end 317.654686 -394.231876)
				)
				(arc
					(start 317.262256 -393.552934)
					(mid 317.149859 -393.431317)
					(end 316.990476 -393.38631)
				)
				(arc
					(start 316.990476 -393.38631)
					(mid 316.77495 -393.475584)
					(end 316.685676 -393.69111)
				)
				(arc
					(start 316.685676 -393.69111)
					(mid 316.695254 -393.767172)
					(end 316.723522 -393.83843)
				)
				(xy 317.120778 -394.525754) (xy 317.13297 -394.54709) (xy 317.13551 -394.551408)
			)
		)
	)
	(zone
		(layer "In10.Cu")
		(hatch none 0.5)
		(connect_pads
			(clearance 0)
		)
		(min_thickness 0.25)
		(keepout
			(tracks not_allowed)
			(vias allowed)
			(pads allowed)
			(copperpour not_allowed)
			(footprints allowed)
		)
		(placement
			(enabled no)
			(sheetname "")
		)
		(fill
			(thermal_gap 0.5)
			(thermal_bridge_width 0.5)
			(island_removal_mode 0)
		)
		(polygon
			(pts
				(arc
					(start 135.241538 -436.160672)
					(mid 135.263856 -436.214554)
					(end 135.317738 -436.236872)
				)
				(arc
					(start 136.257538 -436.236872)
					(mid 136.31142 -436.214554)
					(end 136.333738 -436.160672)
				)
				(arc
					(start 136.333738 -433.619148)
					(mid 136.31142 -433.565266)
					(end 136.257538 -433.542948)
				)
				(arc
					(start 135.317738 -433.542948)
					(mid 135.263856 -433.565266)
					(end 135.241538 -433.619148)
				)
			)
		)
	)
	(zone
		(layer "In10.Cu")
		(hatch none 0.5)
		(connect_pads
			(clearance 0)
		)
		(min_thickness 0.25)
		(keepout
			(tracks not_allowed)
			(vias allowed)
			(pads allowed)
			(copperpour not_allowed)
			(footprints allowed)
		)
		(placement
			(enabled no)
			(sheetname "")
		)
		(fill
			(thermal_gap 0.5)
			(thermal_bridge_width 0.5)
			(island_removal_mode 0)
		)
		(polygon
			(pts
				(arc
					(start 322.141342 -435.160674)
					(mid 322.16366 -435.214556)
					(end 322.217542 -435.236874)
				)
				(arc
					(start 323.157342 -435.236874)
					(mid 323.211224 -435.214556)
					(end 323.233542 -435.160674)
				)
				(arc
					(start 323.233542 -432.61915)
					(mid 323.211224 -432.565268)
					(end 323.157342 -432.54295)
				)
				(arc
					(start 322.217542 -432.54295)
					(mid 322.16366 -432.565268)
					(end 322.141342 -432.61915)
				)
			)
		)
	)
	(zone
		(layer "In10.Cu")
		(hatch none 0.5)
		(connect_pads
			(clearance 0)
		)
		(min_thickness 0.25)
		(keepout
			(tracks not_allowed)
			(vias allowed)
			(pads allowed)
			(copperpour not_allowed)
			(footprints allowed)
		)
		(placement
			(enabled no)
			(sheetname "")
		)
		(fill
			(thermal_gap 0.5)
			(thermal_bridge_width 0.5)
			(island_removal_mode 0)
		)
		(polygon
			(pts
				(arc
					(start 337.141566 -436.160672)
					(mid 337.163884 -436.214554)
					(end 337.217766 -436.236872)
				)
				(arc
					(start 338.157566 -436.236872)
					(mid 338.211448 -436.214554)
					(end 338.233766 -436.160672)
				)
				(arc
					(start 338.233766 -433.619148)
					(mid 338.211448 -433.565266)
					(end 338.157566 -433.542948)
				)
				(arc
					(start 337.217766 -433.542948)
					(mid 337.163884 -433.565266)
					(end 337.141566 -433.619148)
				)
			)
		)
	)
	(zone
		(layers "In10.Cu" "In12.Cu")
		(hatch none 0.5)
		(connect_pads
			(clearance 0)
		)
		(min_thickness 0.25)
		(keepout
			(tracks not_allowed)
			(vias allowed)
			(pads allowed)
			(copperpour not_allowed)
			(footprints allowed)
		)
		(placement
			(enabled no)
			(sheetname "")
		)
		(fill yes
			(thermal_gap 0.5)
			(thermal_bridge_width 0.5)
			(island_removal_mode 0)
		)
		(polygon
			(pts
				(arc
					(start 408.242008 -432.560476)
					(mid 408.264326 -432.614358)
					(end 408.318208 -432.636676)
				)
				(arc
					(start 409.258008 -432.636676)
					(mid 409.31189 -432.614358)
					(end 409.334208 -432.560476)
				)
				(arc
					(start 409.334208 -430.018952)
					(mid 409.31189 -429.96507)
					(end 409.258008 -429.942752)
				)
				(arc
					(start 408.318208 -429.942752)
					(mid 408.264326 -429.96507)
					(end 408.242008 -430.018952)
				)
				(arc
					(start 408.242008 -430.746408)
					(mid 408.244007 -430.763749)
					(end 408.249882 -430.78019)
				)
				(arc
					(start 408.483308 -431.25644)
					(mid 408.491091 -431.289968)
					(end 408.483308 -431.323496)
				)
				(arc
					(start 408.249882 -431.799746)
					(mid 408.243987 -431.816182)
					(end 408.242008 -431.833528)
				)
			)
		)
	)
	(zone
		(layers "In10.Cu" "In12.Cu")
		(hatch none 0.5)
		(connect_pads
			(clearance 0)
		)
		(min_thickness 0.25)
		(keepout
			(tracks not_allowed)
			(vias allowed)
			(pads allowed)
			(copperpour not_allowed)
			(footprints allowed)
		)
		(placement
			(enabled no)
			(sheetname "")
		)
		(fill yes
			(thermal_gap 0.5)
			(thermal_bridge_width 0.5)
			(island_removal_mode 0)
		)
		(polygon
			(pts
				(arc
					(start 326.141588 -431.560478)
					(mid 326.163906 -431.61436)
					(end 326.217788 -431.636678)
				)
				(arc
					(start 327.157588 -431.636678)
					(mid 327.21147 -431.61436)
					(end 327.233788 -431.560478)
				)
				(arc
					(start 327.233788 -429.018954)
					(mid 327.21147 -428.965072)
					(end 327.157588 -428.942754)
				)
				(arc
					(start 326.217788 -428.942754)
					(mid 326.163906 -428.965072)
					(end 326.141588 -429.018954)
				)
				(arc
					(start 326.141588 -429.74641)
					(mid 326.143587 -429.763751)
					(end 326.149462 -429.780192)
				)
				(arc
					(start 326.382888 -430.256442)
					(mid 326.390671 -430.28997)
					(end 326.382888 -430.323498)
				)
				(arc
					(start 326.149462 -430.799748)
					(mid 326.143567 -430.816184)
					(end 326.141588 -430.83353)
				)
			)
		)
	)
	(zone
		(layers "In10.Cu" "In12.Cu")
		(hatch none 0.5)
		(connect_pads
			(clearance 0)
		)
		(min_thickness 0.25)
		(keepout
			(tracks not_allowed)
			(vias allowed)
			(pads allowed)
			(copperpour not_allowed)
			(footprints allowed)
		)
		(placement
			(enabled no)
			(sheetname "")
		)
		(fill yes
			(thermal_gap 0.5)
			(thermal_bridge_width 0.5)
			(island_removal_mode 0)
		)
		(polygon
			(pts
				(arc
					(start 150.242016 -431.560478)
					(mid 150.264334 -431.61436)
					(end 150.318216 -431.636678)
				)
				(arc
					(start 151.258016 -431.636678)
					(mid 151.311898 -431.61436)
					(end 151.334216 -431.560478)
				)
				(arc
					(start 151.334216 -429.018954)
					(mid 151.311898 -428.965072)
					(end 151.258016 -428.942754)
				)
				(arc
					(start 150.318216 -428.942754)
					(mid 150.264334 -428.965072)
					(end 150.242016 -429.018954)
				)
				(arc
					(start 150.242016 -429.74641)
					(mid 150.244015 -429.763751)
					(end 150.24989 -429.780192)
				)
				(arc
					(start 150.483316 -430.256442)
					(mid 150.491099 -430.28997)
					(end 150.483316 -430.323498)
				)
				(arc
					(start 150.24989 -430.799748)
					(mid 150.243995 -430.816184)
					(end 150.242016 -430.83353)
				)
			)
		)
	)
	(zone
		(layers "In10.Cu" "In12.Cu")
		(hatch none 0.5)
		(connect_pads
			(clearance 0)
		)
		(min_thickness 0.25)
		(keepout
			(tracks not_allowed)
			(vias allowed)
			(pads allowed)
			(copperpour not_allowed)
			(footprints allowed)
		)
		(placement
			(enabled no)
			(sheetname "")
		)
		(fill yes
			(thermal_gap 0.5)
			(thermal_bridge_width 0.5)
			(island_removal_mode 0)
		)
		(polygon
			(pts
				(arc
					(start 412.242 -432.560476)
					(mid 412.264318 -432.614358)
					(end 412.3182 -432.636676)
				)
				(arc
					(start 413.258 -432.636676)
					(mid 413.311882 -432.614358)
					(end 413.3342 -432.560476)
				)
				(arc
					(start 413.3342 -430.018952)
					(mid 413.311882 -429.96507)
					(end 413.258 -429.942752)
				)
				(arc
					(start 412.3182 -429.942752)
					(mid 412.264318 -429.96507)
					(end 412.242 -430.018952)
				)
				(arc
					(start 412.242 -430.746408)
					(mid 412.243999 -430.763749)
					(end 412.249874 -430.78019)
				)
				(arc
					(start 412.4833 -431.25644)
					(mid 412.491083 -431.289968)
					(end 412.4833 -431.323496)
				)
				(arc
					(start 412.249874 -431.799746)
					(mid 412.243979 -431.816182)
					(end 412.242 -431.833528)
				)
			)
		)
	)
	(zone
		(layers "In10.Cu" "In12.Cu")
		(hatch none 0.5)
		(connect_pads
			(clearance 0)
		)
		(min_thickness 0.25)
		(keepout
			(tracks not_allowed)
			(vias allowed)
			(pads allowed)
			(copperpour not_allowed)
			(footprints allowed)
		)
		(placement
			(enabled no)
			(sheetname "")
		)
		(fill yes
			(thermal_gap 0.5)
			(thermal_bridge_width 0.5)
			(island_removal_mode 0)
		)
		(polygon
			(pts
				(arc
					(start 316.141608 -432.560476)
					(mid 316.163926 -432.614358)
					(end 316.217808 -432.636676)
				)
				(arc
					(start 317.157608 -432.636676)
					(mid 317.21149 -432.614358)
					(end 317.233808 -432.560476)
				)
				(arc
					(start 317.233808 -430.018952)
					(mid 317.21149 -429.96507)
					(end 317.157608 -429.942752)
				)
				(arc
					(start 316.217808 -429.942752)
					(mid 316.163926 -429.96507)
					(end 316.141608 -430.018952)
				)
				(arc
					(start 316.141608 -430.746408)
					(mid 316.143607 -430.763749)
					(end 316.149482 -430.78019)
				)
				(arc
					(start 316.382908 -431.25644)
					(mid 316.390691 -431.289968)
					(end 316.382908 -431.323496)
				)
				(arc
					(start 316.149482 -431.799746)
					(mid 316.143587 -431.816182)
					(end 316.141608 -431.833528)
				)
			)
		)
	)
	(zone
		(layers "In10.Cu" "In12.Cu")
		(hatch none 0.5)
		(connect_pads
			(clearance 0)
		)
		(min_thickness 0.25)
		(keepout
			(tracks not_allowed)
			(vias allowed)
			(pads allowed)
			(copperpour not_allowed)
			(footprints allowed)
		)
		(placement
			(enabled no)
			(sheetname "")
		)
		(fill yes
			(thermal_gap 0.5)
			(thermal_bridge_width 0.5)
			(island_removal_mode 0)
		)
		(polygon
			(pts
				(arc
					(start 404.242016 -432.560476)
					(mid 404.264334 -432.614358)
					(end 404.318216 -432.636676)
				)
				(arc
					(start 405.258016 -432.636676)
					(mid 405.311898 -432.614358)
					(end 405.334216 -432.560476)
				)
				(arc
					(start 405.334216 -430.018952)
					(mid 405.311898 -429.96507)
					(end 405.258016 -429.942752)
				)
				(arc
					(start 404.318216 -429.942752)
					(mid 404.264334 -429.96507)
					(end 404.242016 -430.018952)
				)
				(arc
					(start 404.242016 -430.746408)
					(mid 404.244015 -430.763749)
					(end 404.24989 -430.78019)
				)
				(arc
					(start 404.483316 -431.25644)
					(mid 404.491099 -431.289968)
					(end 404.483316 -431.323496)
				)
				(arc
					(start 404.24989 -431.799746)
					(mid 404.243995 -431.816182)
					(end 404.242016 -431.833528)
				)
			)
		)
	)
	(zone
		(layers "In10.Cu" "In12.Cu")
		(hatch none 0.5)
		(connect_pads
			(clearance 0)
		)
		(min_thickness 0.25)
		(keepout
			(tracks not_allowed)
			(vias allowed)
			(pads allowed)
			(copperpour not_allowed)
			(footprints allowed)
		)
		(placement
			(enabled no)
			(sheetname "")
		)
		(fill yes
			(thermal_gap 0.5)
			(thermal_bridge_width 0.5)
			(island_removal_mode 0)
		)
		(polygon
			(pts
				(arc
					(start 328.141584 -432.560476)
					(mid 328.163902 -432.614358)
					(end 328.217784 -432.636676)
				)
				(arc
					(start 329.157584 -432.636676)
					(mid 329.211466 -432.614358)
					(end 329.233784 -432.560476)
				)
				(arc
					(start 329.233784 -430.018952)
					(mid 329.211466 -429.96507)
					(end 329.157584 -429.942752)
				)
				(arc
					(start 328.217784 -429.942752)
					(mid 328.163902 -429.96507)
					(end 328.141584 -430.018952)
				)
				(arc
					(start 328.141584 -430.746408)
					(mid 328.143583 -430.763749)
					(end 328.149458 -430.78019)
				)
				(arc
					(start 328.382884 -431.25644)
					(mid 328.390667 -431.289968)
					(end 328.382884 -431.323496)
				)
				(arc
					(start 328.149458 -431.799746)
					(mid 328.143563 -431.816182)
					(end 328.141584 -431.833528)
				)
			)
		)
	)
	(zone
		(layers "In10.Cu" "In12.Cu")
		(hatch none 0.5)
		(connect_pads
			(clearance 0)
		)
		(min_thickness 0.25)
		(keepout
			(tracks not_allowed)
			(vias allowed)
			(pads allowed)
			(copperpour not_allowed)
			(footprints allowed)
		)
		(placement
			(enabled no)
			(sheetname "")
		)
		(fill yes
			(thermal_gap 0.5)
			(thermal_bridge_width 0.5)
			(island_removal_mode 0)
		)
		(polygon
			(pts
				(arc
					(start 314.141612 -431.560478)
					(mid 314.16393 -431.61436)
					(end 314.217812 -431.636678)
				)
				(arc
					(start 315.157612 -431.636678)
					(mid 315.211494 -431.61436)
					(end 315.233812 -431.560478)
				)
				(arc
					(start 315.233812 -429.018954)
					(mid 315.211494 -428.965072)
					(end 315.157612 -428.942754)
				)
				(arc
					(start 314.217812 -428.942754)
					(mid 314.16393 -428.965072)
					(end 314.141612 -429.018954)
				)
				(arc
					(start 314.141612 -429.74641)
					(mid 314.143611 -429.763751)
					(end 314.149486 -429.780192)
				)
				(arc
					(start 314.382912 -430.256442)
					(mid 314.390695 -430.28997)
					(end 314.382912 -430.323498)
				)
				(arc
					(start 314.149486 -430.799748)
					(mid 314.143591 -430.816184)
					(end 314.141612 -430.83353)
				)
			)
		)
	)
	(zone
		(layers "In10.Cu" "In12.Cu")
		(hatch none 0.5)
		(connect_pads
			(clearance 0)
		)
		(min_thickness 0.25)
		(keepout
			(tracks not_allowed)
			(vias allowed)
			(pads allowed)
			(copperpour not_allowed)
			(footprints allowed)
		)
		(placement
			(enabled no)
			(sheetname "")
		)
		(fill yes
			(thermal_gap 0.5)
			(thermal_bridge_width 0.5)
			(island_removal_mode 0)
		)
		(polygon
			(pts
				(arc
					(start 79.141828 -431.560478)
					(mid 79.164146 -431.61436)
					(end 79.218028 -431.636678)
				)
				(arc
					(start 80.157828 -431.636678)
					(mid 80.21171 -431.61436)
					(end 80.234028 -431.560478)
				)
				(arc
					(start 80.234028 -429.018954)
					(mid 80.21171 -428.965072)
					(end 80.157828 -428.942754)
				)
				(arc
					(start 79.218028 -428.942754)
					(mid 79.164146 -428.965072)
					(end 79.141828 -429.018954)
				)
				(arc
					(start 79.141828 -429.74641)
					(mid 79.143827 -429.763751)
					(end 79.149702 -429.780192)
				)
				(arc
					(start 79.383128 -430.256442)
					(mid 79.390911 -430.28997)
					(end 79.383128 -430.323498)
				)
				(arc
					(start 79.149702 -430.799748)
					(mid 79.143807 -430.816184)
					(end 79.141828 -430.83353)
				)
			)
		)
	)
	(zone
		(layers "In10.Cu" "In12.Cu")
		(hatch none 0.5)
		(connect_pads
			(clearance 0)
		)
		(min_thickness 0.25)
		(keepout
			(tracks not_allowed)
			(vias allowed)
			(pads allowed)
			(copperpour not_allowed)
			(footprints allowed)
		)
		(placement
			(enabled no)
			(sheetname "")
		)
		(fill yes
			(thermal_gap 0.5)
			(thermal_bridge_width 0.5)
			(island_removal_mode 0)
		)
		(polygon
			(pts
				(arc
					(start 89.141808 -432.560476)
					(mid 89.164126 -432.614358)
					(end 89.218008 -432.636676)
				)
				(arc
					(start 90.157808 -432.636676)
					(mid 90.21169 -432.614358)
					(end 90.234008 -432.560476)
				)
				(arc
					(start 90.234008 -430.018952)
					(mid 90.21169 -429.96507)
					(end 90.157808 -429.942752)
				)
				(arc
					(start 89.218008 -429.942752)
					(mid 89.164126 -429.96507)
					(end 89.141808 -430.018952)
				)
				(arc
					(start 89.141808 -430.746408)
					(mid 89.143807 -430.763749)
					(end 89.149682 -430.78019)
				)
				(arc
					(start 89.383108 -431.25644)
					(mid 89.390891 -431.289968)
					(end 89.383108 -431.323496)
				)
				(arc
					(start 89.149682 -431.799746)
					(mid 89.143787 -431.816182)
					(end 89.141808 -431.833528)
				)
			)
		)
	)
	(zone
		(layers "In10.Cu" "In12.Cu")
		(hatch none 0.5)
		(connect_pads
			(clearance 0)
		)
		(min_thickness 0.25)
		(keepout
			(tracks not_allowed)
			(vias allowed)
			(pads allowed)
			(copperpour not_allowed)
			(footprints allowed)
		)
		(placement
			(enabled no)
			(sheetname "")
		)
		(fill yes
			(thermal_gap 0.5)
			(thermal_bridge_width 0.5)
			(island_removal_mode 0)
		)
		(polygon
			(pts
				(arc
					(start 131.2418 -432.560476)
					(mid 131.264118 -432.614358)
					(end 131.318 -432.636676)
				)
				(arc
					(start 132.2578 -432.636676)
					(mid 132.311682 -432.614358)
					(end 132.334 -432.560476)
				)
				(arc
					(start 132.334 -430.018952)
					(mid 132.311682 -429.96507)
					(end 132.2578 -429.942752)
				)
				(arc
					(start 131.318 -429.942752)
					(mid 131.264118 -429.96507)
					(end 131.2418 -430.018952)
				)
				(arc
					(start 131.2418 -430.746408)
					(mid 131.243799 -430.763749)
					(end 131.249674 -430.78019)
				)
				(arc
					(start 131.4831 -431.25644)
					(mid 131.490883 -431.289968)
					(end 131.4831 -431.323496)
				)
				(arc
					(start 131.249674 -431.799746)
					(mid 131.243779 -431.816182)
					(end 131.2418 -431.833528)
				)
			)
		)
	)
	(zone
		(layers "In10.Cu" "In12.Cu")
		(hatch none 0.5)
		(connect_pads
			(clearance 0)
		)
		(min_thickness 0.25)
		(keepout
			(tracks not_allowed)
			(vias allowed)
			(pads allowed)
			(copperpour not_allowed)
			(footprints allowed)
		)
		(placement
			(enabled no)
			(sheetname "")
		)
		(fill yes
			(thermal_gap 0.5)
			(thermal_bridge_width 0.5)
			(island_removal_mode 0)
		)
		(polygon
			(pts
				(arc
					(start 135.241792 -432.560476)
					(mid 135.26411 -432.614358)
					(end 135.317992 -432.636676)
				)
				(arc
					(start 136.257792 -432.636676)
					(mid 136.311674 -432.614358)
					(end 136.333992 -432.560476)
				)
				(arc
					(start 136.333992 -430.018952)
					(mid 136.311674 -429.96507)
					(end 136.257792 -429.942752)
				)
				(arc
					(start 135.317992 -429.942752)
					(mid 135.26411 -429.96507)
					(end 135.241792 -430.018952)
				)
				(arc
					(start 135.241792 -430.746408)
					(mid 135.243791 -430.763749)
					(end 135.249666 -430.78019)
				)
				(arc
					(start 135.483092 -431.25644)
					(mid 135.490875 -431.289968)
					(end 135.483092 -431.323496)
				)
				(arc
					(start 135.249666 -431.799746)
					(mid 135.243771 -431.816182)
					(end 135.241792 -431.833528)
				)
			)
		)
	)
	(zone
		(layers "In10.Cu" "In12.Cu")
		(hatch none 0.5)
		(connect_pads
			(clearance 0)
		)
		(min_thickness 0.25)
		(keepout
			(tracks not_allowed)
			(vias allowed)
			(pads allowed)
			(copperpour not_allowed)
			(footprints allowed)
		)
		(placement
			(enabled no)
			(sheetname "")
		)
		(fill yes
			(thermal_gap 0.5)
			(thermal_bridge_width 0.5)
			(island_removal_mode 0)
		)
		(polygon
			(pts
				(arc
					(start 133.241796 -431.560478)
					(mid 133.264114 -431.61436)
					(end 133.317996 -431.636678)
				)
				(arc
					(start 134.257796 -431.636678)
					(mid 134.311678 -431.61436)
					(end 134.333996 -431.560478)
				)
				(arc
					(start 134.333996 -429.018954)
					(mid 134.311678 -428.965072)
					(end 134.257796 -428.942754)
				)
				(arc
					(start 133.317996 -428.942754)
					(mid 133.264114 -428.965072)
					(end 133.241796 -429.018954)
				)
				(arc
					(start 133.241796 -429.74641)
					(mid 133.243795 -429.763751)
					(end 133.24967 -429.780192)
				)
				(arc
					(start 133.483096 -430.256442)
					(mid 133.490879 -430.28997)
					(end 133.483096 -430.323498)
				)
				(arc
					(start 133.24967 -430.799748)
					(mid 133.243775 -430.816184)
					(end 133.241796 -430.83353)
				)
			)
		)
	)
	(zone
		(layers "In10.Cu" "In12.Cu")
		(hatch none 0.5)
		(connect_pads
			(clearance 0)
		)
		(min_thickness 0.25)
		(keepout
			(tracks not_allowed)
			(vias allowed)
			(pads allowed)
			(copperpour not_allowed)
			(footprints allowed)
		)
		(placement
			(enabled no)
			(sheetname "")
		)
		(fill yes
			(thermal_gap 0.5)
			(thermal_bridge_width 0.5)
			(island_removal_mode 0)
		)
		(polygon
			(pts
				(arc
					(start 387.241796 -432.560476)
					(mid 387.264114 -432.614358)
					(end 387.317996 -432.636676)
				)
				(arc
					(start 388.257796 -432.636676)
					(mid 388.311678 -432.614358)
					(end 388.333996 -432.560476)
				)
				(arc
					(start 388.333996 -430.018952)
					(mid 388.311678 -429.96507)
					(end 388.257796 -429.942752)
				)
				(arc
					(start 387.317996 -429.942752)
					(mid 387.264114 -429.96507)
					(end 387.241796 -430.018952)
				)
				(arc
					(start 387.241796 -430.746408)
					(mid 387.243795 -430.763749)
					(end 387.24967 -430.78019)
				)
				(arc
					(start 387.483096 -431.25644)
					(mid 387.490879 -431.289968)
					(end 387.483096 -431.323496)
				)
				(arc
					(start 387.24967 -431.799746)
					(mid 387.243775 -431.816182)
					(end 387.241796 -431.833528)
				)
			)
		)
	)
	(zone
		(layers "In10.Cu" "In12.Cu")
		(hatch none 0.5)
		(connect_pads
			(clearance 0)
		)
		(min_thickness 0.25)
		(keepout
			(tracks not_allowed)
			(vias allowed)
			(pads allowed)
			(copperpour not_allowed)
			(footprints allowed)
		)
		(placement
			(enabled no)
			(sheetname "")
		)
		(fill yes
			(thermal_gap 0.5)
			(thermal_bridge_width 0.5)
			(island_removal_mode 0)
		)
		(polygon
			(pts
				(arc
					(start 62.141862 -431.560478)
					(mid 62.16418 -431.61436)
					(end 62.218062 -431.636678)
				)
				(arc
					(start 63.157862 -431.636678)
					(mid 63.211744 -431.61436)
					(end 63.234062 -431.560478)
				)
				(arc
					(start 63.234062 -429.018954)
					(mid 63.211744 -428.965072)
					(end 63.157862 -428.942754)
				)
				(arc
					(start 62.218062 -428.942754)
					(mid 62.16418 -428.965072)
					(end 62.141862 -429.018954)
				)
				(arc
					(start 62.141862 -429.74641)
					(mid 62.143861 -429.763751)
					(end 62.149736 -429.780192)
				)
				(arc
					(start 62.383162 -430.256442)
					(mid 62.390945 -430.28997)
					(end 62.383162 -430.323498)
				)
				(arc
					(start 62.149736 -430.799748)
					(mid 62.143841 -430.816184)
					(end 62.141862 -430.83353)
				)
			)
		)
	)
	(zone
		(layers "In10.Cu" "In12.Cu")
		(hatch none 0.5)
		(connect_pads
			(clearance 0)
		)
		(min_thickness 0.25)
		(keepout
			(tracks not_allowed)
			(vias allowed)
			(pads allowed)
			(copperpour not_allowed)
			(footprints allowed)
		)
		(placement
			(enabled no)
			(sheetname "")
		)
		(fill yes
			(thermal_gap 0.5)
			(thermal_bridge_width 0.5)
			(island_removal_mode 0)
		)
		(polygon
			(pts
				(arc
					(start 77.141832 -432.560476)
					(mid 77.16415 -432.614358)
					(end 77.218032 -432.636676)
				)
				(arc
					(start 78.157832 -432.636676)
					(mid 78.211714 -432.614358)
					(end 78.234032 -432.560476)
				)
				(arc
					(start 78.234032 -430.018952)
					(mid 78.211714 -429.96507)
					(end 78.157832 -429.942752)
				)
				(arc
					(start 77.218032 -429.942752)
					(mid 77.16415 -429.96507)
					(end 77.141832 -430.018952)
				)
				(arc
					(start 77.141832 -430.746408)
					(mid 77.143831 -430.763749)
					(end 77.149706 -430.78019)
				)
				(arc
					(start 77.383132 -431.25644)
					(mid 77.390915 -431.289968)
					(end 77.383132 -431.323496)
				)
				(arc
					(start 77.149706 -431.799746)
					(mid 77.143811 -431.816182)
					(end 77.141832 -431.833528)
				)
			)
		)
	)
	(zone
		(layers "In10.Cu" "In12.Cu")
		(hatch none 0.5)
		(connect_pads
			(clearance 0)
		)
		(min_thickness 0.25)
		(keepout
			(tracks not_allowed)
			(vias allowed)
			(pads allowed)
			(copperpour not_allowed)
			(footprints allowed)
		)
		(placement
			(enabled no)
			(sheetname "")
		)
		(fill yes
			(thermal_gap 0.5)
			(thermal_bridge_width 0.5)
			(island_removal_mode 0)
		)
		(polygon
			(pts
				(arc
					(start 146.242024 -431.560478)
					(mid 146.264342 -431.61436)
					(end 146.318224 -431.636678)
				)
				(arc
					(start 147.258024 -431.636678)
					(mid 147.311906 -431.61436)
					(end 147.334224 -431.560478)
				)
				(arc
					(start 147.334224 -429.018954)
					(mid 147.311906 -428.965072)
					(end 147.258024 -428.942754)
				)
				(arc
					(start 146.318224 -428.942754)
					(mid 146.264342 -428.965072)
					(end 146.242024 -429.018954)
				)
				(arc
					(start 146.242024 -429.74641)
					(mid 146.244023 -429.763751)
					(end 146.249898 -429.780192)
				)
				(arc
					(start 146.483324 -430.256442)
					(mid 146.491107 -430.28997)
					(end 146.483324 -430.323498)
				)
				(arc
					(start 146.249898 -430.799748)
					(mid 146.244003 -430.816184)
					(end 146.242024 -430.83353)
				)
			)
		)
	)
	(zone
		(layers "In10.Cu" "In12.Cu")
		(hatch none 0.5)
		(connect_pads
			(clearance 0)
		)
		(min_thickness 0.25)
		(keepout
			(tracks not_allowed)
			(vias allowed)
			(pads allowed)
			(copperpour not_allowed)
			(footprints allowed)
		)
		(placement
			(enabled no)
			(sheetname "")
		)
		(fill yes
			(thermal_gap 0.5)
			(thermal_bridge_width 0.5)
			(island_removal_mode 0)
		)
		(polygon
			(pts
				(arc
					(start 68.14185 -432.560476)
					(mid 68.164168 -432.614358)
					(end 68.21805 -432.636676)
				)
				(arc
					(start 69.15785 -432.636676)
					(mid 69.211732 -432.614358)
					(end 69.23405 -432.560476)
				)
				(arc
					(start 69.23405 -430.018952)
					(mid 69.211732 -429.96507)
					(end 69.15785 -429.942752)
				)
				(arc
					(start 68.21805 -429.942752)
					(mid 68.164168 -429.96507)
					(end 68.14185 -430.018952)
				)
				(arc
					(start 68.14185 -430.746408)
					(mid 68.143849 -430.763749)
					(end 68.149724 -430.78019)
				)
				(arc
					(start 68.38315 -431.25644)
					(mid 68.390933 -431.289968)
					(end 68.38315 -431.323496)
				)
				(arc
					(start 68.149724 -431.799746)
					(mid 68.143829 -431.816182)
					(end 68.14185 -431.833528)
				)
			)
		)
	)
	(zone
		(layers "In10.Cu" "In12.Cu")
		(hatch none 0.5)
		(connect_pads
			(clearance 0)
		)
		(min_thickness 0.25)
		(keepout
			(tracks not_allowed)
			(vias allowed)
			(pads allowed)
			(copperpour not_allowed)
			(footprints allowed)
		)
		(placement
			(enabled no)
			(sheetname "")
		)
		(fill yes
			(thermal_gap 0.5)
			(thermal_bridge_width 0.5)
			(island_removal_mode 0)
		)
		(polygon
			(pts
				(arc
					(start 85.141816 -432.560476)
					(mid 85.164134 -432.614358)
					(end 85.218016 -432.636676)
				)
				(arc
					(start 86.157816 -432.636676)
					(mid 86.211698 -432.614358)
					(end 86.234016 -432.560476)
				)
				(arc
					(start 86.234016 -430.018952)
					(mid 86.211698 -429.96507)
					(end 86.157816 -429.942752)
				)
				(arc
					(start 85.218016 -429.942752)
					(mid 85.164134 -429.96507)
					(end 85.141816 -430.018952)
				)
				(arc
					(start 85.141816 -430.746408)
					(mid 85.143815 -430.763749)
					(end 85.14969 -430.78019)
				)
				(arc
					(start 85.383116 -431.25644)
					(mid 85.390899 -431.289968)
					(end 85.383116 -431.323496)
				)
				(arc
					(start 85.14969 -431.799746)
					(mid 85.143795 -431.816182)
					(end 85.141816 -431.833528)
				)
			)
		)
	)
	(zone
		(layers "In10.Cu" "In12.Cu")
		(hatch none 0.5)
		(connect_pads
			(clearance 0)
		)
		(min_thickness 0.25)
		(keepout
			(tracks not_allowed)
			(vias allowed)
			(pads allowed)
			(copperpour not_allowed)
			(footprints allowed)
		)
		(placement
			(enabled no)
			(sheetname "")
		)
		(fill yes
			(thermal_gap 0.5)
			(thermal_bridge_width 0.5)
			(island_removal_mode 0)
		)
		(polygon
			(pts
				(arc
					(start 335.141824 -431.560478)
					(mid 335.164142 -431.61436)
					(end 335.218024 -431.636678)
				)
				(arc
					(start 336.157824 -431.636678)
					(mid 336.211706 -431.61436)
					(end 336.234024 -431.560478)
				)
				(arc
					(start 336.234024 -429.018954)
					(mid 336.211706 -428.965072)
					(end 336.157824 -428.942754)
				)
				(arc
					(start 335.218024 -428.942754)
					(mid 335.164142 -428.965072)
					(end 335.141824 -429.018954)
				)
				(arc
					(start 335.141824 -429.74641)
					(mid 335.143823 -429.763751)
					(end 335.149698 -429.780192)
				)
				(arc
					(start 335.383124 -430.256442)
					(mid 335.390907 -430.28997)
					(end 335.383124 -430.323498)
				)
				(arc
					(start 335.149698 -430.799748)
					(mid 335.143803 -430.816184)
					(end 335.141824 -430.83353)
				)
			)
		)
	)
	(zone
		(layers "In10.Cu" "In12.Cu")
		(hatch none 0.5)
		(connect_pads
			(clearance 0)
		)
		(min_thickness 0.25)
		(keepout
			(tracks not_allowed)
			(vias allowed)
			(pads allowed)
			(copperpour not_allowed)
			(footprints allowed)
		)
		(placement
			(enabled no)
			(sheetname "")
		)
		(fill yes
			(thermal_gap 0.5)
			(thermal_bridge_width 0.5)
			(island_removal_mode 0)
		)
		(polygon
			(pts
				(arc
					(start 406.242012 -431.560478)
					(mid 406.26433 -431.61436)
					(end 406.318212 -431.636678)
				)
				(arc
					(start 407.258012 -431.636678)
					(mid 407.311894 -431.61436)
					(end 407.334212 -431.560478)
				)
				(arc
					(start 407.334212 -429.018954)
					(mid 407.311894 -428.965072)
					(end 407.258012 -428.942754)
				)
				(arc
					(start 406.318212 -428.942754)
					(mid 406.26433 -428.965072)
					(end 406.242012 -429.018954)
				)
				(arc
					(start 406.242012 -429.74641)
					(mid 406.244011 -429.763751)
					(end 406.249886 -429.780192)
				)
				(arc
					(start 406.483312 -430.256442)
					(mid 406.491095 -430.28997)
					(end 406.483312 -430.323498)
				)
				(arc
					(start 406.249886 -430.799748)
					(mid 406.243991 -430.816184)
					(end 406.242012 -430.83353)
				)
			)
		)
	)
	(zone
		(layers "In10.Cu" "In12.Cu")
		(hatch none 0.5)
		(connect_pads
			(clearance 0)
		)
		(min_thickness 0.25)
		(keepout
			(tracks not_allowed)
			(vias allowed)
			(pads allowed)
			(copperpour not_allowed)
			(footprints allowed)
		)
		(placement
			(enabled no)
			(sheetname "")
		)
		(fill yes
			(thermal_gap 0.5)
			(thermal_bridge_width 0.5)
			(island_removal_mode 0)
		)
		(polygon
			(pts
				(arc
					(start 64.141858 -432.560476)
					(mid 64.164176 -432.614358)
					(end 64.218058 -432.636676)
				)
				(arc
					(start 65.157858 -432.636676)
					(mid 65.21174 -432.614358)
					(end 65.234058 -432.560476)
				)
				(arc
					(start 65.234058 -430.018952)
					(mid 65.21174 -429.96507)
					(end 65.157858 -429.942752)
				)
				(arc
					(start 64.218058 -429.942752)
					(mid 64.164176 -429.96507)
					(end 64.141858 -430.018952)
				)
				(arc
					(start 64.141858 -430.746408)
					(mid 64.143857 -430.763749)
					(end 64.149732 -430.78019)
				)
				(arc
					(start 64.383158 -431.25644)
					(mid 64.390941 -431.289968)
					(end 64.383158 -431.323496)
				)
				(arc
					(start 64.149732 -431.799746)
					(mid 64.143837 -431.816182)
					(end 64.141858 -431.833528)
				)
			)
		)
	)
	(zone
		(layers "In10.Cu" "In12.Cu")
		(hatch none 0.5)
		(connect_pads
			(clearance 0)
		)
		(min_thickness 0.25)
		(keepout
			(tracks not_allowed)
			(vias allowed)
			(pads allowed)
			(copperpour not_allowed)
			(footprints allowed)
		)
		(placement
			(enabled no)
			(sheetname "")
		)
		(fill yes
			(thermal_gap 0.5)
			(thermal_bridge_width 0.5)
			(island_removal_mode 0)
		)
		(polygon
			(pts
				(arc
					(start 66.141854 -431.560478)
					(mid 66.164172 -431.61436)
					(end 66.218054 -431.636678)
				)
				(arc
					(start 67.157854 -431.636678)
					(mid 67.211736 -431.61436)
					(end 67.234054 -431.560478)
				)
				(arc
					(start 67.234054 -429.018954)
					(mid 67.211736 -428.965072)
					(end 67.157854 -428.942754)
				)
				(arc
					(start 66.218054 -428.942754)
					(mid 66.164172 -428.965072)
					(end 66.141854 -429.018954)
				)
				(arc
					(start 66.141854 -429.74641)
					(mid 66.143853 -429.763751)
					(end 66.149728 -429.780192)
				)
				(arc
					(start 66.383154 -430.256442)
					(mid 66.390937 -430.28997)
					(end 66.383154 -430.323498)
				)
				(arc
					(start 66.149728 -430.799748)
					(mid 66.143833 -430.816184)
					(end 66.141854 -430.83353)
				)
			)
		)
	)
	(zone
		(layers "In10.Cu" "In12.Cu")
		(hatch none 0.5)
		(connect_pads
			(clearance 0)
		)
		(min_thickness 0.25)
		(keepout
			(tracks not_allowed)
			(vias allowed)
			(pads allowed)
			(copperpour not_allowed)
			(footprints allowed)
		)
		(placement
			(enabled no)
			(sheetname "")
		)
		(fill yes
			(thermal_gap 0.5)
			(thermal_bridge_width 0.5)
			(island_removal_mode 0)
		)
		(polygon
			(pts
				(arc
					(start 337.14182 -432.560476)
					(mid 337.164138 -432.614358)
					(end 337.21802 -432.636676)
				)
				(arc
					(start 338.15782 -432.636676)
					(mid 338.211702 -432.614358)
					(end 338.23402 -432.560476)
				)
				(arc
					(start 338.23402 -430.018952)
					(mid 338.211702 -429.96507)
					(end 338.15782 -429.942752)
				)
				(arc
					(start 337.21802 -429.942752)
					(mid 337.164138 -429.96507)
					(end 337.14182 -430.018952)
				)
				(arc
					(start 337.14182 -430.746408)
					(mid 337.143819 -430.763749)
					(end 337.149694 -430.78019)
				)
				(arc
					(start 337.38312 -431.25644)
					(mid 337.390903 -431.289968)
					(end 337.38312 -431.323496)
				)
				(arc
					(start 337.149694 -431.799746)
					(mid 337.143799 -431.816182)
					(end 337.14182 -431.833528)
				)
			)
		)
	)
	(zone
		(layers "In10.Cu" "In12.Cu")
		(hatch none 0.5)
		(connect_pads
			(clearance 0)
		)
		(min_thickness 0.25)
		(keepout
			(tracks not_allowed)
			(vias allowed)
			(pads allowed)
			(copperpour not_allowed)
			(footprints allowed)
		)
		(placement
			(enabled no)
			(sheetname "")
		)
		(fill yes
			(thermal_gap 0.5)
			(thermal_bridge_width 0.5)
			(island_removal_mode 0)
		)
		(polygon
			(pts
				(arc
					(start 402.24202 -431.560478)
					(mid 402.264338 -431.61436)
					(end 402.31822 -431.636678)
				)
				(arc
					(start 403.25802 -431.636678)
					(mid 403.311902 -431.61436)
					(end 403.33422 -431.560478)
				)
				(arc
					(start 403.33422 -429.018954)
					(mid 403.311902 -428.965072)
					(end 403.25802 -428.942754)
				)
				(arc
					(start 402.31822 -428.942754)
					(mid 402.264338 -428.965072)
					(end 402.24202 -429.018954)
				)
				(arc
					(start 402.24202 -429.74641)
					(mid 402.244019 -429.763751)
					(end 402.249894 -429.780192)
				)
				(arc
					(start 402.48332 -430.256442)
					(mid 402.491103 -430.28997)
					(end 402.48332 -430.323498)
				)
				(arc
					(start 402.249894 -430.799748)
					(mid 402.243999 -430.816184)
					(end 402.24202 -430.83353)
				)
			)
		)
	)
	(zone
		(layers "In10.Cu" "In12.Cu")
		(hatch none 0.5)
		(connect_pads
			(clearance 0)
		)
		(min_thickness 0.25)
		(keepout
			(tracks not_allowed)
			(vias allowed)
			(pads allowed)
			(copperpour not_allowed)
			(footprints allowed)
		)
		(placement
			(enabled no)
			(sheetname "")
		)
		(fill yes
			(thermal_gap 0.5)
			(thermal_bridge_width 0.5)
			(island_removal_mode 0)
		)
		(polygon
			(pts
				(arc
					(start 72.141842 -432.560476)
					(mid 72.16416 -432.614358)
					(end 72.218042 -432.636676)
				)
				(arc
					(start 73.157842 -432.636676)
					(mid 73.211724 -432.614358)
					(end 73.234042 -432.560476)
				)
				(arc
					(start 73.234042 -430.018952)
					(mid 73.211724 -429.96507)
					(end 73.157842 -429.942752)
				)
				(arc
					(start 72.218042 -429.942752)
					(mid 72.16416 -429.96507)
					(end 72.141842 -430.018952)
				)
				(arc
					(start 72.141842 -430.746408)
					(mid 72.143841 -430.763749)
					(end 72.149716 -430.78019)
				)
				(arc
					(start 72.383142 -431.25644)
					(mid 72.390925 -431.289968)
					(end 72.383142 -431.323496)
				)
				(arc
					(start 72.149716 -431.799746)
					(mid 72.143821 -431.816182)
					(end 72.141842 -431.833528)
				)
			)
		)
	)
	(zone
		(layers "In10.Cu" "In12.Cu")
		(hatch none 0.5)
		(connect_pads
			(clearance 0)
		)
		(min_thickness 0.25)
		(keepout
			(tracks not_allowed)
			(vias allowed)
			(pads allowed)
			(copperpour not_allowed)
			(footprints allowed)
		)
		(placement
			(enabled no)
			(sheetname "")
		)
		(fill yes
			(thermal_gap 0.5)
			(thermal_bridge_width 0.5)
			(island_removal_mode 0)
		)
		(polygon
			(pts
				(arc
					(start 70.141846 -431.560478)
					(mid 70.164164 -431.61436)
					(end 70.218046 -431.636678)
				)
				(arc
					(start 71.157846 -431.636678)
					(mid 71.211728 -431.61436)
					(end 71.234046 -431.560478)
				)
				(arc
					(start 71.234046 -429.018954)
					(mid 71.211728 -428.965072)
					(end 71.157846 -428.942754)
				)
				(arc
					(start 70.218046 -428.942754)
					(mid 70.164164 -428.965072)
					(end 70.141846 -429.018954)
				)
				(arc
					(start 70.141846 -429.74641)
					(mid 70.143845 -429.763751)
					(end 70.14972 -429.780192)
				)
				(arc
					(start 70.383146 -430.256442)
					(mid 70.390929 -430.28997)
					(end 70.383146 -430.323498)
				)
				(arc
					(start 70.14972 -430.799748)
					(mid 70.143825 -430.816184)
					(end 70.141846 -430.83353)
				)
			)
		)
	)
	(zone
		(layers "In10.Cu" "In12.Cu")
		(hatch none 0.5)
		(connect_pads
			(clearance 0)
		)
		(min_thickness 0.25)
		(keepout
			(tracks not_allowed)
			(vias allowed)
			(pads allowed)
			(copperpour not_allowed)
			(footprints allowed)
		)
		(placement
			(enabled no)
			(sheetname "")
		)
		(fill yes
			(thermal_gap 0.5)
			(thermal_bridge_width 0.5)
			(island_removal_mode 0)
		)
		(polygon
			(pts
				(arc
					(start 81.141824 -432.560476)
					(mid 81.164142 -432.614358)
					(end 81.218024 -432.636676)
				)
				(arc
					(start 82.157824 -432.636676)
					(mid 82.211706 -432.614358)
					(end 82.234024 -432.560476)
				)
				(arc
					(start 82.234024 -430.018952)
					(mid 82.211706 -429.96507)
					(end 82.157824 -429.942752)
				)
				(arc
					(start 81.218024 -429.942752)
					(mid 81.164142 -429.96507)
					(end 81.141824 -430.018952)
				)
				(arc
					(start 81.141824 -430.746408)
					(mid 81.143823 -430.763749)
					(end 81.149698 -430.78019)
				)
				(arc
					(start 81.383124 -431.25644)
					(mid 81.390907 -431.289968)
					(end 81.383124 -431.323496)
				)
				(arc
					(start 81.149698 -431.799746)
					(mid 81.143803 -431.816182)
					(end 81.141824 -431.833528)
				)
			)
		)
	)
	(zone
		(layers "In10.Cu" "In12.Cu")
		(hatch none 0.5)
		(connect_pads
			(clearance 0)
		)
		(min_thickness 0.25)
		(keepout
			(tracks not_allowed)
			(vias allowed)
			(pads allowed)
			(copperpour not_allowed)
			(footprints allowed)
		)
		(placement
			(enabled no)
			(sheetname "")
		)
		(fill yes
			(thermal_gap 0.5)
			(thermal_bridge_width 0.5)
			(island_removal_mode 0)
		)
		(polygon
			(pts
				(arc
					(start 139.241784 -432.560476)
					(mid 139.264102 -432.614358)
					(end 139.317984 -432.636676)
				)
				(arc
					(start 140.257784 -432.636676)
					(mid 140.311666 -432.614358)
					(end 140.333984 -432.560476)
				)
				(arc
					(start 140.333984 -430.018952)
					(mid 140.311666 -429.96507)
					(end 140.257784 -429.942752)
				)
				(arc
					(start 139.317984 -429.942752)
					(mid 139.264102 -429.96507)
					(end 139.241784 -430.018952)
				)
				(arc
					(start 139.241784 -430.746408)
					(mid 139.243783 -430.763749)
					(end 139.249658 -430.78019)
				)
				(arc
					(start 139.483084 -431.25644)
					(mid 139.490867 -431.289968)
					(end 139.483084 -431.323496)
				)
				(arc
					(start 139.249658 -431.799746)
					(mid 139.243763 -431.816182)
					(end 139.241784 -431.833528)
				)
			)
		)
	)
	(zone
		(layers "In10.Cu" "In12.Cu")
		(hatch none 0.5)
		(connect_pads
			(clearance 0)
		)
		(min_thickness 0.25)
		(keepout
			(tracks not_allowed)
			(vias allowed)
			(pads allowed)
			(copperpour not_allowed)
			(footprints allowed)
		)
		(placement
			(enabled no)
			(sheetname "")
		)
		(fill yes
			(thermal_gap 0.5)
			(thermal_bridge_width 0.5)
			(island_removal_mode 0)
		)
		(polygon
			(pts
				(arc
					(start 341.141812 -432.560476)
					(mid 341.16413 -432.614358)
					(end 341.218012 -432.636676)
				)
				(arc
					(start 342.157812 -432.636676)
					(mid 342.211694 -432.614358)
					(end 342.234012 -432.560476)
				)
				(arc
					(start 342.234012 -430.018952)
					(mid 342.211694 -429.96507)
					(end 342.157812 -429.942752)
				)
				(arc
					(start 341.218012 -429.942752)
					(mid 341.16413 -429.96507)
					(end 341.141812 -430.018952)
				)
				(arc
					(start 341.141812 -430.746408)
					(mid 341.143811 -430.763749)
					(end 341.149686 -430.78019)
				)
				(arc
					(start 341.383112 -431.25644)
					(mid 341.390895 -431.289968)
					(end 341.383112 -431.323496)
				)
				(arc
					(start 341.149686 -431.799746)
					(mid 341.143791 -431.816182)
					(end 341.141812 -431.833528)
				)
			)
		)
	)
	(zone
		(layers "In10.Cu" "In12.Cu")
		(hatch none 0.5)
		(connect_pads
			(clearance 0)
		)
		(min_thickness 0.25)
		(keepout
			(tracks not_allowed)
			(vias allowed)
			(pads allowed)
			(copperpour not_allowed)
			(footprints allowed)
		)
		(placement
			(enabled no)
			(sheetname "")
		)
		(fill yes
			(thermal_gap 0.5)
			(thermal_bridge_width 0.5)
			(island_removal_mode 0)
		)
		(polygon
			(pts
				(arc
					(start 391.241788 -432.560476)
					(mid 391.264106 -432.614358)
					(end 391.317988 -432.636676)
				)
				(arc
					(start 392.257788 -432.636676)
					(mid 392.31167 -432.614358)
					(end 392.333988 -432.560476)
				)
				(arc
					(start 392.333988 -430.018952)
					(mid 392.31167 -429.96507)
					(end 392.257788 -429.942752)
				)
				(arc
					(start 391.317988 -429.942752)
					(mid 391.264106 -429.96507)
					(end 391.241788 -430.018952)
				)
				(arc
					(start 391.241788 -430.746408)
					(mid 391.243787 -430.763749)
					(end 391.249662 -430.78019)
				)
				(arc
					(start 391.483088 -431.25644)
					(mid 391.490871 -431.289968)
					(end 391.483088 -431.323496)
				)
				(arc
					(start 391.249662 -431.799746)
					(mid 391.243767 -431.816182)
					(end 391.241788 -431.833528)
				)
			)
		)
	)
	(zone
		(layers "In10.Cu" "In12.Cu")
		(hatch none 0.5)
		(connect_pads
			(clearance 0)
		)
		(min_thickness 0.25)
		(keepout
			(tracks not_allowed)
			(vias allowed)
			(pads allowed)
			(copperpour not_allowed)
			(footprints allowed)
		)
		(placement
			(enabled no)
			(sheetname "")
		)
		(fill yes
			(thermal_gap 0.5)
			(thermal_bridge_width 0.5)
			(island_removal_mode 0)
		)
		(polygon
			(pts
				(arc
					(start 383.241804 -432.560476)
					(mid 383.264122 -432.614358)
					(end 383.318004 -432.636676)
				)
				(arc
					(start 384.257804 -432.636676)
					(mid 384.311686 -432.614358)
					(end 384.334004 -432.560476)
				)
				(arc
					(start 384.334004 -430.018952)
					(mid 384.311686 -429.96507)
					(end 384.257804 -429.942752)
				)
				(arc
					(start 383.318004 -429.942752)
					(mid 383.264122 -429.96507)
					(end 383.241804 -430.018952)
				)
				(arc
					(start 383.241804 -430.746408)
					(mid 383.243803 -430.763749)
					(end 383.249678 -430.78019)
				)
				(arc
					(start 383.483104 -431.25644)
					(mid 383.490887 -431.289968)
					(end 383.483104 -431.323496)
				)
				(arc
					(start 383.249678 -431.799746)
					(mid 383.243783 -431.816182)
					(end 383.241804 -431.833528)
				)
			)
		)
	)
	(zone
		(layers "In10.Cu" "In12.Cu")
		(hatch none 0.5)
		(connect_pads
			(clearance 0)
		)
		(min_thickness 0.25)
		(keepout
			(tracks not_allowed)
			(vias allowed)
			(pads allowed)
			(copperpour not_allowed)
			(footprints allowed)
		)
		(placement
			(enabled no)
			(sheetname "")
		)
		(fill yes
			(thermal_gap 0.5)
			(thermal_bridge_width 0.5)
			(island_removal_mode 0)
		)
		(polygon
			(pts
				(arc
					(start 400.242024 -432.560476)
					(mid 400.264342 -432.614358)
					(end 400.318224 -432.636676)
				)
				(arc
					(start 401.258024 -432.636676)
					(mid 401.311906 -432.614358)
					(end 401.334224 -432.560476)
				)
				(arc
					(start 401.334224 -430.018952)
					(mid 401.311906 -429.96507)
					(end 401.258024 -429.942752)
				)
				(arc
					(start 400.318224 -429.942752)
					(mid 400.264342 -429.96507)
					(end 400.242024 -430.018952)
				)
				(arc
					(start 400.242024 -430.746408)
					(mid 400.244023 -430.763749)
					(end 400.249898 -430.78019)
				)
				(arc
					(start 400.483324 -431.25644)
					(mid 400.491107 -431.289968)
					(end 400.483324 -431.323496)
				)
				(arc
					(start 400.249898 -431.799746)
					(mid 400.244003 -431.816182)
					(end 400.242024 -431.833528)
				)
			)
		)
	)
	(zone
		(layers "In10.Cu" "In12.Cu")
		(hatch none 0.5)
		(connect_pads
			(clearance 0)
		)
		(min_thickness 0.25)
		(keepout
			(tracks not_allowed)
			(vias allowed)
			(pads allowed)
			(copperpour not_allowed)
			(footprints allowed)
		)
		(placement
			(enabled no)
			(sheetname "")
		)
		(fill yes
			(thermal_gap 0.5)
			(thermal_bridge_width 0.5)
			(island_removal_mode 0)
		)
		(polygon
			(pts
				(arc
					(start 385.2418 -431.560478)
					(mid 385.264118 -431.61436)
					(end 385.318 -431.636678)
				)
				(arc
					(start 386.2578 -431.636678)
					(mid 386.311682 -431.61436)
					(end 386.334 -431.560478)
				)
				(arc
					(start 386.334 -429.018954)
					(mid 386.311682 -428.965072)
					(end 386.2578 -428.942754)
				)
				(arc
					(start 385.318 -428.942754)
					(mid 385.264118 -428.965072)
					(end 385.2418 -429.018954)
				)
				(arc
					(start 385.2418 -429.74641)
					(mid 385.243799 -429.763751)
					(end 385.249674 -429.780192)
				)
				(arc
					(start 385.4831 -430.256442)
					(mid 385.490883 -430.28997)
					(end 385.4831 -430.323498)
				)
				(arc
					(start 385.249674 -430.799748)
					(mid 385.243779 -430.816184)
					(end 385.2418 -430.83353)
				)
			)
		)
	)
	(zone
		(layers "In10.Cu" "In12.Cu")
		(hatch none 0.5)
		(connect_pads
			(clearance 0)
		)
		(min_thickness 0.25)
		(keepout
			(tracks not_allowed)
			(vias allowed)
			(pads allowed)
			(copperpour not_allowed)
			(footprints allowed)
		)
		(placement
			(enabled no)
			(sheetname "")
		)
		(fill yes
			(thermal_gap 0.5)
			(thermal_bridge_width 0.5)
			(island_removal_mode 0)
		)
		(polygon
			(pts
				(arc
					(start 144.242028 -432.560476)
					(mid 144.264346 -432.614358)
					(end 144.318228 -432.636676)
				)
				(arc
					(start 145.258028 -432.636676)
					(mid 145.31191 -432.614358)
					(end 145.334228 -432.560476)
				)
				(arc
					(start 145.334228 -430.018952)
					(mid 145.31191 -429.96507)
					(end 145.258028 -429.942752)
				)
				(arc
					(start 144.318228 -429.942752)
					(mid 144.264346 -429.96507)
					(end 144.242028 -430.018952)
				)
				(arc
					(start 144.242028 -430.746408)
					(mid 144.244027 -430.763749)
					(end 144.249902 -430.78019)
				)
				(arc
					(start 144.483328 -431.25644)
					(mid 144.491111 -431.289968)
					(end 144.483328 -431.323496)
				)
				(arc
					(start 144.249902 -431.799746)
					(mid 144.244007 -431.816182)
					(end 144.242028 -431.833528)
				)
			)
		)
	)
	(zone
		(layers "In10.Cu" "In12.Cu")
		(hatch none 0.5)
		(connect_pads
			(clearance 0)
		)
		(min_thickness 0.25)
		(keepout
			(tracks not_allowed)
			(vias allowed)
			(pads allowed)
			(copperpour not_allowed)
			(footprints allowed)
		)
		(placement
			(enabled no)
			(sheetname "")
		)
		(fill yes
			(thermal_gap 0.5)
			(thermal_bridge_width 0.5)
			(island_removal_mode 0)
		)
		(polygon
			(pts
				(arc
					(start 125.241812 -431.560478)
					(mid 125.26413 -431.61436)
					(end 125.318012 -431.636678)
				)
				(arc
					(start 126.257812 -431.636678)
					(mid 126.311694 -431.61436)
					(end 126.334012 -431.560478)
				)
				(arc
					(start 126.334012 -429.018954)
					(mid 126.311694 -428.965072)
					(end 126.257812 -428.942754)
				)
				(arc
					(start 125.318012 -428.942754)
					(mid 125.26413 -428.965072)
					(end 125.241812 -429.018954)
				)
				(arc
					(start 125.241812 -429.74641)
					(mid 125.243811 -429.763751)
					(end 125.249686 -429.780192)
				)
				(arc
					(start 125.483112 -430.256442)
					(mid 125.490895 -430.28997)
					(end 125.483112 -430.323498)
				)
				(arc
					(start 125.249686 -430.799748)
					(mid 125.243791 -430.816184)
					(end 125.241812 -430.83353)
				)
			)
		)
	)
	(zone
		(layers "In10.Cu" "In12.Cu")
		(hatch none 0.5)
		(connect_pads
			(clearance 0)
		)
		(min_thickness 0.25)
		(keepout
			(tracks not_allowed)
			(vias allowed)
			(pads allowed)
			(copperpour not_allowed)
			(footprints allowed)
		)
		(placement
			(enabled no)
			(sheetname "")
		)
		(fill yes
			(thermal_gap 0.5)
			(thermal_bridge_width 0.5)
			(island_removal_mode 0)
		)
		(polygon
			(pts
				(arc
					(start 322.141596 -431.560478)
					(mid 322.163914 -431.61436)
					(end 322.217796 -431.636678)
				)
				(arc
					(start 323.157596 -431.636678)
					(mid 323.211478 -431.61436)
					(end 323.233796 -431.560478)
				)
				(arc
					(start 323.233796 -429.018954)
					(mid 323.211478 -428.965072)
					(end 323.157596 -428.942754)
				)
				(arc
					(start 322.217796 -428.942754)
					(mid 322.163914 -428.965072)
					(end 322.141596 -429.018954)
				)
				(arc
					(start 322.141596 -429.74641)
					(mid 322.143595 -429.763751)
					(end 322.14947 -429.780192)
				)
				(arc
					(start 322.382896 -430.256442)
					(mid 322.390679 -430.28997)
					(end 322.382896 -430.323498)
				)
				(arc
					(start 322.14947 -430.799748)
					(mid 322.143575 -430.816184)
					(end 322.141596 -430.83353)
				)
			)
		)
	)
	(zone
		(layers "In10.Cu" "In12.Cu")
		(hatch none 0.5)
		(connect_pads
			(clearance 0)
		)
		(min_thickness 0.25)
		(keepout
			(tracks not_allowed)
			(vias allowed)
			(pads allowed)
			(copperpour not_allowed)
			(footprints allowed)
		)
		(placement
			(enabled no)
			(sheetname "")
		)
		(fill yes
			(thermal_gap 0.5)
			(thermal_bridge_width 0.5)
			(island_removal_mode 0)
		)
		(polygon
			(pts
				(arc
					(start 331.141832 -431.560478)
					(mid 331.16415 -431.61436)
					(end 331.218032 -431.636678)
				)
				(arc
					(start 332.157832 -431.636678)
					(mid 332.211714 -431.61436)
					(end 332.234032 -431.560478)
				)
				(arc
					(start 332.234032 -429.018954)
					(mid 332.211714 -428.965072)
					(end 332.157832 -428.942754)
				)
				(arc
					(start 331.218032 -428.942754)
					(mid 331.16415 -428.965072)
					(end 331.141832 -429.018954)
				)
				(arc
					(start 331.141832 -429.74641)
					(mid 331.143831 -429.763751)
					(end 331.149706 -429.780192)
				)
				(arc
					(start 331.383132 -430.256442)
					(mid 331.390915 -430.28997)
					(end 331.383132 -430.323498)
				)
				(arc
					(start 331.149706 -430.799748)
					(mid 331.143811 -430.816184)
					(end 331.141832 -430.83353)
				)
			)
		)
	)
	(zone
		(layers "In10.Cu" "In12.Cu")
		(hatch none 0.5)
		(connect_pads
			(clearance 0)
		)
		(min_thickness 0.25)
		(keepout
			(tracks not_allowed)
			(vias allowed)
			(pads allowed)
			(copperpour not_allowed)
			(footprints allowed)
		)
		(placement
			(enabled no)
			(sheetname "")
		)
		(fill yes
			(thermal_gap 0.5)
			(thermal_bridge_width 0.5)
			(island_removal_mode 0)
		)
		(polygon
			(pts
				(arc
					(start 333.141828 -432.560476)
					(mid 333.164146 -432.614358)
					(end 333.218028 -432.636676)
				)
				(arc
					(start 334.157828 -432.636676)
					(mid 334.21171 -432.614358)
					(end 334.234028 -432.560476)
				)
				(arc
					(start 334.234028 -430.018952)
					(mid 334.21171 -429.96507)
					(end 334.157828 -429.942752)
				)
				(arc
					(start 333.218028 -429.942752)
					(mid 333.164146 -429.96507)
					(end 333.141828 -430.018952)
				)
				(arc
					(start 333.141828 -430.746408)
					(mid 333.143827 -430.763749)
					(end 333.149702 -430.78019)
				)
				(arc
					(start 333.383128 -431.25644)
					(mid 333.390911 -431.289968)
					(end 333.383128 -431.323496)
				)
				(arc
					(start 333.149702 -431.799746)
					(mid 333.143807 -431.816182)
					(end 333.141828 -431.833528)
				)
			)
		)
	)
	(zone
		(layers "In10.Cu" "In12.Cu")
		(hatch none 0.5)
		(connect_pads
			(clearance 0)
		)
		(min_thickness 0.25)
		(keepout
			(tracks not_allowed)
			(vias allowed)
			(pads allowed)
			(copperpour not_allowed)
			(footprints allowed)
		)
		(placement
			(enabled no)
			(sheetname "")
		)
		(fill yes
			(thermal_gap 0.5)
			(thermal_bridge_width 0.5)
			(island_removal_mode 0)
		)
		(polygon
			(pts
				(arc
					(start 410.242004 -431.560478)
					(mid 410.264322 -431.61436)
					(end 410.318204 -431.636678)
				)
				(arc
					(start 411.258004 -431.636678)
					(mid 411.311886 -431.61436)
					(end 411.334204 -431.560478)
				)
				(arc
					(start 411.334204 -429.018954)
					(mid 411.311886 -428.965072)
					(end 411.258004 -428.942754)
				)
				(arc
					(start 410.318204 -428.942754)
					(mid 410.264322 -428.965072)
					(end 410.242004 -429.018954)
				)
				(arc
					(start 410.242004 -429.74641)
					(mid 410.244003 -429.763751)
					(end 410.249878 -429.780192)
				)
				(arc
					(start 410.483304 -430.256442)
					(mid 410.491087 -430.28997)
					(end 410.483304 -430.323498)
				)
				(arc
					(start 410.249878 -430.799748)
					(mid 410.243983 -430.816184)
					(end 410.242004 -430.83353)
				)
			)
		)
	)
	(zone
		(layers "In10.Cu" "In12.Cu")
		(hatch none 0.5)
		(connect_pads
			(clearance 0)
		)
		(min_thickness 0.25)
		(keepout
			(tracks not_allowed)
			(vias allowed)
			(pads allowed)
			(copperpour not_allowed)
			(footprints allowed)
		)
		(placement
			(enabled no)
			(sheetname "")
		)
		(fill yes
			(thermal_gap 0.5)
			(thermal_bridge_width 0.5)
			(island_removal_mode 0)
		)
		(polygon
			(pts
				(arc
					(start 148.24202 -432.560476)
					(mid 148.264338 -432.614358)
					(end 148.31822 -432.636676)
				)
				(arc
					(start 149.25802 -432.636676)
					(mid 149.311902 -432.614358)
					(end 149.33422 -432.560476)
				)
				(arc
					(start 149.33422 -430.018952)
					(mid 149.311902 -429.96507)
					(end 149.25802 -429.942752)
				)
				(arc
					(start 148.31822 -429.942752)
					(mid 148.264338 -429.96507)
					(end 148.24202 -430.018952)
				)
				(arc
					(start 148.24202 -430.746408)
					(mid 148.244019 -430.763749)
					(end 148.249894 -430.78019)
				)
				(arc
					(start 148.48332 -431.25644)
					(mid 148.491103 -431.289968)
					(end 148.48332 -431.323496)
				)
				(arc
					(start 148.249894 -431.799746)
					(mid 148.243999 -431.816182)
					(end 148.24202 -431.833528)
				)
			)
		)
	)
	(zone
		(layers "In10.Cu" "In12.Cu")
		(hatch none 0.5)
		(connect_pads
			(clearance 0)
		)
		(min_thickness 0.25)
		(keepout
			(tracks not_allowed)
			(vias allowed)
			(pads allowed)
			(copperpour not_allowed)
			(footprints allowed)
		)
		(placement
			(enabled no)
			(sheetname "")
		)
		(fill yes
			(thermal_gap 0.5)
			(thermal_bridge_width 0.5)
			(island_removal_mode 0)
		)
		(polygon
			(pts
				(arc
					(start 389.241792 -431.560478)
					(mid 389.26411 -431.61436)
					(end 389.317992 -431.636678)
				)
				(arc
					(start 390.257792 -431.636678)
					(mid 390.311674 -431.61436)
					(end 390.333992 -431.560478)
				)
				(arc
					(start 390.333992 -429.018954)
					(mid 390.311674 -428.965072)
					(end 390.257792 -428.942754)
				)
				(arc
					(start 389.317992 -428.942754)
					(mid 389.26411 -428.965072)
					(end 389.241792 -429.018954)
				)
				(arc
					(start 389.241792 -429.74641)
					(mid 389.243791 -429.763751)
					(end 389.249666 -429.780192)
				)
				(arc
					(start 389.483092 -430.256442)
					(mid 389.490875 -430.28997)
					(end 389.483092 -430.323498)
				)
				(arc
					(start 389.249666 -430.799748)
					(mid 389.243771 -430.816184)
					(end 389.241792 -430.83353)
				)
			)
		)
	)
	(zone
		(layers "In10.Cu" "In12.Cu")
		(hatch none 0.5)
		(connect_pads
			(clearance 0)
		)
		(min_thickness 0.25)
		(keepout
			(tracks not_allowed)
			(vias allowed)
			(pads allowed)
			(copperpour not_allowed)
			(footprints allowed)
		)
		(placement
			(enabled no)
			(sheetname "")
		)
		(fill yes
			(thermal_gap 0.5)
			(thermal_bridge_width 0.5)
			(island_removal_mode 0)
		)
		(polygon
			(pts
				(arc
					(start 398.242028 -431.560478)
					(mid 398.264346 -431.61436)
					(end 398.318228 -431.636678)
				)
				(arc
					(start 399.258028 -431.636678)
					(mid 399.31191 -431.61436)
					(end 399.334228 -431.560478)
				)
				(arc
					(start 399.334228 -429.018954)
					(mid 399.31191 -428.965072)
					(end 399.258028 -428.942754)
				)
				(arc
					(start 398.318228 -428.942754)
					(mid 398.264346 -428.965072)
					(end 398.242028 -429.018954)
				)
				(arc
					(start 398.242028 -429.74641)
					(mid 398.244027 -429.763751)
					(end 398.249902 -429.780192)
				)
				(arc
					(start 398.483328 -430.256442)
					(mid 398.491111 -430.28997)
					(end 398.483328 -430.323498)
				)
				(arc
					(start 398.249902 -430.799748)
					(mid 398.244007 -430.816184)
					(end 398.242028 -430.83353)
				)
			)
		)
	)
	(zone
		(layers "In10.Cu" "In12.Cu")
		(hatch none 0.5)
		(connect_pads
			(clearance 0)
		)
		(min_thickness 0.25)
		(keepout
			(tracks not_allowed)
			(vias allowed)
			(pads allowed)
			(copperpour not_allowed)
			(footprints allowed)
		)
		(placement
			(enabled no)
			(sheetname "")
		)
		(fill yes
			(thermal_gap 0.5)
			(thermal_bridge_width 0.5)
			(island_removal_mode 0)
		)
		(polygon
			(pts
				(arc
					(start 393.241784 -431.560478)
					(mid 393.264102 -431.61436)
					(end 393.317984 -431.636678)
				)
				(arc
					(start 394.257784 -431.636678)
					(mid 394.311666 -431.61436)
					(end 394.333984 -431.560478)
				)
				(arc
					(start 394.333984 -429.018954)
					(mid 394.311666 -428.965072)
					(end 394.257784 -428.942754)
				)
				(arc
					(start 393.317984 -428.942754)
					(mid 393.264102 -428.965072)
					(end 393.241784 -429.018954)
				)
				(arc
					(start 393.241784 -429.74641)
					(mid 393.243783 -429.763751)
					(end 393.249658 -429.780192)
				)
				(arc
					(start 393.483084 -430.256442)
					(mid 393.490867 -430.28997)
					(end 393.483084 -430.323498)
				)
				(arc
					(start 393.249658 -430.799748)
					(mid 393.243763 -430.816184)
					(end 393.241784 -430.83353)
				)
			)
		)
	)
	(zone
		(layers "In10.Cu" "In12.Cu")
		(hatch none 0.5)
		(connect_pads
			(clearance 0)
		)
		(min_thickness 0.25)
		(keepout
			(tracks not_allowed)
			(vias allowed)
			(pads allowed)
			(copperpour not_allowed)
			(footprints allowed)
		)
		(placement
			(enabled no)
			(sheetname "")
		)
		(fill yes
			(thermal_gap 0.5)
			(thermal_bridge_width 0.5)
			(island_removal_mode 0)
		)
		(polygon
			(pts
				(arc
					(start 156.242004 -432.560476)
					(mid 156.264322 -432.614358)
					(end 156.318204 -432.636676)
				)
				(arc
					(start 157.258004 -432.636676)
					(mid 157.311886 -432.614358)
					(end 157.334204 -432.560476)
				)
				(arc
					(start 157.334204 -430.018952)
					(mid 157.311886 -429.96507)
					(end 157.258004 -429.942752)
				)
				(arc
					(start 156.318204 -429.942752)
					(mid 156.264322 -429.96507)
					(end 156.242004 -430.018952)
				)
				(arc
					(start 156.242004 -430.746408)
					(mid 156.244003 -430.763749)
					(end 156.249878 -430.78019)
				)
				(arc
					(start 156.483304 -431.25644)
					(mid 156.491087 -431.289968)
					(end 156.483304 -431.323496)
				)
				(arc
					(start 156.249878 -431.799746)
					(mid 156.243983 -431.816182)
					(end 156.242004 -431.833528)
				)
			)
		)
	)
	(zone
		(layers "In10.Cu" "In12.Cu")
		(hatch none 0.5)
		(connect_pads
			(clearance 0)
		)
		(min_thickness 0.25)
		(keepout
			(tracks not_allowed)
			(vias allowed)
			(pads allowed)
			(copperpour not_allowed)
			(footprints allowed)
		)
		(placement
			(enabled no)
			(sheetname "")
		)
		(fill yes
			(thermal_gap 0.5)
			(thermal_bridge_width 0.5)
			(island_removal_mode 0)
		)
		(polygon
			(pts
				(arc
					(start 87.141812 -431.560478)
					(mid 87.16413 -431.61436)
					(end 87.218012 -431.636678)
				)
				(arc
					(start 88.157812 -431.636678)
					(mid 88.211694 -431.61436)
					(end 88.234012 -431.560478)
				)
				(arc
					(start 88.234012 -429.018954)
					(mid 88.211694 -428.965072)
					(end 88.157812 -428.942754)
				)
				(arc
					(start 87.218012 -428.942754)
					(mid 87.16413 -428.965072)
					(end 87.141812 -429.018954)
				)
				(arc
					(start 87.141812 -429.74641)
					(mid 87.143811 -429.763751)
					(end 87.149686 -429.780192)
				)
				(arc
					(start 87.383112 -430.256442)
					(mid 87.390895 -430.28997)
					(end 87.383112 -430.323498)
				)
				(arc
					(start 87.149686 -430.799748)
					(mid 87.143791 -430.816184)
					(end 87.141812 -430.83353)
				)
			)
		)
	)
	(zone
		(layers "In10.Cu" "In12.Cu")
		(hatch none 0.5)
		(connect_pads
			(clearance 0)
		)
		(min_thickness 0.25)
		(keepout
			(tracks not_allowed)
			(vias allowed)
			(pads allowed)
			(copperpour not_allowed)
			(footprints allowed)
		)
		(placement
			(enabled no)
			(sheetname "")
		)
		(fill yes
			(thermal_gap 0.5)
			(thermal_bridge_width 0.5)
			(island_removal_mode 0)
		)
		(polygon
			(pts
				(arc
					(start 142.242032 -431.560478)
					(mid 142.26435 -431.61436)
					(end 142.318232 -431.636678)
				)
				(arc
					(start 143.258032 -431.636678)
					(mid 143.311914 -431.61436)
					(end 143.334232 -431.560478)
				)
				(arc
					(start 143.334232 -429.018954)
					(mid 143.311914 -428.965072)
					(end 143.258032 -428.942754)
				)
				(arc
					(start 142.318232 -428.942754)
					(mid 142.26435 -428.965072)
					(end 142.242032 -429.018954)
				)
				(arc
					(start 142.242032 -429.74641)
					(mid 142.244031 -429.763751)
					(end 142.249906 -429.780192)
				)
				(arc
					(start 142.483332 -430.256442)
					(mid 142.491115 -430.28997)
					(end 142.483332 -430.323498)
				)
				(arc
					(start 142.249906 -430.799748)
					(mid 142.244011 -430.816184)
					(end 142.242032 -430.83353)
				)
			)
		)
	)
	(zone
		(layers "In10.Cu" "In12.Cu")
		(hatch none 0.5)
		(connect_pads
			(clearance 0)
		)
		(min_thickness 0.25)
		(keepout
			(tracks not_allowed)
			(vias allowed)
			(pads allowed)
			(copperpour not_allowed)
			(footprints allowed)
		)
		(placement
			(enabled no)
			(sheetname "")
		)
		(fill yes
			(thermal_gap 0.5)
			(thermal_bridge_width 0.5)
			(island_removal_mode 0)
		)
		(polygon
			(pts
				(arc
					(start 395.24178 -432.560476)
					(mid 395.264098 -432.614358)
					(end 395.31798 -432.636676)
				)
				(arc
					(start 396.25778 -432.636676)
					(mid 396.311662 -432.614358)
					(end 396.33398 -432.560476)
				)
				(arc
					(start 396.33398 -430.018952)
					(mid 396.311662 -429.96507)
					(end 396.25778 -429.942752)
				)
				(arc
					(start 395.31798 -429.942752)
					(mid 395.264098 -429.96507)
					(end 395.24178 -430.018952)
				)
				(arc
					(start 395.24178 -430.746408)
					(mid 395.243779 -430.763749)
					(end 395.249654 -430.78019)
				)
				(arc
					(start 395.48308 -431.25644)
					(mid 395.490863 -431.289968)
					(end 395.48308 -431.323496)
				)
				(arc
					(start 395.249654 -431.799746)
					(mid 395.243759 -431.816182)
					(end 395.24178 -431.833528)
				)
			)
		)
	)
	(zone
		(layers "In10.Cu" "In12.Cu")
		(hatch none 0.5)
		(connect_pads
			(clearance 0)
		)
		(min_thickness 0.25)
		(keepout
			(tracks not_allowed)
			(vias allowed)
			(pads allowed)
			(copperpour not_allowed)
			(footprints allowed)
		)
		(placement
			(enabled no)
			(sheetname "")
		)
		(fill yes
			(thermal_gap 0.5)
			(thermal_bridge_width 0.5)
			(island_removal_mode 0)
		)
		(polygon
			(pts
				(arc
					(start 75.141836 -431.560478)
					(mid 75.164154 -431.61436)
					(end 75.218036 -431.636678)
				)
				(arc
					(start 76.157836 -431.636678)
					(mid 76.211718 -431.61436)
					(end 76.234036 -431.560478)
				)
				(arc
					(start 76.234036 -429.018954)
					(mid 76.211718 -428.965072)
					(end 76.157836 -428.942754)
				)
				(arc
					(start 75.218036 -428.942754)
					(mid 75.164154 -428.965072)
					(end 75.141836 -429.018954)
				)
				(arc
					(start 75.141836 -429.74641)
					(mid 75.143835 -429.763751)
					(end 75.14971 -429.780192)
				)
				(arc
					(start 75.383136 -430.256442)
					(mid 75.390919 -430.28997)
					(end 75.383136 -430.323498)
				)
				(arc
					(start 75.14971 -430.799748)
					(mid 75.143815 -430.816184)
					(end 75.141836 -430.83353)
				)
			)
		)
	)
	(zone
		(layers "In10.Cu" "In12.Cu")
		(hatch none 0.5)
		(connect_pads
			(clearance 0)
		)
		(min_thickness 0.25)
		(keepout
			(tracks not_allowed)
			(vias allowed)
			(pads allowed)
			(copperpour not_allowed)
			(footprints allowed)
		)
		(placement
			(enabled no)
			(sheetname "")
		)
		(fill yes
			(thermal_gap 0.5)
			(thermal_bridge_width 0.5)
			(island_removal_mode 0)
		)
		(polygon
			(pts
				(arc
					(start 83.14182 -431.560478)
					(mid 83.164138 -431.61436)
					(end 83.21802 -431.636678)
				)
				(arc
					(start 84.15782 -431.636678)
					(mid 84.211702 -431.61436)
					(end 84.23402 -431.560478)
				)
				(arc
					(start 84.23402 -429.018954)
					(mid 84.211702 -428.965072)
					(end 84.15782 -428.942754)
				)
				(arc
					(start 83.21802 -428.942754)
					(mid 83.164138 -428.965072)
					(end 83.14182 -429.018954)
				)
				(arc
					(start 83.14182 -429.74641)
					(mid 83.143819 -429.763751)
					(end 83.149694 -429.780192)
				)
				(arc
					(start 83.38312 -430.256442)
					(mid 83.390903 -430.28997)
					(end 83.38312 -430.323498)
				)
				(arc
					(start 83.149694 -430.799748)
					(mid 83.143799 -430.816184)
					(end 83.14182 -430.83353)
				)
			)
		)
	)
	(zone
		(layers "In10.Cu" "In12.Cu")
		(hatch none 0.5)
		(connect_pads
			(clearance 0)
		)
		(min_thickness 0.25)
		(keepout
			(tracks not_allowed)
			(vias allowed)
			(pads allowed)
			(copperpour not_allowed)
			(footprints allowed)
		)
		(placement
			(enabled no)
			(sheetname "")
		)
		(fill yes
			(thermal_gap 0.5)
			(thermal_bridge_width 0.5)
			(island_removal_mode 0)
		)
		(polygon
			(pts
				(arc
					(start 152.242012 -432.560476)
					(mid 152.26433 -432.614358)
					(end 152.318212 -432.636676)
				)
				(arc
					(start 153.258012 -432.636676)
					(mid 153.311894 -432.614358)
					(end 153.334212 -432.560476)
				)
				(arc
					(start 153.334212 -430.018952)
					(mid 153.311894 -429.96507)
					(end 153.258012 -429.942752)
				)
				(arc
					(start 152.318212 -429.942752)
					(mid 152.26433 -429.96507)
					(end 152.242012 -430.018952)
				)
				(arc
					(start 152.242012 -430.746408)
					(mid 152.244011 -430.763749)
					(end 152.249886 -430.78019)
				)
				(arc
					(start 152.483312 -431.25644)
					(mid 152.491095 -431.289968)
					(end 152.483312 -431.323496)
				)
				(arc
					(start 152.249886 -431.799746)
					(mid 152.243991 -431.816182)
					(end 152.242012 -431.833528)
				)
			)
		)
	)
	(zone
		(layers "In10.Cu" "In12.Cu")
		(hatch none 0.5)
		(connect_pads
			(clearance 0)
		)
		(min_thickness 0.25)
		(keepout
			(tracks not_allowed)
			(vias allowed)
			(pads allowed)
			(copperpour not_allowed)
			(footprints allowed)
		)
		(placement
			(enabled no)
			(sheetname "")
		)
		(fill yes
			(thermal_gap 0.5)
			(thermal_bridge_width 0.5)
			(island_removal_mode 0)
		)
		(polygon
			(pts
				(arc
					(start 127.241808 -432.560476)
					(mid 127.264126 -432.614358)
					(end 127.318008 -432.636676)
				)
				(arc
					(start 128.257808 -432.636676)
					(mid 128.31169 -432.614358)
					(end 128.334008 -432.560476)
				)
				(arc
					(start 128.334008 -430.018952)
					(mid 128.31169 -429.96507)
					(end 128.257808 -429.942752)
				)
				(arc
					(start 127.318008 -429.942752)
					(mid 127.264126 -429.96507)
					(end 127.241808 -430.018952)
				)
				(arc
					(start 127.241808 -430.746408)
					(mid 127.243807 -430.763749)
					(end 127.249682 -430.78019)
				)
				(arc
					(start 127.483108 -431.25644)
					(mid 127.490891 -431.289968)
					(end 127.483108 -431.323496)
				)
				(arc
					(start 127.249682 -431.799746)
					(mid 127.243787 -431.816182)
					(end 127.241808 -431.833528)
				)
			)
		)
	)
	(zone
		(layers "In10.Cu" "In12.Cu")
		(hatch none 0.5)
		(connect_pads
			(clearance 0)
		)
		(min_thickness 0.25)
		(keepout
			(tracks not_allowed)
			(vias allowed)
			(pads allowed)
			(copperpour not_allowed)
			(footprints allowed)
		)
		(placement
			(enabled no)
			(sheetname "")
		)
		(fill yes
			(thermal_gap 0.5)
			(thermal_bridge_width 0.5)
			(island_removal_mode 0)
		)
		(polygon
			(pts
				(arc
					(start 324.141592 -432.560476)
					(mid 324.16391 -432.614358)
					(end 324.217792 -432.636676)
				)
				(arc
					(start 325.157592 -432.636676)
					(mid 325.211474 -432.614358)
					(end 325.233792 -432.560476)
				)
				(arc
					(start 325.233792 -430.018952)
					(mid 325.211474 -429.96507)
					(end 325.157592 -429.942752)
				)
				(arc
					(start 324.217792 -429.942752)
					(mid 324.16391 -429.96507)
					(end 324.141592 -430.018952)
				)
				(arc
					(start 324.141592 -430.746408)
					(mid 324.143591 -430.763749)
					(end 324.149466 -430.78019)
				)
				(arc
					(start 324.382892 -431.25644)
					(mid 324.390675 -431.289968)
					(end 324.382892 -431.323496)
				)
				(arc
					(start 324.149466 -431.799746)
					(mid 324.143571 -431.816182)
					(end 324.141592 -431.833528)
				)
			)
		)
	)
	(zone
		(layers "In10.Cu" "In12.Cu")
		(hatch none 0.5)
		(connect_pads
			(clearance 0)
		)
		(min_thickness 0.25)
		(keepout
			(tracks not_allowed)
			(vias allowed)
			(pads allowed)
			(copperpour not_allowed)
			(footprints allowed)
		)
		(placement
			(enabled no)
			(sheetname "")
		)
		(fill yes
			(thermal_gap 0.5)
			(thermal_bridge_width 0.5)
			(island_removal_mode 0)
		)
		(polygon
			(pts
				(arc
					(start 339.141816 -431.560478)
					(mid 339.164134 -431.61436)
					(end 339.218016 -431.636678)
				)
				(arc
					(start 340.157816 -431.636678)
					(mid 340.211698 -431.61436)
					(end 340.234016 -431.560478)
				)
				(arc
					(start 340.234016 -429.018954)
					(mid 340.211698 -428.965072)
					(end 340.157816 -428.942754)
				)
				(arc
					(start 339.218016 -428.942754)
					(mid 339.164134 -428.965072)
					(end 339.141816 -429.018954)
				)
				(arc
					(start 339.141816 -429.74641)
					(mid 339.143815 -429.763751)
					(end 339.14969 -429.780192)
				)
				(arc
					(start 339.383116 -430.256442)
					(mid 339.390899 -430.28997)
					(end 339.383116 -430.323498)
				)
				(arc
					(start 339.14969 -430.799748)
					(mid 339.143795 -430.816184)
					(end 339.141816 -430.83353)
				)
			)
		)
	)
	(zone
		(layers "In10.Cu" "In12.Cu")
		(hatch none 0.5)
		(connect_pads
			(clearance 0)
		)
		(min_thickness 0.25)
		(keepout
			(tracks not_allowed)
			(vias allowed)
			(pads allowed)
			(copperpour not_allowed)
			(footprints allowed)
		)
		(placement
			(enabled no)
			(sheetname "")
		)
		(fill yes
			(thermal_gap 0.5)
			(thermal_bridge_width 0.5)
			(island_removal_mode 0)
		)
		(polygon
			(pts
				(arc
					(start 58.14187 -431.560478)
					(mid 58.164188 -431.61436)
					(end 58.21807 -431.636678)
				)
				(arc
					(start 59.15787 -431.636678)
					(mid 59.211752 -431.61436)
					(end 59.23407 -431.560478)
				)
				(arc
					(start 59.23407 -429.018954)
					(mid 59.211752 -428.965072)
					(end 59.15787 -428.942754)
				)
				(arc
					(start 58.21807 -428.942754)
					(mid 58.164188 -428.965072)
					(end 58.14187 -429.018954)
				)
				(arc
					(start 58.14187 -429.74641)
					(mid 58.143869 -429.763751)
					(end 58.149744 -429.780192)
				)
				(arc
					(start 58.38317 -430.256442)
					(mid 58.390953 -430.28997)
					(end 58.38317 -430.323498)
				)
				(arc
					(start 58.149744 -430.799748)
					(mid 58.143849 -430.816184)
					(end 58.14187 -430.83353)
				)
			)
		)
	)
	(zone
		(layers "In10.Cu" "In12.Cu")
		(hatch none 0.5)
		(connect_pads
			(clearance 0)
		)
		(min_thickness 0.25)
		(keepout
			(tracks not_allowed)
			(vias allowed)
			(pads allowed)
			(copperpour not_allowed)
			(footprints allowed)
		)
		(placement
			(enabled no)
			(sheetname "")
		)
		(fill yes
			(thermal_gap 0.5)
			(thermal_bridge_width 0.5)
			(island_removal_mode 0)
		)
		(polygon
			(pts
				(arc
					(start 129.241804 -431.560478)
					(mid 129.264122 -431.61436)
					(end 129.318004 -431.636678)
				)
				(arc
					(start 130.257804 -431.636678)
					(mid 130.311686 -431.61436)
					(end 130.334004 -431.560478)
				)
				(arc
					(start 130.334004 -429.018954)
					(mid 130.311686 -428.965072)
					(end 130.257804 -428.942754)
				)
				(arc
					(start 129.318004 -428.942754)
					(mid 129.264122 -428.965072)
					(end 129.241804 -429.018954)
				)
				(arc
					(start 129.241804 -429.74641)
					(mid 129.243803 -429.763751)
					(end 129.249678 -429.780192)
				)
				(arc
					(start 129.483104 -430.256442)
					(mid 129.490887 -430.28997)
					(end 129.483104 -430.323498)
				)
				(arc
					(start 129.249678 -430.799748)
					(mid 129.243783 -430.816184)
					(end 129.241804 -430.83353)
				)
			)
		)
	)
	(zone
		(layers "In10.Cu" "In12.Cu")
		(hatch none 0.5)
		(connect_pads
			(clearance 0)
		)
		(min_thickness 0.25)
		(keepout
			(tracks not_allowed)
			(vias allowed)
			(pads allowed)
			(copperpour not_allowed)
			(footprints allowed)
		)
		(placement
			(enabled no)
			(sheetname "")
		)
		(fill yes
			(thermal_gap 0.5)
			(thermal_bridge_width 0.5)
			(island_removal_mode 0)
		)
		(polygon
			(pts
				(arc
					(start 320.1416 -432.560476)
					(mid 320.163918 -432.614358)
					(end 320.2178 -432.636676)
				)
				(arc
					(start 321.1576 -432.636676)
					(mid 321.211482 -432.614358)
					(end 321.2338 -432.560476)
				)
				(arc
					(start 321.2338 -430.018952)
					(mid 321.211482 -429.96507)
					(end 321.1576 -429.942752)
				)
				(arc
					(start 320.2178 -429.942752)
					(mid 320.163918 -429.96507)
					(end 320.1416 -430.018952)
				)
				(arc
					(start 320.1416 -430.746408)
					(mid 320.143599 -430.763749)
					(end 320.149474 -430.78019)
				)
				(arc
					(start 320.3829 -431.25644)
					(mid 320.390683 -431.289968)
					(end 320.3829 -431.323496)
				)
				(arc
					(start 320.149474 -431.799746)
					(mid 320.143579 -431.816182)
					(end 320.1416 -431.833528)
				)
			)
		)
	)
	(zone
		(layers "In10.Cu" "In12.Cu")
		(hatch none 0.5)
		(connect_pads
			(clearance 0)
		)
		(min_thickness 0.25)
		(keepout
			(tracks not_allowed)
			(vias allowed)
			(pads allowed)
			(copperpour not_allowed)
			(footprints allowed)
		)
		(placement
			(enabled no)
			(sheetname "")
		)
		(fill yes
			(thermal_gap 0.5)
			(thermal_bridge_width 0.5)
			(island_removal_mode 0)
		)
		(polygon
			(pts
				(arc
					(start 137.241788 -431.560478)
					(mid 137.264106 -431.61436)
					(end 137.317988 -431.636678)
				)
				(arc
					(start 138.257788 -431.636678)
					(mid 138.31167 -431.61436)
					(end 138.333988 -431.560478)
				)
				(arc
					(start 138.333988 -429.018954)
					(mid 138.31167 -428.965072)
					(end 138.257788 -428.942754)
				)
				(arc
					(start 137.317988 -428.942754)
					(mid 137.264106 -428.965072)
					(end 137.241788 -429.018954)
				)
				(arc
					(start 137.241788 -429.74641)
					(mid 137.243787 -429.763751)
					(end 137.249662 -429.780192)
				)
				(arc
					(start 137.483088 -430.256442)
					(mid 137.490871 -430.28997)
					(end 137.483088 -430.323498)
				)
				(arc
					(start 137.249662 -430.799748)
					(mid 137.243767 -430.816184)
					(end 137.241788 -430.83353)
				)
			)
		)
	)
	(zone
		(layers "In10.Cu" "In12.Cu")
		(hatch none 0.5)
		(connect_pads
			(clearance 0)
		)
		(min_thickness 0.25)
		(keepout
			(tracks not_allowed)
			(vias allowed)
			(pads allowed)
			(copperpour not_allowed)
			(footprints allowed)
		)
		(placement
			(enabled no)
			(sheetname "")
		)
		(fill yes
			(thermal_gap 0.5)
			(thermal_bridge_width 0.5)
			(island_removal_mode 0)
		)
		(polygon
			(pts
				(arc
					(start 381.241808 -431.560478)
					(mid 381.264126 -431.61436)
					(end 381.318008 -431.636678)
				)
				(arc
					(start 382.257808 -431.636678)
					(mid 382.31169 -431.61436)
					(end 382.334008 -431.560478)
				)
				(arc
					(start 382.334008 -429.018954)
					(mid 382.31169 -428.965072)
					(end 382.257808 -428.942754)
				)
				(arc
					(start 381.318008 -428.942754)
					(mid 381.264126 -428.965072)
					(end 381.241808 -429.018954)
				)
				(arc
					(start 381.241808 -429.74641)
					(mid 381.243807 -429.763751)
					(end 381.249682 -429.780192)
				)
				(arc
					(start 381.483108 -430.256442)
					(mid 381.490891 -430.28997)
					(end 381.483108 -430.323498)
				)
				(arc
					(start 381.249682 -430.799748)
					(mid 381.243787 -430.816184)
					(end 381.241808 -430.83353)
				)
			)
		)
	)
	(zone
		(layers "In10.Cu" "In12.Cu")
		(hatch none 0.5)
		(connect_pads
			(clearance 0)
		)
		(min_thickness 0.25)
		(keepout
			(tracks not_allowed)
			(vias allowed)
			(pads allowed)
			(copperpour not_allowed)
			(footprints allowed)
		)
		(placement
			(enabled no)
			(sheetname "")
		)
		(fill yes
			(thermal_gap 0.5)
			(thermal_bridge_width 0.5)
			(island_removal_mode 0)
		)
		(polygon
			(pts
				(arc
					(start 345.141804 -432.560476)
					(mid 345.164122 -432.614358)
					(end 345.218004 -432.636676)
				)
				(arc
					(start 346.157804 -432.636676)
					(mid 346.211686 -432.614358)
					(end 346.234004 -432.560476)
				)
				(arc
					(start 346.234004 -430.018952)
					(mid 346.211686 -429.96507)
					(end 346.157804 -429.942752)
				)
				(arc
					(start 345.218004 -429.942752)
					(mid 345.164122 -429.96507)
					(end 345.141804 -430.018952)
				)
				(arc
					(start 345.141804 -430.746408)
					(mid 345.143803 -430.763749)
					(end 345.149678 -430.78019)
				)
				(arc
					(start 345.383104 -431.25644)
					(mid 345.390887 -431.289968)
					(end 345.383104 -431.323496)
				)
				(arc
					(start 345.149678 -431.799746)
					(mid 345.143783 -431.816182)
					(end 345.141804 -431.833528)
				)
			)
		)
	)
	(zone
		(layers "In10.Cu" "In12.Cu")
		(hatch none 0.5)
		(connect_pads
			(clearance 0)
		)
		(min_thickness 0.25)
		(keepout
			(tracks not_allowed)
			(vias allowed)
			(pads allowed)
			(copperpour not_allowed)
			(footprints allowed)
		)
		(placement
			(enabled no)
			(sheetname "")
		)
		(fill yes
			(thermal_gap 0.5)
			(thermal_bridge_width 0.5)
			(island_removal_mode 0)
		)
		(polygon
			(pts
				(arc
					(start 318.141604 -431.560478)
					(mid 318.163922 -431.61436)
					(end 318.217804 -431.636678)
				)
				(arc
					(start 319.157604 -431.636678)
					(mid 319.211486 -431.61436)
					(end 319.233804 -431.560478)
				)
				(arc
					(start 319.233804 -429.018954)
					(mid 319.211486 -428.965072)
					(end 319.157604 -428.942754)
				)
				(arc
					(start 318.217804 -428.942754)
					(mid 318.163922 -428.965072)
					(end 318.141604 -429.018954)
				)
				(arc
					(start 318.141604 -429.74641)
					(mid 318.143603 -429.763751)
					(end 318.149478 -429.780192)
				)
				(arc
					(start 318.382904 -430.256442)
					(mid 318.390687 -430.28997)
					(end 318.382904 -430.323498)
				)
				(arc
					(start 318.149478 -430.799748)
					(mid 318.143583 -430.816184)
					(end 318.141604 -430.83353)
				)
			)
		)
	)
	(zone
		(layers "In10.Cu" "In12.Cu")
		(hatch none 0.5)
		(connect_pads
			(clearance 0)
		)
		(min_thickness 0.25)
		(keepout
			(tracks not_allowed)
			(vias allowed)
			(pads allowed)
			(copperpour not_allowed)
			(footprints allowed)
		)
		(placement
			(enabled no)
			(sheetname "")
		)
		(fill yes
			(thermal_gap 0.5)
			(thermal_bridge_width 0.5)
			(island_removal_mode 0)
		)
		(polygon
			(pts
				(arc
					(start 343.141808 -431.560478)
					(mid 343.164126 -431.61436)
					(end 343.218008 -431.636678)
				)
				(arc
					(start 344.157808 -431.636678)
					(mid 344.21169 -431.61436)
					(end 344.234008 -431.560478)
				)
				(arc
					(start 344.234008 -429.018954)
					(mid 344.21169 -428.965072)
					(end 344.157808 -428.942754)
				)
				(arc
					(start 343.218008 -428.942754)
					(mid 343.164126 -428.965072)
					(end 343.141808 -429.018954)
				)
				(arc
					(start 343.141808 -429.74641)
					(mid 343.143807 -429.763751)
					(end 343.149682 -429.780192)
				)
				(arc
					(start 343.383108 -430.256442)
					(mid 343.390891 -430.28997)
					(end 343.383108 -430.323498)
				)
				(arc
					(start 343.149682 -430.799748)
					(mid 343.143787 -430.816184)
					(end 343.141808 -430.83353)
				)
			)
		)
	)
	(zone
		(layers "In10.Cu" "In12.Cu")
		(hatch none 0.5)
		(connect_pads
			(clearance 0)
		)
		(min_thickness 0.25)
		(keepout
			(tracks not_allowed)
			(vias allowed)
			(pads allowed)
			(copperpour not_allowed)
			(footprints allowed)
		)
		(placement
			(enabled no)
			(sheetname "")
		)
		(fill yes
			(thermal_gap 0.5)
			(thermal_bridge_width 0.5)
			(island_removal_mode 0)
		)
		(polygon
			(pts
				(arc
					(start 60.141866 -432.560476)
					(mid 60.164184 -432.614358)
					(end 60.218066 -432.636676)
				)
				(arc
					(start 61.157866 -432.636676)
					(mid 61.211748 -432.614358)
					(end 61.234066 -432.560476)
				)
				(arc
					(start 61.234066 -430.018952)
					(mid 61.211748 -429.96507)
					(end 61.157866 -429.942752)
				)
				(arc
					(start 60.218066 -429.942752)
					(mid 60.164184 -429.96507)
					(end 60.141866 -430.018952)
				)
				(arc
					(start 60.141866 -430.746408)
					(mid 60.143865 -430.763749)
					(end 60.14974 -430.78019)
				)
				(arc
					(start 60.383166 -431.25644)
					(mid 60.390949 -431.289968)
					(end 60.383166 -431.323496)
				)
				(arc
					(start 60.14974 -431.799746)
					(mid 60.143845 -431.816182)
					(end 60.141866 -431.833528)
				)
			)
		)
	)
	(zone
		(layers "In10.Cu" "In12.Cu")
		(hatch none 0.5)
		(connect_pads
			(clearance 0)
		)
		(min_thickness 0.25)
		(keepout
			(tracks not_allowed)
			(vias allowed)
			(pads allowed)
			(copperpour not_allowed)
			(footprints allowed)
		)
		(placement
			(enabled no)
			(sheetname "")
		)
		(fill yes
			(thermal_gap 0.5)
			(thermal_bridge_width 0.5)
			(island_removal_mode 0)
		)
		(polygon
			(pts
				(arc
					(start 154.242008 -431.560478)
					(mid 154.264326 -431.61436)
					(end 154.318208 -431.636678)
				)
				(arc
					(start 155.258008 -431.636678)
					(mid 155.31189 -431.61436)
					(end 155.334208 -431.560478)
				)
				(arc
					(start 155.334208 -429.018954)
					(mid 155.31189 -428.965072)
					(end 155.258008 -428.942754)
				)
				(arc
					(start 154.318208 -428.942754)
					(mid 154.264326 -428.965072)
					(end 154.242008 -429.018954)
				)
				(arc
					(start 154.242008 -429.74641)
					(mid 154.244007 -429.763751)
					(end 154.249882 -429.780192)
				)
				(arc
					(start 154.483308 -430.256442)
					(mid 154.491091 -430.28997)
					(end 154.483308 -430.323498)
				)
				(arc
					(start 154.249882 -430.799748)
					(mid 154.243987 -430.816184)
					(end 154.242008 -430.83353)
				)
			)
		)
	)
	(zone
		(layer "In11.Cu")
		(hatch none 0.5)
		(connect_pads
			(clearance 0)
		)
		(min_thickness 0.25)
		(keepout
			(tracks allowed)
			(vias allowed)
			(pads allowed)
			(copperpour allowed)
			(footprints allowed)
		)
		(placement
			(enabled no)
			(sheetname "")
		)
		(fill
			(thermal_gap 0.5)
			(thermal_bridge_width 0.5)
			(island_removal_mode 0)
		)
		(polygon
			(pts
				(xy 391.481818 -178.251612) (xy 391.481818 -179.089812) (xy 391.278618 -179.089812) (xy 391.278618 -178.251612)
			)
		)
	)
	(zone
		(layer "In11.Cu")
		(hatch none 0.5)
		(connect_pads
			(clearance 0)
		)
		(min_thickness 0.25)
		(keepout
			(tracks allowed)
			(vias allowed)
			(pads allowed)
			(copperpour allowed)
			(footprints allowed)
		)
		(placement
			(enabled no)
			(sheetname "")
		)
		(fill
			(thermal_gap 0.5)
			(thermal_bridge_width 0.5)
			(island_removal_mode 0)
		)
		(polygon
			(pts
				(xy 47.935134 -347.661992) (xy 47.935134 -348.375732) (xy 47.749714 -348.375732) (xy 47.749714 -347.661992)
			)
		)
	)
	(zone
		(layer "In11.Cu")
		(hatch none 0.5)
		(connect_pads
			(clearance 0)
		)
		(min_thickness 0.25)
		(keepout
			(tracks allowed)
			(vias allowed)
			(pads allowed)
			(copperpour allowed)
			(footprints allowed)
		)
		(placement
			(enabled no)
			(sheetname "")
		)
		(fill
			(thermal_gap 0.5)
			(thermal_bridge_width 0.5)
			(island_removal_mode 0)
		)
		(polygon
			(pts
				(xy 48.567594 -355.091492) (xy 46.972474 -353.496372) (xy 34.554414 -353.496372) (xy 33.048194 -351.990152)
				(xy 33.048194 -351.398332) (xy 33.180274 -351.266252) (xy 33.180274 -350.511872) (xy 32.956754 -350.288352)
				(xy 32.639254 -350.288352) (xy 32.151574 -350.776032) (xy 32.151574 -352.322892) (xy 34.102294 -354.273612)
				(xy 46.510194 -354.273612) (xy 47.607474 -355.370892) (xy 48.435514 -355.370892) (xy 48.567594 -355.238812)
			)
		)
	)
	(zone
		(layer "In11.Cu")
		(hatch none 0.5)
		(connect_pads
			(clearance 0)
		)
		(min_thickness 0.25)
		(keepout
			(tracks not_allowed)
			(vias allowed)
			(pads allowed)
			(copperpour not_allowed)
			(footprints allowed)
		)
		(placement
			(enabled no)
			(sheetname "")
		)
		(fill
			(thermal_gap 0.5)
			(thermal_bridge_width 0.5)
			(island_removal_mode 0)
		)
		(polygon
			(pts
				(arc
					(start 316.141862 -428.960788)
					(mid 316.16418 -429.01467)
					(end 316.218062 -429.036988)
				)
				(arc
					(start 317.157862 -429.036988)
					(mid 317.211744 -429.01467)
					(end 317.234062 -428.960788)
				)
				(arc
					(start 317.234062 -426.419264)
					(mid 317.211744 -426.365382)
					(end 317.157862 -426.343064)
				)
				(arc
					(start 316.218062 -426.343064)
					(mid 316.16418 -426.365382)
					(end 316.141862 -426.419264)
				)
			)
		)
	)
	(zone
		(layer "In11.Cu")
		(hatch none 0.5)
		(connect_pads
			(clearance 0)
		)
		(min_thickness 0.25)
		(keepout
			(tracks not_allowed)
			(vias allowed)
			(pads allowed)
			(copperpour not_allowed)
			(footprints allowed)
		)
		(placement
			(enabled no)
			(sheetname "")
		)
		(fill
			(thermal_gap 0.5)
			(thermal_bridge_width 0.5)
			(island_removal_mode 0)
		)
		(polygon
			(pts
				(arc
					(start 81.141824 -428.960788)
					(mid 81.164142 -429.01467)
					(end 81.218024 -429.036988)
				)
				(arc
					(start 82.157824 -429.036988)
					(mid 82.211706 -429.01467)
					(end 82.234024 -428.960788)
				)
				(arc
					(start 82.234024 -426.419264)
					(mid 82.211706 -426.365382)
					(end 82.157824 -426.343064)
				)
				(arc
					(start 81.218024 -426.343064)
					(mid 81.164142 -426.365382)
					(end 81.141824 -426.419264)
				)
			)
		)
	)
	(zone
		(layer "In11.Cu")
		(hatch none 0.5)
		(connect_pads
			(clearance 0)
		)
		(min_thickness 0.25)
		(keepout
			(tracks allowed)
			(vias allowed)
			(pads allowed)
			(copperpour allowed)
			(footprints allowed)
		)
		(placement
			(enabled no)
			(sheetname "")
		)
		(fill
			(thermal_gap 0.5)
			(thermal_bridge_width 0.5)
			(island_removal_mode 0)
		)
		(polygon
			(pts
				(xy 89.860374 -335.838292) (xy 89.860374 -336.816192) (xy 89.702894 -336.816192) (xy 89.702894 -335.838292)
			)
		)
	)
	(zone
		(layer "In11.Cu")
		(hatch none 0.5)
		(connect_pads
			(clearance 0)
		)
		(min_thickness 0.25)
		(keepout
			(tracks not_allowed)
			(vias allowed)
			(pads allowed)
			(copperpour not_allowed)
			(footprints allowed)
		)
		(placement
			(enabled no)
			(sheetname "")
		)
		(fill
			(thermal_gap 0.5)
			(thermal_bridge_width 0.5)
			(island_removal_mode 0)
		)
		(polygon
			(pts
				(arc
					(start 85.141816 -428.960788)
					(mid 85.164134 -429.01467)
					(end 85.218016 -429.036988)
				)
				(arc
					(start 86.157816 -429.036988)
					(mid 86.211698 -429.01467)
					(end 86.234016 -428.960788)
				)
				(arc
					(start 86.234016 -426.419264)
					(mid 86.211698 -426.365382)
					(end 86.157816 -426.343064)
				)
				(arc
					(start 85.218016 -426.343064)
					(mid 85.164134 -426.365382)
					(end 85.141816 -426.419264)
				)
			)
		)
	)
	(zone
		(layer "In11.Cu")
		(hatch none 0.5)
		(connect_pads
			(clearance 0)
		)
		(min_thickness 0.25)
		(keepout
			(tracks allowed)
			(vias allowed)
			(pads allowed)
			(copperpour allowed)
			(footprints allowed)
		)
		(placement
			(enabled no)
			(sheetname "")
		)
		(fill
			(thermal_gap 0.5)
			(thermal_bridge_width 0.5)
			(island_removal_mode 0)
		)
		(polygon
			(pts
				(xy 243.480082 -394.16863) (xy 243.480082 -393.611862) (xy 244.707664 -393.611862) (xy 244.707664 -394.16863)
			)
		)
	)
	(zone
		(layer "In11.Cu")
		(hatch none 0.5)
		(connect_pads
			(clearance 0)
		)
		(min_thickness 0.25)
		(keepout
			(tracks allowed)
			(vias allowed)
			(pads allowed)
			(copperpour allowed)
			(footprints allowed)
		)
		(placement
			(enabled no)
			(sheetname "")
		)
		(fill
			(thermal_gap 0.5)
			(thermal_bridge_width 0.5)
			(island_removal_mode 0)
		)
		(polygon
			(pts
				(xy 92.166694 -148.292312) (xy 91.506294 -148.292312) (xy 89.194894 -150.603712) (xy 85.435694 -150.603712)
				(xy 79.263494 -156.775912) (xy 69.840094 -156.775912) (xy 67.655694 -158.960312) (xy 67.655694 -163.989512)
				(xy 67.909694 -164.243512) (xy 67.909694 -165.157912) (xy 67.935094 -165.183312) (xy 68.087494 -165.183312)
				(xy 68.519294 -164.751512) (xy 68.519294 -159.290512) (xy 70.221094 -157.588712) (xy 79.644494 -157.588712)
				(xy 85.918294 -151.314912) (xy 89.550494 -151.314912) (xy 91.811094 -149.054312) (xy 92.192094 -149.054312)
				(xy 92.319094 -148.927312) (xy 92.319094 -148.444712)
			)
		)
	)
	(zone
		(layer "In11.Cu")
		(hatch none 0.5)
		(connect_pads
			(clearance 0)
		)
		(min_thickness 0.25)
		(keepout
			(tracks allowed)
			(vias allowed)
			(pads allowed)
			(copperpour allowed)
			(footprints allowed)
		)
		(placement
			(enabled no)
			(sheetname "")
		)
		(fill
			(thermal_gap 0.5)
			(thermal_bridge_width 0.5)
			(island_removal_mode 0)
		)
		(polygon
			(pts
				(xy 259.53593 -394.172694) (xy 259.53593 -393.615926) (xy 260.763512 -393.615926) (xy 260.763512 -394.172694)
			)
		)
	)
	(zone
		(layer "In11.Cu")
		(hatch none 0.5)
		(connect_pads
			(clearance 0)
		)
		(min_thickness 0.25)
		(keepout
			(tracks not_allowed)
			(vias allowed)
			(pads allowed)
			(copperpour not_allowed)
			(footprints allowed)
		)
		(placement
			(enabled no)
			(sheetname "")
		)
		(fill
			(thermal_gap 0.5)
			(thermal_bridge_width 0.5)
			(island_removal_mode 0)
		)
		(polygon
			(pts
				(arc
					(start 337.14182 -428.960788)
					(mid 337.164138 -429.01467)
					(end 337.21802 -429.036988)
				)
				(arc
					(start 338.15782 -429.036988)
					(mid 338.211702 -429.01467)
					(end 338.23402 -428.960788)
				)
				(arc
					(start 338.23402 -426.419264)
					(mid 338.211702 -426.365382)
					(end 338.15782 -426.343064)
				)
				(arc
					(start 337.21802 -426.343064)
					(mid 337.164138 -426.365382)
					(end 337.14182 -426.419264)
				)
			)
		)
	)
	(zone
		(layer "In11.Cu")
		(hatch none 0.5)
		(connect_pads
			(clearance 0)
		)
		(min_thickness 0.25)
		(keepout
			(tracks allowed)
			(vias allowed)
			(pads allowed)
			(copperpour allowed)
			(footprints allowed)
		)
		(placement
			(enabled no)
			(sheetname "")
		)
		(fill
			(thermal_gap 0.5)
			(thermal_bridge_width 0.5)
			(island_removal_mode 0)
		)
		(polygon
			(pts
				(xy 98.135694 -340.839552) (xy 98.135694 -341.644732) (xy 97.950274 -341.644732) (xy 97.950274 -340.839552)
			)
		)
	)
	(zone
		(layer "In11.Cu")
		(hatch none 0.5)
		(connect_pads
			(clearance 0)
		)
		(min_thickness 0.25)
		(keepout
			(tracks allowed)
			(vias allowed)
			(pads allowed)
			(copperpour allowed)
			(footprints allowed)
		)
		(placement
			(enabled no)
			(sheetname "")
		)
		(fill
			(thermal_gap 0.5)
			(thermal_bridge_width 0.5)
			(island_removal_mode 0)
		)
		(polygon
			(pts
				(xy 374.717818 -178.175412) (xy 374.717818 -179.039012) (xy 374.514618 -179.039012) (xy 374.514618 -178.175412)
			)
		)
	)
	(zone
		(layer "In11.Cu")
		(hatch none 0.5)
		(connect_pads
			(clearance 0)
		)
		(min_thickness 0.25)
		(keepout
			(tracks allowed)
			(vias allowed)
			(pads allowed)
			(copperpour allowed)
			(footprints allowed)
		)
		(placement
			(enabled no)
			(sheetname "")
		)
		(fill
			(thermal_gap 0.5)
			(thermal_bridge_width 0.5)
			(island_removal_mode 0)
		)
		(polygon
			(pts
				(xy 81.519014 -335.878932) (xy 81.519014 -336.656172) (xy 81.336134 -336.656172) (xy 81.336134 -335.878932)
			)
		)
	)
	(zone
		(layer "In11.Cu")
		(hatch none 0.5)
		(connect_pads
			(clearance 0)
		)
		(min_thickness 0.25)
		(keepout
			(tracks not_allowed)
			(vias allowed)
			(pads allowed)
			(copperpour not_allowed)
			(footprints allowed)
		)
		(placement
			(enabled no)
			(sheetname "")
		)
		(fill
			(thermal_gap 0.5)
			(thermal_bridge_width 0.5)
			(island_removal_mode 0)
		)
		(polygon
			(pts
				(arc
					(start 144.241774 -428.960788)
					(mid 144.264092 -429.01467)
					(end 144.317974 -429.036988)
				)
				(arc
					(start 145.257774 -429.036988)
					(mid 145.311656 -429.01467)
					(end 145.333974 -428.960788)
				)
				(arc
					(start 145.333974 -426.419264)
					(mid 145.311656 -426.365382)
					(end 145.257774 -426.343064)
				)
				(arc
					(start 144.317974 -426.343064)
					(mid 144.264092 -426.365382)
					(end 144.241774 -426.419264)
				)
			)
		)
	)
	(zone
		(layer "In11.Cu")
		(hatch none 0.5)
		(connect_pads
			(clearance 0)
		)
		(min_thickness 0.25)
		(keepout
			(tracks allowed)
			(vias allowed)
			(pads allowed)
			(copperpour allowed)
			(footprints allowed)
		)
		(placement
			(enabled no)
			(sheetname "")
		)
		(fill
			(thermal_gap 0.5)
			(thermal_bridge_width 0.5)
			(island_removal_mode 0)
		)
		(polygon
			(pts
				(xy 251.50953 -394.172694) (xy 251.50953 -393.615926) (xy 252.737112 -393.615926) (xy 252.737112 -394.172694)
			)
		)
	)
	(zone
		(layer "In11.Cu")
		(hatch none 0.5)
		(connect_pads
			(clearance 0)
		)
		(min_thickness 0.25)
		(keepout
			(tracks allowed)
			(vias allowed)
			(pads allowed)
			(copperpour allowed)
			(footprints allowed)
		)
		(placement
			(enabled no)
			(sheetname "")
		)
		(fill
			(thermal_gap 0.5)
			(thermal_bridge_width 0.5)
			(island_removal_mode 0)
		)
		(polygon
			(pts
				(xy 408.220418 -164.053012) (xy 408.220418 -164.916612) (xy 407.966418 -164.916612) (xy 407.966418 -164.053012)
			)
		)
	)
	(zone
		(layer "In11.Cu")
		(hatch none 0.5)
		(connect_pads
			(clearance 0)
		)
		(min_thickness 0.25)
		(keepout
			(tracks not_allowed)
			(vias allowed)
			(pads allowed)
			(copperpour not_allowed)
			(footprints allowed)
		)
		(placement
			(enabled no)
			(sheetname "")
		)
		(fill
			(thermal_gap 0.5)
			(thermal_bridge_width 0.5)
			(island_removal_mode 0)
		)
		(polygon
			(pts
				(arc
					(start 181.627018 -376.489976)
					(mid 173.373034 -376.489976)
					(end 181.627018 -376.489976)
				)
			)
		)
	)
	(zone
		(layer "In11.Cu")
		(hatch none 0.5)
		(connect_pads
			(clearance 0)
		)
		(min_thickness 0.25)
		(keepout
			(tracks allowed)
			(vias allowed)
			(pads allowed)
			(copperpour allowed)
			(footprints allowed)
		)
		(placement
			(enabled no)
			(sheetname "")
		)
		(fill
			(thermal_gap 0.5)
			(thermal_bridge_width 0.5)
			(island_removal_mode 0)
		)
		(polygon
			(pts
				(xy 56.327294 -347.583252) (xy 56.327294 -348.454472) (xy 56.063134 -348.454472) (xy 56.063134 -347.583252)
			)
		)
	)
	(zone
		(layer "In11.Cu")
		(hatch none 0.5)
		(connect_pads
			(clearance 0)
		)
		(min_thickness 0.25)
		(keepout
			(tracks allowed)
			(vias allowed)
			(pads allowed)
			(copperpour allowed)
			(footprints allowed)
		)
		(placement
			(enabled no)
			(sheetname "")
		)
		(fill
			(thermal_gap 0.5)
			(thermal_bridge_width 0.5)
			(island_removal_mode 0)
		)
		(polygon
			(pts
				(xy 417.212018 -159.735012) (xy 417.212018 -158.515812) (xy 415.662618 -156.966412) (xy 399.457418 -156.966412)
				(xy 389.272018 -146.781012) (xy 382.160018 -146.781012) (xy 382.033018 -146.908012) (xy 382.033018 -147.466812)
				(xy 382.185418 -147.619212) (xy 388.891018 -147.619212) (xy 399.101818 -157.830012) (xy 415.434018 -157.830012)
				(xy 416.246818 -158.642812) (xy 416.246818 -160.014412) (xy 416.475418 -160.243012) (xy 416.704018 -160.243012)
			)
		)
	)
	(zone
		(layer "In11.Cu")
		(hatch none 0.5)
		(connect_pads
			(clearance 0)
		)
		(min_thickness 0.25)
		(keepout
			(tracks allowed)
			(vias allowed)
			(pads allowed)
			(copperpour allowed)
			(footprints allowed)
		)
		(placement
			(enabled no)
			(sheetname "")
		)
		(fill
			(thermal_gap 0.5)
			(thermal_bridge_width 0.5)
			(island_removal_mode 0)
		)
		(polygon
			(pts
				(xy 64.772794 -335.904332) (xy 64.772794 -336.800952) (xy 64.589914 -336.800952) (xy 64.589914 -335.904332)
			)
		)
	)
	(zone
		(layer "In11.Cu")
		(hatch none 0.5)
		(connect_pads
			(clearance 0)
		)
		(min_thickness 0.25)
		(keepout
			(tracks not_allowed)
			(vias allowed)
			(pads allowed)
			(copperpour not_allowed)
			(footprints allowed)
		)
		(placement
			(enabled no)
			(sheetname "")
		)
		(fill
			(thermal_gap 0.5)
			(thermal_bridge_width 0.5)
			(island_removal_mode 0)
		)
		(polygon
			(pts
				(arc
					(start 127.241808 -428.960788)
					(mid 127.264126 -429.01467)
					(end 127.318008 -429.036988)
				)
				(arc
					(start 128.257808 -429.036988)
					(mid 128.31169 -429.01467)
					(end 128.334008 -428.960788)
				)
				(arc
					(start 128.334008 -426.419264)
					(mid 128.31169 -426.365382)
					(end 128.257808 -426.343064)
				)
				(arc
					(start 127.318008 -426.343064)
					(mid 127.264126 -426.365382)
					(end 127.241808 -426.419264)
				)
			)
		)
	)
	(zone
		(layer "In11.Cu")
		(hatch none 0.5)
		(connect_pads
			(clearance 0)
		)
		(min_thickness 0.25)
		(keepout
			(tracks allowed)
			(vias allowed)
			(pads allowed)
			(copperpour allowed)
			(footprints allowed)
		)
		(placement
			(enabled no)
			(sheetname "")
		)
		(fill
			(thermal_gap 0.5)
			(thermal_bridge_width 0.5)
			(island_removal_mode 0)
		)
		(polygon
			(pts
				(xy 267.56233 -394.172694) (xy 267.56233 -393.615926) (xy 268.789912 -393.615926) (xy 268.789912 -394.172694)
			)
		)
	)
	(zone
		(layer "In11.Cu")
		(hatch none 0.5)
		(connect_pads
			(clearance 0)
		)
		(min_thickness 0.25)
		(keepout
			(tracks allowed)
			(vias allowed)
			(pads allowed)
			(copperpour allowed)
			(footprints allowed)
		)
		(placement
			(enabled no)
			(sheetname "")
		)
		(fill
			(thermal_gap 0.5)
			(thermal_bridge_width 0.5)
			(island_removal_mode 0)
		)
		(polygon
			(pts
				(xy 276.588982 -394.15847) (xy 276.588982 -393.601702) (xy 277.816564 -393.601702) (xy 277.816564 -394.15847)
			)
		)
	)
	(zone
		(layer "In11.Cu")
		(hatch none 0.5)
		(connect_pads
			(clearance 0)
		)
		(min_thickness 0.25)
		(keepout
			(tracks not_allowed)
			(vias allowed)
			(pads allowed)
			(copperpour not_allowed)
			(footprints allowed)
		)
		(placement
			(enabled no)
			(sheetname "")
		)
		(fill
			(thermal_gap 0.5)
			(thermal_bridge_width 0.5)
			(island_removal_mode 0)
		)
		(polygon
			(pts
				(arc
					(start 131.2418 -428.960788)
					(mid 131.264118 -429.01467)
					(end 131.318 -429.036988)
				)
				(arc
					(start 132.2578 -429.036988)
					(mid 132.311682 -429.01467)
					(end 132.334 -428.960788)
				)
				(arc
					(start 132.334 -426.419264)
					(mid 132.311682 -426.365382)
					(end 132.2578 -426.343064)
				)
				(arc
					(start 131.318 -426.343064)
					(mid 131.264118 -426.365382)
					(end 131.2418 -426.419264)
				)
			)
		)
	)
	(zone
		(layer "In11.Cu")
		(hatch none 0.5)
		(connect_pads
			(clearance 0)
		)
		(min_thickness 0.25)
		(keepout
			(tracks allowed)
			(vias allowed)
			(pads allowed)
			(copperpour allowed)
			(footprints allowed)
		)
		(placement
			(enabled no)
			(sheetname "")
		)
		(fill
			(thermal_gap 0.5)
			(thermal_bridge_width 0.5)
			(island_removal_mode 0)
		)
		(polygon
			(pts
				(xy 174.382176 -99.625658) (xy 174.382176 -94.821502) (xy 179.402232 -94.821502) (xy 179.402232 -99.625658)
			)
		)
	)
	(zone
		(layer "In11.Cu")
		(hatch none 0.5)
		(connect_pads
			(clearance 0)
		)
		(min_thickness 0.25)
		(keepout
			(tracks not_allowed)
			(vias allowed)
			(pads allowed)
			(copperpour not_allowed)
			(footprints allowed)
		)
		(placement
			(enabled no)
			(sheetname "")
		)
		(fill
			(thermal_gap 0.5)
			(thermal_bridge_width 0.5)
			(island_removal_mode 0)
		)
		(polygon
			(pts
				(arc
					(start 333.141828 -428.960788)
					(mid 333.164146 -429.01467)
					(end 333.218028 -429.036988)
				)
				(arc
					(start 334.157828 -429.036988)
					(mid 334.21171 -429.01467)
					(end 334.234028 -428.960788)
				)
				(arc
					(start 334.234028 -426.419264)
					(mid 334.21171 -426.365382)
					(end 334.157828 -426.343064)
				)
				(arc
					(start 333.218028 -426.343064)
					(mid 333.164146 -426.365382)
					(end 333.141828 -426.419264)
				)
			)
		)
	)
	(zone
		(layer "In11.Cu")
		(hatch none 0.5)
		(connect_pads
			(clearance 0)
		)
		(min_thickness 0.25)
		(keepout
			(tracks not_allowed)
			(vias allowed)
			(pads allowed)
			(copperpour not_allowed)
			(footprints allowed)
		)
		(placement
			(enabled no)
			(sheetname "")
		)
		(fill
			(thermal_gap 0.5)
			(thermal_bridge_width 0.5)
			(island_removal_mode 0)
		)
		(polygon
			(pts
				(arc
					(start 345.141804 -428.960788)
					(mid 345.164122 -429.01467)
					(end 345.218004 -429.036988)
				)
				(arc
					(start 346.157804 -429.036988)
					(mid 346.211686 -429.01467)
					(end 346.234004 -428.960788)
				)
				(arc
					(start 346.234004 -426.419264)
					(mid 346.211686 -426.365382)
					(end 346.157804 -426.343064)
				)
				(arc
					(start 345.218004 -426.343064)
					(mid 345.164122 -426.365382)
					(end 345.141804 -426.419264)
				)
			)
		)
	)
	(zone
		(layer "In11.Cu")
		(hatch none 0.5)
		(connect_pads
			(clearance 0)
		)
		(min_thickness 0.25)
		(keepout
			(tracks allowed)
			(vias allowed)
			(pads allowed)
			(copperpour allowed)
			(footprints allowed)
		)
		(placement
			(enabled no)
			(sheetname "")
		)
		(fill
			(thermal_gap 0.5)
			(thermal_bridge_width 0.5)
			(island_removal_mode 0)
		)
		(polygon
			(pts
				(xy 357.801418 -164.865812) (xy 357.801418 -165.754812) (xy 358.004618 -165.958012) (xy 358.157018 -165.958012)
				(xy 358.792018 -165.323012) (xy 358.792018 -163.824412) (xy 360.849418 -161.767012) (xy 360.849418 -153.308812)
				(xy 363.186218 -150.972012) (xy 372.254018 -150.972012) (xy 374.438418 -148.787612) (xy 374.438418 -147.695412)
				(xy 375.657618 -146.476212) (xy 375.657618 -146.349212) (xy 375.454418 -146.146012) (xy 374.844818 -146.146012)
				(xy 373.676418 -147.314412) (xy 373.676418 -148.406612) (xy 371.923818 -150.159212) (xy 362.906818 -150.159212)
				(xy 360.087418 -152.978612) (xy 360.087418 -161.360612) (xy 359.376218 -162.071812) (xy 359.376218 -162.122612)
				(xy 358.030018 -163.468812) (xy 358.030018 -164.637212)
			)
		)
	)
	(zone
		(layer "In11.Cu")
		(hatch none 0.5)
		(connect_pads
			(clearance 0)
		)
		(min_thickness 0.25)
		(keepout
			(tracks allowed)
			(vias allowed)
			(pads allowed)
			(copperpour allowed)
			(footprints allowed)
		)
		(placement
			(enabled no)
			(sheetname "")
		)
		(fill
			(thermal_gap 0.5)
			(thermal_bridge_width 0.5)
			(island_removal_mode 0)
		)
		(polygon
			(pts
				(xy 39.540434 -347.636592) (xy 39.540434 -348.533212) (xy 39.489634 -348.533212) (xy 39.489634 -347.636592)
			)
		)
	)
	(zone
		(layer "In11.Cu")
		(hatch none 0.5)
		(connect_pads
			(clearance 0)
		)
		(min_thickness 0.25)
		(keepout
			(tracks allowed)
			(vias allowed)
			(pads allowed)
			(copperpour allowed)
			(footprints allowed)
		)
		(placement
			(enabled no)
			(sheetname "")
		)
		(fill
			(thermal_gap 0.5)
			(thermal_bridge_width 0.5)
			(island_removal_mode 0)
		)
		(polygon
			(pts
				(xy 99.763834 -343.493852) (xy 99.499674 -343.493852) (xy 98.999294 -343.994232) (xy 98.999294 -345.233752)
				(xy 97.929954 -346.303092) (xy 96.057974 -346.303092) (xy 92.245434 -342.490552) (xy 76.728574 -342.490552)
				(xy 74.485754 -344.733372) (xy 74.485754 -347.136212) (xy 66.014854 -355.607112) (xy 59.916314 -355.607112)
				(xy 59.309254 -356.214172) (xy 59.309254 -356.320852) (xy 59.784234 -356.795832) (xy 59.995054 -356.795832)
				(xy 60.365894 -356.424992) (xy 66.395854 -356.424992) (xy 75.278234 -347.542612) (xy 75.278234 -344.997532)
				(xy 77.046074 -343.229692) (xy 91.772994 -343.229692) (xy 95.664274 -347.120972) (xy 98.280474 -347.120972)
				(xy 99.850194 -345.551252) (xy 99.850194 -344.680032) (xy 99.994974 -344.535252) (xy 99.994974 -343.724992)
			)
		)
	)
	(zone
		(layer "In11.Cu")
		(hatch none 0.5)
		(connect_pads
			(clearance 0)
		)
		(min_thickness 0.25)
		(keepout
			(tracks not_allowed)
			(vias allowed)
			(pads allowed)
			(copperpour not_allowed)
			(footprints allowed)
		)
		(placement
			(enabled no)
			(sheetname "")
		)
		(fill
			(thermal_gap 0.5)
			(thermal_bridge_width 0.5)
			(island_removal_mode 0)
		)
		(polygon
			(pts
				(arc
					(start 89.141808 -428.960788)
					(mid 89.164126 -429.01467)
					(end 89.218008 -429.036988)
				)
				(arc
					(start 90.157808 -429.036988)
					(mid 90.21169 -429.01467)
					(end 90.234008 -428.960788)
				)
				(arc
					(start 90.234008 -426.419264)
					(mid 90.21169 -426.365382)
					(end 90.157808 -426.343064)
				)
				(arc
					(start 89.218008 -426.343064)
					(mid 89.164126 -426.365382)
					(end 89.141808 -426.419264)
				)
			)
		)
	)
	(zone
		(layer "In11.Cu")
		(hatch none 0.5)
		(connect_pads
			(clearance 0)
		)
		(min_thickness 0.25)
		(keepout
			(tracks allowed)
			(vias allowed)
			(pads allowed)
			(copperpour allowed)
			(footprints allowed)
		)
		(placement
			(enabled no)
			(sheetname "")
		)
		(fill
			(thermal_gap 0.5)
			(thermal_bridge_width 0.5)
			(island_removal_mode 0)
		)
		(polygon
			(pts
				(xy 23.020274 -347.636592) (xy 23.020274 -348.375732) (xy 22.860254 -348.375732) (xy 22.860254 -347.636592)
			)
		)
	)
	(zone
		(layer "In11.Cu")
		(hatch none 0.5)
		(connect_pads
			(clearance 0)
		)
		(min_thickness 0.25)
		(keepout
			(tracks not_allowed)
			(vias allowed)
			(pads allowed)
			(copperpour not_allowed)
			(footprints allowed)
		)
		(placement
			(enabled no)
			(sheetname "")
		)
		(fill
			(thermal_gap 0.5)
			(thermal_bridge_width 0.5)
			(island_removal_mode 0)
		)
		(polygon
			(pts
				(arc
					(start 152.241758 -428.960788)
					(mid 152.264076 -429.01467)
					(end 152.317958 -429.036988)
				)
				(arc
					(start 153.257758 -429.036988)
					(mid 153.31164 -429.01467)
					(end 153.333958 -428.960788)
				)
				(arc
					(start 153.333958 -426.419264)
					(mid 153.31164 -426.365382)
					(end 153.257758 -426.343064)
				)
				(arc
					(start 152.317958 -426.343064)
					(mid 152.264076 -426.365382)
					(end 152.241758 -426.419264)
				)
			)
		)
	)
	(zone
		(layer "In11.Cu")
		(hatch none 0.5)
		(connect_pads
			(clearance 0)
		)
		(min_thickness 0.25)
		(keepout
			(tracks allowed)
			(vias allowed)
			(pads allowed)
			(copperpour allowed)
			(footprints allowed)
		)
		(placement
			(enabled no)
			(sheetname "")
		)
		(fill
			(thermal_gap 0.5)
			(thermal_bridge_width 0.5)
			(island_removal_mode 0)
		)
		(polygon
			(pts
				(xy 23.748238 -352.958654) (xy 23.748238 -352.40341) (xy 24.363934 -352.40341) (xy 24.363934 -352.958654)
			)
		)
	)
	(zone
		(layer "In11.Cu")
		(hatch none 0.5)
		(connect_pads
			(clearance 0)
		)
		(min_thickness 0.25)
		(keepout
			(tracks not_allowed)
			(vias allowed)
			(pads allowed)
			(copperpour not_allowed)
			(footprints allowed)
		)
		(placement
			(enabled no)
			(sheetname "")
		)
		(fill
			(thermal_gap 0.5)
			(thermal_bridge_width 0.5)
			(island_removal_mode 0)
		)
		(polygon
			(pts
				(arc
					(start 77.141832 -428.960788)
					(mid 77.16415 -429.01467)
					(end 77.218032 -429.036988)
				)
				(arc
					(start 78.157832 -429.036988)
					(mid 78.211714 -429.01467)
					(end 78.234032 -428.960788)
				)
				(arc
					(start 78.234032 -426.419264)
					(mid 78.211714 -426.365382)
					(end 78.157832 -426.343064)
				)
				(arc
					(start 77.218032 -426.343064)
					(mid 77.16415 -426.365382)
					(end 77.141832 -426.419264)
				)
			)
		)
	)
	(zone
		(layer "In11.Cu")
		(hatch none 0.5)
		(connect_pads
			(clearance 0)
		)
		(min_thickness 0.25)
		(keepout
			(tracks not_allowed)
			(vias allowed)
			(pads allowed)
			(copperpour not_allowed)
			(footprints allowed)
		)
		(placement
			(enabled no)
			(sheetname "")
		)
		(fill
			(thermal_gap 0.5)
			(thermal_bridge_width 0.5)
			(island_removal_mode 0)
		)
		(polygon
			(pts
				(arc
					(start 148.241766 -428.960788)
					(mid 148.264084 -429.01467)
					(end 148.317966 -429.036988)
				)
				(arc
					(start 149.257766 -429.036988)
					(mid 149.311648 -429.01467)
					(end 149.333966 -428.960788)
				)
				(arc
					(start 149.333966 -426.419264)
					(mid 149.311648 -426.365382)
					(end 149.257766 -426.343064)
				)
				(arc
					(start 148.317966 -426.343064)
					(mid 148.264084 -426.365382)
					(end 148.241766 -426.419264)
				)
			)
		)
	)
	(zone
		(layer "In11.Cu")
		(hatch none 0.5)
		(connect_pads
			(clearance 0)
		)
		(min_thickness 0.25)
		(keepout
			(tracks allowed)
			(vias allowed)
			(pads allowed)
			(copperpour allowed)
			(footprints allowed)
		)
		(placement
			(enabled no)
			(sheetname "")
		)
		(fill
			(thermal_gap 0.5)
			(thermal_bridge_width 0.5)
			(island_removal_mode 0)
		)
		(polygon
			(pts
				(xy 58.069734 -350.433132) (xy 58.069734 -351.253552) (xy 57.752234 -351.253552) (xy 57.752234 -350.433132)
			)
		)
	)
	(zone
		(layer "In11.Cu")
		(hatch none 0.5)
		(connect_pads
			(clearance 0)
		)
		(min_thickness 0.25)
		(keepout
			(tracks allowed)
			(vias allowed)
			(pads allowed)
			(copperpour allowed)
			(footprints allowed)
		)
		(placement
			(enabled no)
			(sheetname "")
		)
		(fill
			(thermal_gap 0.5)
			(thermal_bridge_width 0.5)
			(island_removal_mode 0)
		)
		(polygon
			(pts
				(xy 66.461894 -338.530692) (xy 66.205354 -338.530692) (xy 65.707514 -339.028532) (xy 65.707514 -340.341712)
				(xy 63.789814 -342.259412) (xy 63.789814 -347.677232) (xy 64.739774 -348.627192) (xy 64.739774 -351.438972)
				(xy 63.619634 -352.559112) (xy 53.518054 -352.559112) (xy 52.105814 -353.971352) (xy 52.105814 -355.383592)
				(xy 52.275994 -355.553772) (xy 52.763674 -355.553772) (xy 52.961794 -355.355652) (xy 52.961794 -355.091492)
				(xy 52.817014 -354.946712) (xy 52.817014 -354.367592) (xy 53.860954 -353.323652) (xy 63.929514 -353.323652)
				(xy 65.473834 -351.779332) (xy 65.473834 -348.347792) (xy 64.523874 -347.397832) (xy 64.523874 -342.581992)
				(xy 66.423794 -340.682072) (xy 66.423794 -339.823552) (xy 66.634614 -339.612732) (xy 66.634614 -338.703412)
			)
		)
	)
	(zone
		(layer "In11.Cu")
		(hatch none 0.5)
		(connect_pads
			(clearance 0)
		)
		(min_thickness 0.25)
		(keepout
			(tracks allowed)
			(vias allowed)
			(pads allowed)
			(copperpour allowed)
			(footprints allowed)
		)
		(placement
			(enabled no)
			(sheetname "")
		)
		(fill
			(thermal_gap 0.5)
			(thermal_bridge_width 0.5)
			(island_removal_mode 0)
		)
		(polygon
			(pts
				(xy 24.709374 -350.514412) (xy 24.709374 -351.278952) (xy 24.498554 -351.278952) (xy 24.498554 -350.514412)
			)
		)
	)
	(zone
		(layer "In11.Cu")
		(hatch none 0.5)
		(connect_pads
			(clearance 0)
		)
		(min_thickness 0.25)
		(keepout
			(tracks allowed)
			(vias allowed)
			(pads allowed)
			(copperpour allowed)
			(footprints allowed)
		)
		(placement
			(enabled no)
			(sheetname "")
		)
		(fill
			(thermal_gap 0.5)
			(thermal_bridge_width 0.5)
			(island_removal_mode 0)
		)
		(polygon
			(pts
				(xy 49.781714 -350.382332) (xy 49.781714 -351.304352) (xy 49.492154 -351.304352) (xy 49.492154 -350.382332)
			)
		)
	)
	(zone
		(layer "In11.Cu")
		(hatch none 0.5)
		(connect_pads
			(clearance 0)
		)
		(min_thickness 0.25)
		(keepout
			(tracks not_allowed)
			(vias allowed)
			(pads allowed)
			(copperpour not_allowed)
			(footprints allowed)
		)
		(placement
			(enabled no)
			(sheetname "")
		)
		(fill
			(thermal_gap 0.5)
			(thermal_bridge_width 0.5)
			(island_removal_mode 0)
		)
		(polygon
			(pts
				(arc
					(start 64.382904 -50.630836)
					(mid 67.963796 -47.049944)
					(end 64.382904 -43.469052)
				)
				(arc
					(start 62.782958 -43.469052)
					(mid 59.202066 -47.049944)
					(end 62.782958 -50.630836)
				)
			)
		)
	)
	(zone
		(layer "In11.Cu")
		(hatch none 0.5)
		(connect_pads
			(clearance 0)
		)
		(min_thickness 0.25)
		(keepout
			(tracks not_allowed)
			(vias allowed)
			(pads allowed)
			(copperpour not_allowed)
			(footprints allowed)
		)
		(placement
			(enabled no)
			(sheetname "")
		)
		(fill
			(thermal_gap 0.5)
			(thermal_bridge_width 0.5)
			(island_removal_mode 0)
		)
		(polygon
			(pts
				(arc
					(start 156.24175 -428.960788)
					(mid 156.264068 -429.01467)
					(end 156.31795 -429.036988)
				)
				(arc
					(start 157.25775 -429.036988)
					(mid 157.311632 -429.01467)
					(end 157.33395 -428.960788)
				)
				(arc
					(start 157.33395 -426.419264)
					(mid 157.311632 -426.365382)
					(end 157.25775 -426.343064)
				)
				(arc
					(start 156.31795 -426.343064)
					(mid 156.264068 -426.365382)
					(end 156.24175 -426.419264)
				)
			)
		)
	)
	(zone
		(layer "In11.Cu")
		(hatch none 0.5)
		(connect_pads
			(clearance 0)
		)
		(min_thickness 0.25)
		(keepout
			(tracks not_allowed)
			(vias allowed)
			(pads allowed)
			(copperpour not_allowed)
			(footprints allowed)
		)
		(placement
			(enabled no)
			(sheetname "")
		)
		(fill
			(thermal_gap 0.5)
			(thermal_bridge_width 0.5)
			(island_removal_mode 0)
		)
		(polygon
			(pts
				(arc
					(start 320.141854 -428.960788)
					(mid 320.164172 -429.01467)
					(end 320.218054 -429.036988)
				)
				(arc
					(start 321.157854 -429.036988)
					(mid 321.211736 -429.01467)
					(end 321.234054 -428.960788)
				)
				(arc
					(start 321.234054 -426.419264)
					(mid 321.211736 -426.365382)
					(end 321.157854 -426.343064)
				)
				(arc
					(start 320.218054 -426.343064)
					(mid 320.164172 -426.365382)
					(end 320.141854 -426.419264)
				)
			)
		)
	)
	(zone
		(layer "In11.Cu")
		(hatch none 0.5)
		(connect_pads
			(clearance 0)
		)
		(min_thickness 0.25)
		(keepout
			(tracks allowed)
			(vias allowed)
			(pads allowed)
			(copperpour allowed)
			(footprints allowed)
		)
		(placement
			(enabled no)
			(sheetname "")
		)
		(fill
			(thermal_gap 0.5)
			(thermal_bridge_width 0.5)
			(island_removal_mode 0)
		)
		(polygon
			(pts
				(xy 376.597418 -150.337012) (xy 375.860818 -150.337012) (xy 375.683018 -150.514812) (xy 375.683018 -150.692612)
				(xy 375.860818 -150.870412) (xy 375.860818 -162.605212) (xy 366.081818 -172.384212) (xy 366.081818 -174.060612)
				(xy 366.259618 -174.238412) (xy 366.462818 -174.238412) (xy 367.072418 -173.628812) (xy 367.072418 -172.587412)
				(xy 376.597418 -163.062412)
			)
		)
	)
	(zone
		(layer "In11.Cu")
		(hatch none 0.5)
		(connect_pads
			(clearance 0)
		)
		(min_thickness 0.25)
		(keepout
			(tracks not_allowed)
			(vias allowed)
			(pads allowed)
			(copperpour not_allowed)
			(footprints allowed)
		)
		(placement
			(enabled no)
			(sheetname "")
		)
		(fill
			(thermal_gap 0.5)
			(thermal_bridge_width 0.5)
			(island_removal_mode 0)
		)
		(polygon
			(pts
				(arc
					(start 324.141846 -428.960788)
					(mid 324.164164 -429.01467)
					(end 324.218046 -429.036988)
				)
				(arc
					(start 325.157846 -429.036988)
					(mid 325.211728 -429.01467)
					(end 325.234046 -428.960788)
				)
				(arc
					(start 325.234046 -426.419264)
					(mid 325.211728 -426.365382)
					(end 325.157846 -426.343064)
				)
				(arc
					(start 324.218046 -426.343064)
					(mid 324.164164 -426.365382)
					(end 324.141846 -426.419264)
				)
			)
		)
	)
	(zone
		(layer "In11.Cu")
		(hatch none 0.5)
		(connect_pads
			(clearance 0)
		)
		(min_thickness 0.25)
		(keepout
			(tracks allowed)
			(vias allowed)
			(pads allowed)
			(copperpour allowed)
			(footprints allowed)
		)
		(placement
			(enabled no)
			(sheetname "")
		)
		(fill
			(thermal_gap 0.5)
			(thermal_bridge_width 0.5)
			(island_removal_mode 0)
		)
		(polygon
			(pts
				(xy 74.869294 -338.769452) (xy 74.869294 -339.546692) (xy 74.724514 -339.546692) (xy 74.724514 -338.769452)
			)
		)
	)
	(zone
		(layer "In11.Cu")
		(hatch none 0.5)
		(connect_pads
			(clearance 0)
		)
		(min_thickness 0.25)
		(keepout
			(tracks allowed)
			(vias allowed)
			(pads allowed)
			(copperpour allowed)
			(footprints allowed)
		)
		(placement
			(enabled no)
			(sheetname "")
		)
		(fill
			(thermal_gap 0.5)
			(thermal_bridge_width 0.5)
			(island_removal_mode 0)
		)
		(polygon
			(pts
				(xy 91.590114 -338.563712) (xy 91.244674 -338.563712) (xy 90.632534 -339.175852) (xy 90.632534 -340.405212)
				(xy 90.447114 -340.590632) (xy 75.184254 -340.590632) (xy 72.519794 -343.255092) (xy 72.519794 -346.752672)
				(xy 65.235074 -354.037392) (xy 55.087774 -354.037392) (xy 54.257194 -354.867972) (xy 54.257194 -355.541072)
				(xy 54.401974 -355.685852) (xy 55.194454 -355.685852) (xy 55.339234 -355.541072) (xy 55.339234 -354.987352)
				(xy 55.550054 -354.776532) (xy 65.707514 -354.776532) (xy 73.233534 -347.250512) (xy 73.233534 -343.689432)
				(xy 75.529694 -341.393272) (xy 90.838274 -341.393272) (xy 91.536774 -340.694772) (xy 91.536774 -339.902292)
				(xy 91.826334 -339.612732) (xy 91.826334 -339.348572) (xy 91.734894 -339.257132) (xy 91.734894 -338.708492)
			)
		)
	)
	(zone
		(layer "In11.Cu")
		(hatch none 0.5)
		(connect_pads
			(clearance 0)
		)
		(min_thickness 0.25)
		(keepout
			(tracks not_allowed)
			(vias allowed)
			(pads allowed)
			(copperpour not_allowed)
			(footprints allowed)
		)
		(placement
			(enabled no)
			(sheetname "")
		)
		(fill
			(thermal_gap 0.5)
			(thermal_bridge_width 0.5)
			(island_removal_mode 0)
		)
		(polygon
			(pts
				(arc
					(start 139.241784 -428.960788)
					(mid 139.264102 -429.01467)
					(end 139.317984 -429.036988)
				)
				(arc
					(start 140.257784 -429.036988)
					(mid 140.311666 -429.01467)
					(end 140.333984 -428.960788)
				)
				(arc
					(start 140.333984 -426.419264)
					(mid 140.311666 -426.365382)
					(end 140.257784 -426.343064)
				)
				(arc
					(start 139.317984 -426.343064)
					(mid 139.264102 -426.365382)
					(end 139.241784 -426.419264)
				)
			)
		)
	)
	(zone
		(layer "In11.Cu")
		(hatch none 0.5)
		(connect_pads
			(clearance 0)
		)
		(min_thickness 0.25)
		(keepout
			(tracks allowed)
			(vias allowed)
			(pads allowed)
			(copperpour allowed)
			(footprints allowed)
		)
		(placement
			(enabled no)
			(sheetname "")
		)
		(fill
			(thermal_gap 0.5)
			(thermal_bridge_width 0.5)
			(island_removal_mode 0)
		)
		(polygon
			(pts
				(xy 41.310814 -350.433132) (xy 41.310814 -351.411032) (xy 41.018714 -351.411032) (xy 41.018714 -350.433132)
			)
		)
	)
	(zone
		(layer "In11.Cu")
		(hatch none 0.5)
		(connect_pads
			(clearance 0)
		)
		(min_thickness 0.25)
		(keepout
			(tracks allowed)
			(vias allowed)
			(pads allowed)
			(copperpour allowed)
			(footprints allowed)
		)
		(placement
			(enabled no)
			(sheetname "")
		)
		(fill
			(thermal_gap 0.5)
			(thermal_bridge_width 0.5)
			(island_removal_mode 0)
		)
		(polygon
			(pts
				(xy 83.314794 -338.675472) (xy 83.314794 -339.546692) (xy 82.971894 -339.546692) (xy 82.971894 -338.675472)
			)
		)
	)
	(zone
		(layer "In11.Cu")
		(hatch none 0.5)
		(connect_pads
			(clearance 0)
		)
		(min_thickness 0.25)
		(keepout
			(tracks allowed)
			(vias allowed)
			(pads allowed)
			(copperpour allowed)
			(footprints allowed)
		)
		(placement
			(enabled no)
			(sheetname "")
		)
		(fill
			(thermal_gap 0.5)
			(thermal_bridge_width 0.5)
			(island_removal_mode 0)
		)
		(polygon
			(pts
				(xy 21.877274 -352.306636) (xy 21.877274 -351.727262) (xy 22.504908 -351.727262) (xy 22.504908 -352.306636)
			)
		)
	)
	(zone
		(layer "In11.Cu")
		(hatch none 0.5)
		(connect_pads
			(clearance 0)
		)
		(min_thickness 0.25)
		(keepout
			(tracks not_allowed)
			(vias allowed)
			(pads allowed)
			(copperpour not_allowed)
			(footprints allowed)
		)
		(placement
			(enabled no)
			(sheetname "")
		)
		(fill
			(thermal_gap 0.5)
			(thermal_bridge_width 0.5)
			(island_removal_mode 0)
		)
		(polygon
			(pts
				(arc
					(start 135.241792 -428.960788)
					(mid 135.26411 -429.01467)
					(end 135.317992 -429.036988)
				)
				(arc
					(start 136.257792 -429.036988)
					(mid 136.311674 -429.01467)
					(end 136.333992 -428.960788)
				)
				(arc
					(start 136.333992 -426.419264)
					(mid 136.311674 -426.365382)
					(end 136.257792 -426.343064)
				)
				(arc
					(start 135.317992 -426.343064)
					(mid 135.26411 -426.365382)
					(end 135.241792 -426.419264)
				)
			)
		)
	)
	(zone
		(layer "In11.Cu")
		(hatch none 0.5)
		(connect_pads
			(clearance 0)
		)
		(min_thickness 0.25)
		(keepout
			(tracks allowed)
			(vias allowed)
			(pads allowed)
			(copperpour allowed)
			(footprints allowed)
		)
		(placement
			(enabled no)
			(sheetname "")
		)
		(fill
			(thermal_gap 0.5)
			(thermal_bridge_width 0.5)
			(island_removal_mode 0)
		)
		(polygon
			(pts
				(xy 383.176018 -178.175412) (xy 383.176018 -179.089812) (xy 382.947418 -179.089812) (xy 382.947418 -178.175412)
			)
		)
	)
	(zone
		(layer "In11.Cu")
		(hatch none 0.5)
		(connect_pads
			(clearance 0)
		)
		(min_thickness 0.25)
		(keepout
			(tracks allowed)
			(vias allowed)
			(pads allowed)
			(copperpour allowed)
			(footprints allowed)
		)
		(placement
			(enabled no)
			(sheetname "")
		)
		(fill
			(thermal_gap 0.5)
			(thermal_bridge_width 0.5)
			(island_removal_mode 0)
		)
		(polygon
			(pts
				(xy 76.012294 -172.777912) (xy 76.012294 -171.914312) (xy 76.926694 -170.999912) (xy 94.427294 -170.999912)
				(xy 96.256094 -169.171112) (xy 96.256094 -151.746712) (xy 96.510094 -151.492712) (xy 96.840294 -151.492712)
				(xy 97.068894 -151.721312) (xy 97.068894 -169.501312) (xy 94.757494 -171.812712) (xy 77.079094 -171.812712)
				(xy 76.698094 -172.193712) (xy 76.698094 -173.463712) (xy 76.266294 -173.895512) (xy 76.240894 -173.870112)
				(xy 76.240894 -173.306232) (xy 76.042774 -173.306232) (xy 76.012294 -173.275752) (xy 76.012294 -173.062392)
			)
		)
	)
	(zone
		(layer "In11.Cu")
		(hatch none 0.5)
		(connect_pads
			(clearance 0)
		)
		(min_thickness 0.25)
		(keepout
			(tracks allowed)
			(vias allowed)
			(pads allowed)
			(copperpour allowed)
			(footprints allowed)
		)
		(placement
			(enabled no)
			(sheetname "")
		)
		(fill
			(thermal_gap 0.5)
			(thermal_bridge_width 0.5)
			(island_removal_mode 0)
		)
		(polygon
			(pts
				(xy 31.333694 -347.636592) (xy 31.333694 -348.479872) (xy 31.094934 -348.479872) (xy 31.094934 -347.636592)
			)
		)
	)
	(zone
		(layer "In11.Cu")
		(hatch none 0.5)
		(connect_pads
			(clearance 0)
		)
		(min_thickness 0.25)
		(keepout
			(tracks not_allowed)
			(vias allowed)
			(pads allowed)
			(copperpour not_allowed)
			(footprints allowed)
		)
		(placement
			(enabled no)
			(sheetname "")
		)
		(fill
			(thermal_gap 0.5)
			(thermal_bridge_width 0.5)
			(island_removal_mode 0)
		)
		(polygon
			(pts
				(arc
					(start 341.141812 -428.960788)
					(mid 341.16413 -429.01467)
					(end 341.218012 -429.036988)
				)
				(arc
					(start 342.157812 -429.036988)
					(mid 342.211694 -429.01467)
					(end 342.234012 -428.960788)
				)
				(arc
					(start 342.234012 -426.419264)
					(mid 342.211694 -426.365382)
					(end 342.157812 -426.343064)
				)
				(arc
					(start 341.218012 -426.343064)
					(mid 341.16413 -426.365382)
					(end 341.141812 -426.419264)
				)
			)
		)
	)
	(zone
		(layer "In11.Cu")
		(hatch none 0.5)
		(connect_pads
			(clearance 0)
		)
		(min_thickness 0.25)
		(keepout
			(tracks allowed)
			(vias allowed)
			(pads allowed)
			(copperpour allowed)
			(footprints allowed)
		)
		(placement
			(enabled no)
			(sheetname "")
		)
		(fill
			(thermal_gap 0.5)
			(thermal_bridge_width 0.5)
			(island_removal_mode 0)
		)
		(polygon
			(pts
				(xy 309.135018 -358.947212) (xy 308.322218 -358.947212) (xy 308.119018 -358.744012) (xy 308.119018 -357.651812)
				(xy 324.527418 -341.243412) (xy 337.913218 -341.243412) (xy 338.522818 -340.633812) (xy 338.522818 -339.236812)
				(xy 338.675218 -339.084412) (xy 339.284818 -339.694012) (xy 339.284818 -341.065612) (xy 338.345018 -342.005412)
				(xy 324.933818 -342.005412) (xy 309.185818 -357.753412) (xy 309.185818 -358.896412)
			)
		)
	)
	(zone
		(layer "In11.Cu")
		(hatch none 0.5)
		(connect_pads
			(clearance 0)
		)
		(min_thickness 0.25)
		(keepout
			(tracks allowed)
			(vias allowed)
			(pads allowed)
			(copperpour allowed)
			(footprints allowed)
		)
		(placement
			(enabled no)
			(sheetname "")
		)
		(fill
			(thermal_gap 0.5)
			(thermal_bridge_width 0.5)
			(island_removal_mode 0)
		)
		(polygon
			(pts
				(xy 374.692418 -144.799812) (xy 374.692418 -145.688812) (xy 374.463818 -145.688812) (xy 373.193818 -146.958812)
				(xy 373.193818 -148.051012) (xy 371.847618 -149.397212) (xy 357.064818 -149.397212) (xy 350.562418 -155.899612)
				(xy 350.562418 -157.093412) (xy 350.029018 -157.626812) (xy 349.495618 -157.626812) (xy 349.444818 -157.576012)
				(xy 349.444818 -155.874212) (xy 349.444818 -154.609292) (xy 356.130098 -147.924012) (xy 372.025418 -147.924012)
				(xy 372.279418 -147.670012) (xy 372.279418 -146.755612) (xy 374.311418 -144.723612) (xy 374.616218 -144.723612)
			)
		)
	)
	(zone
		(layer "In11.Cu")
		(hatch none 0.5)
		(connect_pads
			(clearance 0)
		)
		(min_thickness 0.25)
		(keepout
			(tracks allowed)
			(vias allowed)
			(pads allowed)
			(copperpour allowed)
			(footprints allowed)
		)
		(placement
			(enabled no)
			(sheetname "")
		)
		(fill
			(thermal_gap 0.5)
			(thermal_bridge_width 0.5)
			(island_removal_mode 0)
		)
		(polygon
			(pts
				(xy 399.889218 -172.612812) (xy 399.889218 -173.476412) (xy 399.711418 -173.476412) (xy 399.711418 -172.612812)
			)
		)
	)
	(zone
		(layer "In11.Cu")
		(hatch none 0.5)
		(connect_pads
			(clearance 0)
		)
		(min_thickness 0.25)
		(keepout
			(tracks allowed)
			(vias allowed)
			(pads allowed)
			(copperpour allowed)
			(footprints allowed)
		)
		(placement
			(enabled no)
			(sheetname "")
		)
		(fill
			(thermal_gap 0.5)
			(thermal_bridge_width 0.5)
			(island_removal_mode 0)
		)
		(polygon
			(pts
				(xy 73.139554 -335.878932) (xy 73.139554 -336.668872) (xy 72.969374 -336.668872) (xy 72.969374 -335.878932)
			)
		)
	)
	(zone
		(layer "In11.Cu")
		(hatch none 0.5)
		(connect_pads
			(clearance 0)
		)
		(min_thickness 0.25)
		(keepout
			(tracks not_allowed)
			(vias allowed)
			(pads allowed)
			(copperpour not_allowed)
			(footprints allowed)
		)
		(placement
			(enabled no)
			(sheetname "")
		)
		(fill
			(thermal_gap 0.5)
			(thermal_bridge_width 0.5)
			(island_removal_mode 0)
		)
		(polygon
			(pts
				(arc
					(start 328.141838 -428.960788)
					(mid 328.164156 -429.01467)
					(end 328.218038 -429.036988)
				)
				(arc
					(start 329.157838 -429.036988)
					(mid 329.21172 -429.01467)
					(end 329.234038 -428.960788)
				)
				(arc
					(start 329.234038 -426.419264)
					(mid 329.21172 -426.365382)
					(end 329.157838 -426.343064)
				)
				(arc
					(start 328.218038 -426.343064)
					(mid 328.164156 -426.365382)
					(end 328.141838 -426.419264)
				)
			)
		)
	)
	(zone
		(layer "In11.Cu")
		(hatch none 0.5)
		(connect_pads
			(clearance 0)
		)
		(min_thickness 0.25)
		(keepout
			(tracks allowed)
			(vias allowed)
			(pads allowed)
			(copperpour allowed)
			(footprints allowed)
		)
		(placement
			(enabled no)
			(sheetname "")
		)
		(fill
			(thermal_gap 0.5)
			(thermal_bridge_width 0.5)
			(island_removal_mode 0)
		)
		(polygon
			(pts
				(xy 347.489018 -343.580212) (xy 347.311218 -343.580212) (xy 346.828618 -344.062812) (xy 346.828618 -345.434412)
				(xy 346.650818 -345.612212) (xy 344.872818 -345.612212) (xy 341.824818 -342.564212) (xy 326.407018 -342.564212)
				(xy 313.097418 -355.873812) (xy 313.097418 -360.699812) (xy 311.497218 -362.300012) (xy 311.497218 -362.655612)
				(xy 311.852818 -363.011212) (xy 312.132218 -363.011212) (xy 313.859418 -361.284012) (xy 313.859418 -356.153212)
				(xy 326.661018 -343.351612) (xy 341.469218 -343.351612) (xy 344.517218 -346.399612) (xy 347.006418 -346.399612)
				(xy 347.590618 -345.815412) (xy 347.590618 -344.621612) (xy 347.412818 -344.443812) (xy 347.412818 -343.834212)
				(xy 347.489018 -343.758012)
			)
		)
	)
	(zone
		(layers "In11.Cu" "In12.Cu")
		(hatch none 0.5)
		(connect_pads
			(clearance 0)
		)
		(min_thickness 0.25)
		(keepout
			(tracks not_allowed)
			(vias allowed)
			(pads allowed)
			(copperpour not_allowed)
			(footprints allowed)
		)
		(placement
			(enabled no)
			(sheetname "")
		)
		(fill yes
			(thermal_gap 0.5)
			(thermal_bridge_width 0.5)
			(island_removal_mode 0)
		)
		(polygon
			(pts
				(arc
					(start 412.241746 -428.960788)
					(mid 412.264064 -429.01467)
					(end 412.317946 -429.036988)
				)
				(arc
					(start 413.257746 -429.036988)
					(mid 413.311628 -429.01467)
					(end 413.333946 -428.960788)
				)
				(arc
					(start 413.333946 -426.419264)
					(mid 413.311628 -426.365382)
					(end 413.257746 -426.343064)
				)
				(arc
					(start 412.317946 -426.343064)
					(mid 412.264064 -426.365382)
					(end 412.241746 -426.419264)
				)
			)
		)
	)
	(zone
		(layers "In11.Cu" "In12.Cu")
		(hatch none 0.5)
		(connect_pads
			(clearance 0)
		)
		(min_thickness 0.25)
		(keepout
			(tracks not_allowed)
			(vias allowed)
			(pads allowed)
			(copperpour not_allowed)
			(footprints allowed)
		)
		(placement
			(enabled no)
			(sheetname "")
		)
		(fill yes
			(thermal_gap 0.5)
			(thermal_bridge_width 0.5)
			(island_removal_mode 0)
		)
		(polygon
			(pts
				(arc
					(start 400.24177 -428.960788)
					(mid 400.264088 -429.01467)
					(end 400.31797 -429.036988)
				)
				(arc
					(start 401.25777 -429.036988)
					(mid 401.311652 -429.01467)
					(end 401.33397 -428.960788)
				)
				(arc
					(start 401.33397 -426.419264)
					(mid 401.311652 -426.365382)
					(end 401.25777 -426.343064)
				)
				(arc
					(start 400.31797 -426.343064)
					(mid 400.264088 -426.365382)
					(end 400.24177 -426.419264)
				)
			)
		)
	)
	(zone
		(layers "In11.Cu" "In12.Cu")
		(hatch none 0.5)
		(connect_pads
			(clearance 0)
		)
		(min_thickness 0.25)
		(keepout
			(tracks not_allowed)
			(vias allowed)
			(pads allowed)
			(copperpour not_allowed)
			(footprints allowed)
		)
		(placement
			(enabled no)
			(sheetname "")
		)
		(fill yes
			(thermal_gap 0.5)
			(thermal_bridge_width 0.5)
			(island_removal_mode 0)
		)
		(polygon
			(pts
				(arc
					(start 387.241796 -428.960788)
					(mid 387.264114 -429.01467)
					(end 387.317996 -429.036988)
				)
				(arc
					(start 388.257796 -429.036988)
					(mid 388.311678 -429.01467)
					(end 388.333996 -428.960788)
				)
				(arc
					(start 388.333996 -426.419264)
					(mid 388.311678 -426.365382)
					(end 388.257796 -426.343064)
				)
				(arc
					(start 387.317996 -426.343064)
					(mid 387.264114 -426.365382)
					(end 387.241796 -426.419264)
				)
			)
		)
	)
	(zone
		(layers "In11.Cu" "In12.Cu")
		(hatch none 0.5)
		(connect_pads
			(clearance 0)
		)
		(min_thickness 0.25)
		(keepout
			(tracks not_allowed)
			(vias allowed)
			(pads allowed)
			(copperpour not_allowed)
			(footprints allowed)
		)
		(placement
			(enabled no)
			(sheetname "")
		)
		(fill yes
			(thermal_gap 0.5)
			(thermal_bridge_width 0.5)
			(island_removal_mode 0)
		)
		(polygon
			(pts
				(arc
					(start 408.241754 -428.960788)
					(mid 408.264072 -429.01467)
					(end 408.317954 -429.036988)
				)
				(arc
					(start 409.257754 -429.036988)
					(mid 409.311636 -429.01467)
					(end 409.333954 -428.960788)
				)
				(arc
					(start 409.333954 -426.419264)
					(mid 409.311636 -426.365382)
					(end 409.257754 -426.343064)
				)
				(arc
					(start 408.317954 -426.343064)
					(mid 408.264072 -426.365382)
					(end 408.241754 -426.419264)
				)
			)
		)
	)
	(zone
		(layers "In11.Cu" "In12.Cu")
		(hatch none 0.5)
		(connect_pads
			(clearance 0)
		)
		(min_thickness 0.25)
		(keepout
			(tracks not_allowed)
			(vias allowed)
			(pads allowed)
			(copperpour not_allowed)
			(footprints allowed)
		)
		(placement
			(enabled no)
			(sheetname "")
		)
		(fill yes
			(thermal_gap 0.5)
			(thermal_bridge_width 0.5)
			(island_removal_mode 0)
		)
		(polygon
			(pts
				(arc
					(start 383.241804 -428.960788)
					(mid 383.264122 -429.01467)
					(end 383.318004 -429.036988)
				)
				(arc
					(start 384.257804 -429.036988)
					(mid 384.311686 -429.01467)
					(end 384.334004 -428.960788)
				)
				(arc
					(start 384.334004 -426.419264)
					(mid 384.311686 -426.365382)
					(end 384.257804 -426.343064)
				)
				(arc
					(start 383.318004 -426.343064)
					(mid 383.264122 -426.365382)
					(end 383.241804 -426.419264)
				)
			)
		)
	)
	(zone
		(layers "In11.Cu" "In12.Cu")
		(hatch none 0.5)
		(connect_pads
			(clearance 0)
		)
		(min_thickness 0.25)
		(keepout
			(tracks not_allowed)
			(vias allowed)
			(pads allowed)
			(copperpour not_allowed)
			(footprints allowed)
		)
		(placement
			(enabled no)
			(sheetname "")
		)
		(fill yes
			(thermal_gap 0.5)
			(thermal_bridge_width 0.5)
			(island_removal_mode 0)
		)
		(polygon
			(pts
				(arc
					(start 395.24178 -428.960788)
					(mid 395.264098 -429.01467)
					(end 395.31798 -429.036988)
				)
				(arc
					(start 396.25778 -429.036988)
					(mid 396.311662 -429.01467)
					(end 396.33398 -428.960788)
				)
				(arc
					(start 396.33398 -426.419264)
					(mid 396.311662 -426.365382)
					(end 396.25778 -426.343064)
				)
				(arc
					(start 395.31798 -426.343064)
					(mid 395.264098 -426.365382)
					(end 395.24178 -426.419264)
				)
			)
		)
	)
	(zone
		(layers "In11.Cu" "In12.Cu")
		(hatch none 0.5)
		(connect_pads
			(clearance 0)
		)
		(min_thickness 0.25)
		(keepout
			(tracks not_allowed)
			(vias allowed)
			(pads allowed)
			(copperpour not_allowed)
			(footprints allowed)
		)
		(placement
			(enabled no)
			(sheetname "")
		)
		(fill yes
			(thermal_gap 0.5)
			(thermal_bridge_width 0.5)
			(island_removal_mode 0)
		)
		(polygon
			(pts
				(arc
					(start 391.241788 -428.960788)
					(mid 391.264106 -429.01467)
					(end 391.317988 -429.036988)
				)
				(arc
					(start 392.257788 -429.036988)
					(mid 392.31167 -429.01467)
					(end 392.333988 -428.960788)
				)
				(arc
					(start 392.333988 -426.419264)
					(mid 392.31167 -426.365382)
					(end 392.257788 -426.343064)
				)
				(arc
					(start 391.317988 -426.343064)
					(mid 391.264106 -426.365382)
					(end 391.241788 -426.419264)
				)
			)
		)
	)
	(zone
		(layers "In11.Cu" "In12.Cu")
		(hatch none 0.5)
		(connect_pads
			(clearance 0)
		)
		(min_thickness 0.25)
		(keepout
			(tracks not_allowed)
			(vias allowed)
			(pads allowed)
			(copperpour not_allowed)
			(footprints allowed)
		)
		(placement
			(enabled no)
			(sheetname "")
		)
		(fill yes
			(thermal_gap 0.5)
			(thermal_bridge_width 0.5)
			(island_removal_mode 0)
		)
		(polygon
			(pts
				(arc
					(start 404.241762 -428.960788)
					(mid 404.26408 -429.01467)
					(end 404.317962 -429.036988)
				)
				(arc
					(start 405.257762 -429.036988)
					(mid 405.311644 -429.01467)
					(end 405.333962 -428.960788)
				)
				(arc
					(start 405.333962 -426.419264)
					(mid 405.311644 -426.365382)
					(end 405.257762 -426.343064)
				)
				(arc
					(start 404.317962 -426.343064)
					(mid 404.26408 -426.365382)
					(end 404.241762 -426.419264)
				)
			)
		)
	)
	(zone
		(layers "In11.Cu" "In13.Cu")
		(hatch none 0.5)
		(connect_pads
			(clearance 0)
		)
		(min_thickness 0.25)
		(keepout
			(tracks not_allowed)
			(vias allowed)
			(pads allowed)
			(copperpour not_allowed)
			(footprints allowed)
		)
		(placement
			(enabled no)
			(sheetname "")
		)
		(fill yes
			(thermal_gap 0.5)
			(thermal_bridge_width 0.5)
			(island_removal_mode 0)
		)
		(polygon
			(pts
				(arc
					(start 217.83802 -360.764074)
					(mid 209.5119 -360.764074)
					(end 217.83802 -360.764074)
				)
			)
		)
	)
	(zone
		(layers "In11.Cu" "In15.Cu")
		(hatch none 0.5)
		(connect_pads
			(clearance 0)
		)
		(min_thickness 0.25)
		(keepout
			(tracks not_allowed)
			(vias allowed)
			(pads allowed)
			(copperpour not_allowed)
			(footprints allowed)
		)
		(placement
			(enabled no)
			(sheetname "")
		)
		(fill yes
			(thermal_gap 0.5)
			(thermal_bridge_width 0.5)
			(island_removal_mode 0)
		)
		(polygon
			(pts
				(arc
					(start 295.197022 -384.869944)
					(mid 286.943038 -384.869944)
					(end 295.197022 -384.869944)
				)
			)
		)
	)
	(zone
		(layer "In12.Cu")
		(hatch none 0.5)
		(connect_pads
			(clearance 0)
		)
		(min_thickness 0.25)
		(keepout
			(tracks not_allowed)
			(vias allowed)
			(pads allowed)
			(copperpour not_allowed)
			(footprints allowed)
		)
		(placement
			(enabled no)
			(sheetname "")
		)
		(fill
			(thermal_gap 0.5)
			(thermal_bridge_width 0.5)
			(island_removal_mode 0)
		)
		(polygon
			(pts
				(arc
					(start 341.141558 -439.760868)
					(mid 341.163876 -439.81475)
					(end 341.217758 -439.837068)
				)
				(arc
					(start 342.157558 -439.837068)
					(mid 342.21144 -439.81475)
					(end 342.233758 -439.760868)
				)
				(arc
					(start 342.233758 -437.219344)
					(mid 342.21144 -437.165462)
					(end 342.157558 -437.143144)
				)
				(arc
					(start 341.217758 -437.143144)
					(mid 341.163876 -437.165462)
					(end 341.141558 -437.219344)
				)
			)
		)
	)
	(zone
		(layer "In12.Cu")
		(hatch none 0.5)
		(connect_pads
			(clearance 0)
		)
		(min_thickness 0.25)
		(keepout
			(tracks not_allowed)
			(vias allowed)
			(pads allowed)
			(copperpour not_allowed)
			(footprints allowed)
		)
		(placement
			(enabled no)
			(sheetname "")
		)
		(fill
			(thermal_gap 0.5)
			(thermal_bridge_width 0.5)
			(island_removal_mode 0)
		)
		(polygon
			(pts
				(arc
					(start 343.141808 -435.16042)
					(mid 343.164126 -435.214302)
					(end 343.218008 -435.23662)
				)
				(arc
					(start 344.157808 -435.23662)
					(mid 344.21169 -435.214302)
					(end 344.234008 -435.16042)
				)
				(arc
					(start 344.234008 -432.618896)
					(mid 344.21169 -432.565014)
					(end 344.157808 -432.542696)
				)
				(arc
					(start 343.218008 -432.542696)
					(mid 343.164126 -432.565014)
					(end 343.141808 -432.618896)
				)
				(arc
					(start 343.141808 -433.346352)
					(mid 343.143807 -433.363693)
					(end 343.149682 -433.380134)
				)
				(arc
					(start 343.383108 -433.856384)
					(mid 343.390891 -433.889912)
					(end 343.383108 -433.92344)
				)
				(arc
					(start 343.149682 -434.39969)
					(mid 343.143787 -434.416126)
					(end 343.141808 -434.433472)
				)
			)
		)
	)
	(zone
		(layer "In12.Cu")
		(hatch none 0.5)
		(connect_pads
			(clearance 0)
		)
		(min_thickness 0.25)
		(keepout
			(tracks not_allowed)
			(vias allowed)
			(pads allowed)
			(copperpour not_allowed)
			(footprints allowed)
		)
		(placement
			(enabled no)
			(sheetname "")
		)
		(fill
			(thermal_gap 0.5)
			(thermal_bridge_width 0.5)
			(island_removal_mode 0)
		)
		(polygon
			(pts
				(arc
					(start 154.241754 -438.76087)
					(mid 154.264072 -438.814752)
					(end 154.317954 -438.83707)
				)
				(arc
					(start 155.257754 -438.83707)
					(mid 155.311636 -438.814752)
					(end 155.333954 -438.76087)
				)
				(arc
					(start 155.333954 -436.219346)
					(mid 155.311636 -436.165464)
					(end 155.257754 -436.143146)
				)
				(arc
					(start 154.317954 -436.143146)
					(mid 154.264072 -436.165464)
					(end 154.241754 -436.219346)
				)
			)
		)
	)
	(zone
		(layer "In12.Cu")
		(hatch none 0.5)
		(connect_pads
			(clearance 0)
		)
		(min_thickness 0.25)
		(keepout
			(tracks not_allowed)
			(vias allowed)
			(pads allowed)
			(copperpour not_allowed)
			(footprints allowed)
		)
		(placement
			(enabled no)
			(sheetname "")
		)
		(fill
			(thermal_gap 0.5)
			(thermal_bridge_width 0.5)
			(island_removal_mode 0)
		)
		(polygon
			(pts
				(arc
					(start 337.14182 -436.160418)
					(mid 337.164138 -436.2143)
					(end 337.21802 -436.236618)
				)
				(arc
					(start 338.15782 -436.236618)
					(mid 338.211702 -436.2143)
					(end 338.23402 -436.160418)
				)
				(arc
					(start 338.23402 -433.618894)
					(mid 338.211702 -433.565012)
					(end 338.15782 -433.542694)
				)
				(arc
					(start 337.21802 -433.542694)
					(mid 337.164138 -433.565012)
					(end 337.14182 -433.618894)
				)
				(arc
					(start 337.14182 -434.34635)
					(mid 337.143819 -434.363691)
					(end 337.149694 -434.380132)
				)
				(arc
					(start 337.38312 -434.856382)
					(mid 337.390903 -434.88991)
					(end 337.38312 -434.923438)
				)
				(arc
					(start 337.149694 -435.399688)
					(mid 337.143799 -435.416124)
					(end 337.14182 -435.43347)
				)
			)
		)
	)
	(zone
		(layer "In12.Cu")
		(hatch none 0.5)
		(connect_pads
			(clearance 0)
		)
		(min_thickness 0.25)
		(keepout
			(tracks not_allowed)
			(vias allowed)
			(pads allowed)
			(copperpour not_allowed)
			(footprints allowed)
		)
		(placement
			(enabled no)
			(sheetname "")
		)
		(fill
			(thermal_gap 0.5)
			(thermal_bridge_width 0.5)
			(island_removal_mode 0)
		)
		(polygon
			(pts
				(arc
					(start 333.141574 -439.760868)
					(mid 333.163892 -439.81475)
					(end 333.217774 -439.837068)
				)
				(arc
					(start 334.157574 -439.837068)
					(mid 334.211456 -439.81475)
					(end 334.233774 -439.760868)
				)
				(arc
					(start 334.233774 -437.219344)
					(mid 334.211456 -437.165462)
					(end 334.157574 -437.143144)
				)
				(arc
					(start 333.217774 -437.143144)
					(mid 333.163892 -437.165462)
					(end 333.141574 -437.219344)
				)
			)
		)
	)
	(zone
		(layer "In12.Cu")
		(hatch none 0.5)
		(connect_pads
			(clearance 0)
		)
		(min_thickness 0.25)
		(keepout
			(tracks allowed)
			(vias allowed)
			(pads allowed)
			(copperpour allowed)
			(footprints allowed)
		)
		(placement
			(enabled no)
			(sheetname "")
		)
		(fill
			(thermal_gap 0.5)
			(thermal_bridge_width 0.5)
			(island_removal_mode 0)
		)
		(polygon
			(pts
				(xy 64.876934 -335.906872) (xy 64.876934 -336.752692) (xy 64.569594 -336.752692) (xy 64.569594 -335.906872)
			)
		)
	)
	(zone
		(layer "In12.Cu")
		(hatch none 0.5)
		(connect_pads
			(clearance 0)
		)
		(min_thickness 0.25)
		(keepout
			(tracks not_allowed)
			(vias allowed)
			(pads allowed)
			(copperpour not_allowed)
			(footprints allowed)
		)
		(placement
			(enabled no)
			(sheetname "")
		)
		(fill
			(thermal_gap 0.5)
			(thermal_bridge_width 0.5)
			(island_removal_mode 0)
		)
		(polygon
			(pts
				(arc
					(start 324.141338 -439.760868)
					(mid 324.163656 -439.81475)
					(end 324.217538 -439.837068)
				)
				(arc
					(start 325.157338 -439.837068)
					(mid 325.21122 -439.81475)
					(end 325.233538 -439.760868)
				)
				(arc
					(start 325.233538 -437.219344)
					(mid 325.21122 -437.165462)
					(end 325.157338 -437.143144)
				)
				(arc
					(start 324.217538 -437.143144)
					(mid 324.163656 -437.165462)
					(end 324.141338 -437.219344)
				)
			)
		)
	)
	(zone
		(layer "In12.Cu")
		(hatch none 0.5)
		(connect_pads
			(clearance 0)
		)
		(min_thickness 0.25)
		(keepout
			(tracks not_allowed)
			(vias allowed)
			(pads allowed)
			(copperpour not_allowed)
			(footprints allowed)
		)
		(placement
			(enabled no)
			(sheetname "")
		)
		(fill
			(thermal_gap 0.5)
			(thermal_bridge_width 0.5)
			(island_removal_mode 0)
		)
		(polygon
			(pts
				(arc
					(start 402.241766 -438.76087)
					(mid 402.264084 -438.814752)
					(end 402.317966 -438.83707)
				)
				(arc
					(start 403.257766 -438.83707)
					(mid 403.311648 -438.814752)
					(end 403.333966 -438.76087)
				)
				(arc
					(start 403.333966 -436.219346)
					(mid 403.311648 -436.165464)
					(end 403.257766 -436.143146)
				)
				(arc
					(start 402.317966 -436.143146)
					(mid 402.264084 -436.165464)
					(end 402.241766 -436.219346)
				)
			)
		)
	)
	(zone
		(layer "In12.Cu")
		(hatch none 0.5)
		(connect_pads
			(clearance 0)
		)
		(min_thickness 0.25)
		(keepout
			(tracks not_allowed)
			(vias allowed)
			(pads allowed)
			(copperpour not_allowed)
			(footprints allowed)
		)
		(placement
			(enabled no)
			(sheetname "")
		)
		(fill
			(thermal_gap 0.5)
			(thermal_bridge_width 0.5)
			(island_removal_mode 0)
		)
		(polygon
			(pts
				(arc
					(start 322.14185 -435.16042)
					(mid 322.164168 -435.214302)
					(end 322.21805 -435.23662)
				)
				(arc
					(start 323.15785 -435.23662)
					(mid 323.211732 -435.214302)
					(end 323.23405 -435.16042)
				)
				(arc
					(start 323.23405 -432.618896)
					(mid 323.211732 -432.565014)
					(end 323.15785 -432.542696)
				)
				(arc
					(start 322.21805 -432.542696)
					(mid 322.164168 -432.565014)
					(end 322.14185 -432.618896)
				)
				(arc
					(start 322.14185 -433.346352)
					(mid 322.143849 -433.363693)
					(end 322.149724 -433.380134)
				)
				(arc
					(start 322.38315 -433.856384)
					(mid 322.390933 -433.889912)
					(end 322.38315 -433.92344)
				)
				(arc
					(start 322.149724 -434.39969)
					(mid 322.143829 -434.416126)
					(end 322.14185 -434.433472)
				)
			)
		)
	)
	(zone
		(layer "In12.Cu")
		(hatch none 0.5)
		(connect_pads
			(clearance 0)
		)
		(min_thickness 0.25)
		(keepout
			(tracks not_allowed)
			(vias allowed)
			(pads allowed)
			(copperpour not_allowed)
			(footprints allowed)
		)
		(placement
			(enabled no)
			(sheetname "")
		)
		(fill
			(thermal_gap 0.5)
			(thermal_bridge_width 0.5)
			(island_removal_mode 0)
		)
		(polygon
			(pts
				(xy 198.644256 -402.71573) (xy 198.644256 -401.13839) (xy 200.360534 -401.13839) (xy 200.360534 -402.71573)
			)
		)
	)
	(zone
		(layer "In12.Cu")
		(hatch none 0.5)
		(connect_pads
			(clearance 0)
		)
		(min_thickness 0.25)
		(keepout
			(tracks not_allowed)
			(vias allowed)
			(pads allowed)
			(copperpour not_allowed)
			(footprints allowed)
		)
		(placement
			(enabled no)
			(sheetname "")
		)
		(fill
			(thermal_gap 0.5)
			(thermal_bridge_width 0.5)
			(island_removal_mode 0)
		)
		(polygon
			(pts
				(arc
					(start 133.241796 -435.16042)
					(mid 133.264114 -435.214302)
					(end 133.317996 -435.23662)
				)
				(arc
					(start 134.257796 -435.23662)
					(mid 134.311678 -435.214302)
					(end 134.333996 -435.16042)
				)
				(arc
					(start 134.333996 -432.618896)
					(mid 134.311678 -432.565014)
					(end 134.257796 -432.542696)
				)
				(arc
					(start 133.317996 -432.542696)
					(mid 133.264114 -432.565014)
					(end 133.241796 -432.618896)
				)
				(arc
					(start 133.241796 -433.346352)
					(mid 133.243795 -433.363693)
					(end 133.24967 -433.380134)
				)
				(arc
					(start 133.483096 -433.856384)
					(mid 133.490879 -433.889912)
					(end 133.483096 -433.92344)
				)
				(arc
					(start 133.24967 -434.39969)
					(mid 133.243775 -434.416126)
					(end 133.241796 -434.433472)
				)
			)
		)
	)
	(zone
		(layer "In12.Cu")
		(hatch none 0.5)
		(connect_pads
			(clearance 0)
		)
		(min_thickness 0.25)
		(keepout
			(tracks not_allowed)
			(vias allowed)
			(pads allowed)
			(copperpour not_allowed)
			(footprints allowed)
		)
		(placement
			(enabled no)
			(sheetname "")
		)
		(fill
			(thermal_gap 0.5)
			(thermal_bridge_width 0.5)
			(island_removal_mode 0)
		)
		(polygon
			(pts
				(arc
					(start 72.141842 -436.160418)
					(mid 72.16416 -436.2143)
					(end 72.218042 -436.236618)
				)
				(arc
					(start 73.157842 -436.236618)
					(mid 73.211724 -436.2143)
					(end 73.234042 -436.160418)
				)
				(arc
					(start 73.234042 -433.618894)
					(mid 73.211724 -433.565012)
					(end 73.157842 -433.542694)
				)
				(arc
					(start 72.218042 -433.542694)
					(mid 72.16416 -433.565012)
					(end 72.141842 -433.618894)
				)
				(arc
					(start 72.141842 -434.34635)
					(mid 72.143841 -434.363691)
					(end 72.149716 -434.380132)
				)
				(arc
					(start 72.383142 -434.856382)
					(mid 72.390925 -434.88991)
					(end 72.383142 -434.923438)
				)
				(arc
					(start 72.149716 -435.399688)
					(mid 72.143821 -435.416124)
					(end 72.141842 -435.43347)
				)
			)
		)
	)
	(zone
		(layer "In12.Cu")
		(hatch none 0.5)
		(connect_pads
			(clearance 0)
		)
		(min_thickness 0.25)
		(keepout
			(tracks not_allowed)
			(vias allowed)
			(pads allowed)
			(copperpour not_allowed)
			(footprints allowed)
		)
		(placement
			(enabled no)
			(sheetname "")
		)
		(fill
			(thermal_gap 0.5)
			(thermal_bridge_width 0.5)
			(island_removal_mode 0)
		)
		(polygon
			(pts
				(arc
					(start 389.241538 -438.76087)
					(mid 389.263856 -438.814752)
					(end 389.317738 -438.83707)
				)
				(arc
					(start 390.257538 -438.83707)
					(mid 390.31142 -438.814752)
					(end 390.333738 -438.76087)
				)
				(arc
					(start 390.333738 -436.219346)
					(mid 390.31142 -436.165464)
					(end 390.257538 -436.143146)
				)
				(arc
					(start 389.317738 -436.143146)
					(mid 389.263856 -436.165464)
					(end 389.241538 -436.219346)
				)
			)
		)
	)
	(zone
		(layer "In12.Cu")
		(hatch none 0.5)
		(connect_pads
			(clearance 0)
		)
		(min_thickness 0.25)
		(keepout
			(tracks not_allowed)
			(vias allowed)
			(pads allowed)
			(copperpour not_allowed)
			(footprints allowed)
		)
		(placement
			(enabled no)
			(sheetname "")
		)
		(fill
			(thermal_gap 0.5)
			(thermal_bridge_width 0.5)
			(island_removal_mode 0)
		)
		(polygon
			(pts
				(arc
					(start 406.241758 -438.76087)
					(mid 406.264076 -438.814752)
					(end 406.317958 -438.83707)
				)
				(arc
					(start 407.257758 -438.83707)
					(mid 407.31164 -438.814752)
					(end 407.333958 -438.76087)
				)
				(arc
					(start 407.333958 -436.219346)
					(mid 407.31164 -436.165464)
					(end 407.257758 -436.143146)
				)
				(arc
					(start 406.317958 -436.143146)
					(mid 406.264076 -436.165464)
					(end 406.241758 -436.219346)
				)
			)
		)
	)
	(zone
		(layer "In12.Cu")
		(hatch none 0.5)
		(connect_pads
			(clearance 0)
		)
		(min_thickness 0.25)
		(keepout
			(tracks not_allowed)
			(vias allowed)
			(pads allowed)
			(copperpour not_allowed)
			(footprints allowed)
		)
		(placement
			(enabled no)
			(sheetname "")
		)
		(fill
			(thermal_gap 0.5)
			(thermal_bridge_width 0.5)
			(island_removal_mode 0)
		)
		(polygon
			(pts
				(arc
					(start 58.14187 -435.16042)
					(mid 58.164188 -435.214302)
					(end 58.21807 -435.23662)
				)
				(arc
					(start 59.15787 -435.23662)
					(mid 59.211752 -435.214302)
					(end 59.23407 -435.16042)
				)
				(arc
					(start 59.23407 -432.618896)
					(mid 59.211752 -432.565014)
					(end 59.15787 -432.542696)
				)
				(arc
					(start 58.21807 -432.542696)
					(mid 58.164188 -432.565014)
					(end 58.14187 -432.618896)
				)
				(arc
					(start 58.14187 -433.346352)
					(mid 58.143869 -433.363693)
					(end 58.149744 -433.380134)
				)
				(arc
					(start 58.38317 -433.856384)
					(mid 58.390953 -433.889912)
					(end 58.38317 -433.92344)
				)
				(arc
					(start 58.149744 -434.39969)
					(mid 58.143849 -434.416126)
					(end 58.14187 -434.433472)
				)
			)
		)
	)
	(zone
		(layer "In12.Cu")
		(hatch none 0.5)
		(connect_pads
			(clearance 0)
		)
		(min_thickness 0.25)
		(keepout
			(tracks allowed)
			(vias allowed)
			(pads allowed)
			(copperpour allowed)
			(footprints allowed)
		)
		(placement
			(enabled no)
			(sheetname "")
		)
		(fill
			(thermal_gap 0.5)
			(thermal_bridge_width 0.5)
			(island_removal_mode 0)
		)
		(polygon
			(pts
				(xy 127.381 -273.431) (xy 127.381 -270.383) (xy 126.492 -269.494) (xy 117.094 -269.494) (xy 116.332 -268.732)
				(xy 98.425 -268.732) (xy 97.155 -270.002) (xy 97.155 -273.431) (xy 98.171 -274.447) (xy 126.365 -274.447)
			)
		)
	)
	(zone
		(layer "In12.Cu")
		(hatch none 0.5)
		(connect_pads
			(clearance 0)
		)
		(min_thickness 0.25)
		(keepout
			(tracks not_allowed)
			(vias allowed)
			(pads allowed)
			(copperpour not_allowed)
			(footprints allowed)
		)
		(placement
			(enabled no)
			(sheetname "")
		)
		(fill
			(thermal_gap 0.5)
			(thermal_bridge_width 0.5)
			(island_removal_mode 0)
		)
		(polygon
			(pts
				(arc
					(start 393.24153 -438.76087)
					(mid 393.263848 -438.814752)
					(end 393.31773 -438.83707)
				)
				(arc
					(start 394.25753 -438.83707)
					(mid 394.311412 -438.814752)
					(end 394.33373 -438.76087)
				)
				(arc
					(start 394.33373 -436.219346)
					(mid 394.311412 -436.165464)
					(end 394.25753 -436.143146)
				)
				(arc
					(start 393.31773 -436.143146)
					(mid 393.263848 -436.165464)
					(end 393.24153 -436.219346)
				)
			)
		)
	)
	(zone
		(layer "In12.Cu")
		(hatch none 0.5)
		(connect_pads
			(clearance 0)
		)
		(min_thickness 0.25)
		(keepout
			(tracks allowed)
			(vias allowed)
			(pads allowed)
			(copperpour allowed)
			(footprints allowed)
		)
		(placement
			(enabled no)
			(sheetname "")
		)
		(fill
			(thermal_gap 0.5)
			(thermal_bridge_width 0.5)
			(island_removal_mode 0)
		)
		(polygon
			(pts
				(xy 375.321068 -273.430746) (xy 375.321068 -270.382746) (xy 374.432068 -269.493746) (xy 365.034068 -269.493746)
				(xy 364.272068 -268.731746) (xy 346.365068 -268.731746) (xy 345.095068 -270.001746) (xy 345.095068 -273.430746)
				(xy 346.111068 -274.446746) (xy 374.305068 -274.446746)
			)
		)
	)
	(zone
		(layer "In12.Cu")
		(hatch none 0.5)
		(connect_pads
			(clearance 0)
		)
		(min_thickness 0.25)
		(keepout
			(tracks not_allowed)
			(vias allowed)
			(pads allowed)
			(copperpour not_allowed)
			(footprints allowed)
		)
		(placement
			(enabled no)
			(sheetname "")
		)
		(fill
			(thermal_gap 0.5)
			(thermal_bridge_width 0.5)
			(island_removal_mode 0)
		)
		(polygon
			(pts
				(arc
					(start 64.141858 -436.160418)
					(mid 64.164176 -436.2143)
					(end 64.218058 -436.236618)
				)
				(arc
					(start 65.157858 -436.236618)
					(mid 65.21174 -436.2143)
					(end 65.234058 -436.160418)
				)
				(arc
					(start 65.234058 -433.618894)
					(mid 65.21174 -433.565012)
					(end 65.157858 -433.542694)
				)
				(arc
					(start 64.218058 -433.542694)
					(mid 64.164176 -433.565012)
					(end 64.141858 -433.618894)
				)
				(arc
					(start 64.141858 -434.34635)
					(mid 64.143857 -434.363691)
					(end 64.149732 -434.380132)
				)
				(arc
					(start 64.383158 -434.856382)
					(mid 64.390941 -434.88991)
					(end 64.383158 -434.923438)
				)
				(arc
					(start 64.149732 -435.399688)
					(mid 64.143837 -435.416124)
					(end 64.141858 -435.43347)
				)
			)
		)
	)
	(zone
		(layer "In12.Cu")
		(hatch none 0.5)
		(connect_pads
			(clearance 0)
		)
		(min_thickness 0.25)
		(keepout
			(tracks not_allowed)
			(vias allowed)
			(pads allowed)
			(copperpour not_allowed)
			(footprints allowed)
		)
		(placement
			(enabled no)
			(sheetname "")
		)
		(fill
			(thermal_gap 0.5)
			(thermal_bridge_width 0.5)
			(island_removal_mode 0)
		)
		(polygon
			(pts
				(xy 230.68407 -402.746972) (xy 230.68407 -401.08124) (xy 232.412794 -401.08124) (xy 232.412794 -402.746972)
			)
		)
	)
	(zone
		(layer "In12.Cu")
		(hatch none 0.5)
		(connect_pads
			(clearance 0)
		)
		(min_thickness 0.25)
		(keepout
			(tracks not_allowed)
			(vias allowed)
			(pads allowed)
			(copperpour not_allowed)
			(footprints allowed)
		)
		(placement
			(enabled no)
			(sheetname "")
		)
		(fill
			(thermal_gap 0.5)
			(thermal_bridge_width 0.5)
			(island_removal_mode 0)
		)
		(polygon
			(pts
				(arc
					(start 62.141862 -435.16042)
					(mid 62.16418 -435.214302)
					(end 62.218062 -435.23662)
				)
				(arc
					(start 63.157862 -435.23662)
					(mid 63.211744 -435.214302)
					(end 63.234062 -435.16042)
				)
				(arc
					(start 63.234062 -432.618896)
					(mid 63.211744 -432.565014)
					(end 63.157862 -432.542696)
				)
				(arc
					(start 62.218062 -432.542696)
					(mid 62.16418 -432.565014)
					(end 62.141862 -432.618896)
				)
				(arc
					(start 62.141862 -433.346352)
					(mid 62.143861 -433.363693)
					(end 62.149736 -433.380134)
				)
				(arc
					(start 62.383162 -433.856384)
					(mid 62.390945 -433.889912)
					(end 62.383162 -433.92344)
				)
				(arc
					(start 62.149736 -434.39969)
					(mid 62.143841 -434.416126)
					(end 62.141862 -434.433472)
				)
			)
		)
	)
	(zone
		(layer "In12.Cu")
		(hatch none 0.5)
		(connect_pads
			(clearance 0)
		)
		(min_thickness 0.25)
		(keepout
			(tracks allowed)
			(vias allowed)
			(pads allowed)
			(copperpour allowed)
			(footprints allowed)
		)
		(placement
			(enabled no)
			(sheetname "")
		)
		(fill
			(thermal_gap 0.5)
			(thermal_bridge_width 0.5)
			(island_removal_mode 0)
		)
		(polygon
			(pts
				(xy 66.583814 -338.693252) (xy 66.583814 -339.539072) (xy 66.276474 -339.539072) (xy 66.276474 -338.693252)
			)
		)
	)
	(zone
		(layer "In12.Cu")
		(hatch none 0.5)
		(connect_pads
			(clearance 0)
		)
		(min_thickness 0.25)
		(keepout
			(tracks not_allowed)
			(vias allowed)
			(pads allowed)
			(copperpour not_allowed)
			(footprints allowed)
		)
		(placement
			(enabled no)
			(sheetname "")
		)
		(fill
			(thermal_gap 0.5)
			(thermal_bridge_width 0.5)
			(island_removal_mode 0)
		)
		(polygon
			(pts
				(arc
					(start 345.14155 -439.760868)
					(mid 345.163868 -439.81475)
					(end 345.21775 -439.837068)
				)
				(arc
					(start 346.15755 -439.837068)
					(mid 346.211432 -439.81475)
					(end 346.23375 -439.760868)
				)
				(arc
					(start 346.23375 -437.219344)
					(mid 346.211432 -437.165462)
					(end 346.15755 -437.143144)
				)
				(arc
					(start 345.21775 -437.143144)
					(mid 345.163868 -437.165462)
					(end 345.14155 -437.219344)
				)
			)
		)
	)
	(zone
		(layer "In12.Cu")
		(hatch none 0.5)
		(connect_pads
			(clearance 0)
		)
		(min_thickness 0.25)
		(keepout
			(tracks allowed)
			(vias allowed)
			(pads allowed)
			(copperpour allowed)
			(footprints allowed)
		)
		(placement
			(enabled no)
			(sheetname "")
		)
		(fill
			(thermal_gap 0.5)
			(thermal_bridge_width 0.5)
			(island_removal_mode 0)
		)
		(polygon
			(pts
				(xy 98.206814 -340.837012) (xy 98.206814 -341.682832) (xy 97.899474 -341.682832) (xy 97.899474 -340.837012)
			)
		)
	)
	(zone
		(layer "In12.Cu")
		(hatch none 0.5)
		(connect_pads
			(clearance 0)
		)
		(min_thickness 0.25)
		(keepout
			(tracks not_allowed)
			(vias allowed)
			(pads allowed)
			(copperpour not_allowed)
			(footprints allowed)
		)
		(placement
			(enabled no)
			(sheetname "")
		)
		(fill
			(thermal_gap 0.5)
			(thermal_bridge_width 0.5)
			(island_removal_mode 0)
		)
		(polygon
			(pts
				(arc
					(start 410.24175 -438.76087)
					(mid 410.264068 -438.814752)
					(end 410.31795 -438.83707)
				)
				(arc
					(start 411.25775 -438.83707)
					(mid 411.311632 -438.814752)
					(end 411.33395 -438.76087)
				)
				(arc
					(start 411.33395 -436.219346)
					(mid 411.311632 -436.165464)
					(end 411.25775 -436.143146)
				)
				(arc
					(start 410.31795 -436.143146)
					(mid 410.264068 -436.165464)
					(end 410.24175 -436.219346)
				)
			)
		)
	)
	(zone
		(layer "In12.Cu")
		(hatch none 0.5)
		(connect_pads
			(clearance 0)
		)
		(min_thickness 0.25)
		(keepout
			(tracks not_allowed)
			(vias allowed)
			(pads allowed)
			(copperpour not_allowed)
			(footprints allowed)
		)
		(placement
			(enabled no)
			(sheetname "")
		)
		(fill
			(thermal_gap 0.5)
			(thermal_bridge_width 0.5)
			(island_removal_mode 0)
		)
		(polygon
			(pts
				(arc
					(start 316.141354 -439.760868)
					(mid 316.163672 -439.81475)
					(end 316.217554 -439.837068)
				)
				(arc
					(start 317.157354 -439.837068)
					(mid 317.211236 -439.81475)
					(end 317.233554 -439.760868)
				)
				(arc
					(start 317.233554 -437.219344)
					(mid 317.211236 -437.165462)
					(end 317.157354 -437.143144)
				)
				(arc
					(start 316.217554 -437.143144)
					(mid 316.163672 -437.165462)
					(end 316.141354 -437.219344)
				)
			)
		)
	)
	(zone
		(layer "In12.Cu")
		(hatch none 0.5)
		(connect_pads
			(clearance 0)
		)
		(min_thickness 0.25)
		(keepout
			(tracks not_allowed)
			(vias allowed)
			(pads allowed)
			(copperpour not_allowed)
			(footprints allowed)
		)
		(placement
			(enabled no)
			(sheetname "")
		)
		(fill
			(thermal_gap 0.5)
			(thermal_bridge_width 0.5)
			(island_removal_mode 0)
		)
		(polygon
			(pts
				(arc
					(start 331.141578 -438.76087)
					(mid 331.163896 -438.814752)
					(end 331.217778 -438.83707)
				)
				(arc
					(start 332.157578 -438.83707)
					(mid 332.21146 -438.814752)
					(end 332.233778 -438.76087)
				)
				(arc
					(start 332.233778 -436.219346)
					(mid 332.21146 -436.165464)
					(end 332.157578 -436.143146)
				)
				(arc
					(start 331.217778 -436.143146)
					(mid 331.163896 -436.165464)
					(end 331.141578 -436.219346)
				)
			)
		)
	)
	(zone
		(layer "In12.Cu")
		(hatch none 0.5)
		(connect_pads
			(clearance 0)
		)
		(min_thickness 0.25)
		(keepout
			(tracks not_allowed)
			(vias allowed)
			(pads allowed)
			(copperpour not_allowed)
			(footprints allowed)
		)
		(placement
			(enabled no)
			(sheetname "")
		)
		(fill
			(thermal_gap 0.5)
			(thermal_bridge_width 0.5)
			(island_removal_mode 0)
		)
		(polygon
			(pts
				(arc
					(start 133.241542 -438.76087)
					(mid 133.26386 -438.814752)
					(end 133.317742 -438.83707)
				)
				(arc
					(start 134.257542 -438.83707)
					(mid 134.311424 -438.814752)
					(end 134.333742 -438.76087)
				)
				(arc
					(start 134.333742 -436.219346)
					(mid 134.311424 -436.165464)
					(end 134.257542 -436.143146)
				)
				(arc
					(start 133.317742 -436.143146)
					(mid 133.26386 -436.165464)
					(end 133.241542 -436.219346)
				)
			)
		)
	)
	(zone
		(layer "In12.Cu")
		(hatch none 0.5)
		(connect_pads
			(clearance 0)
		)
		(min_thickness 0.25)
		(keepout
			(tracks not_allowed)
			(vias allowed)
			(pads allowed)
			(copperpour not_allowed)
			(footprints allowed)
		)
		(placement
			(enabled no)
			(sheetname "")
		)
		(fill
			(thermal_gap 0.5)
			(thermal_bridge_width 0.5)
			(island_removal_mode 0)
		)
		(polygon
			(pts
				(xy 185.419746 -402.75383) (xy 185.419746 -401.125944) (xy 187.123324 -401.125944) (xy 187.123324 -402.75383)
			)
		)
	)
	(zone
		(layer "In12.Cu")
		(hatch none 0.5)
		(connect_pads
			(clearance 0)
		)
		(min_thickness 0.25)
		(keepout
			(tracks allowed)
			(vias allowed)
			(pads allowed)
			(copperpour allowed)
			(footprints allowed)
		)
		(placement
			(enabled no)
			(sheetname "")
		)
		(fill
			(thermal_gap 0.5)
			(thermal_bridge_width 0.5)
			(island_removal_mode 0)
		)
		(polygon
			(pts
				(xy 99.880674 -343.608152) (xy 99.880674 -344.453972) (xy 99.573334 -344.453972) (xy 99.573334 -343.608152)
			)
		)
	)
	(zone
		(layer "In12.Cu")
		(hatch none 0.5)
		(connect_pads
			(clearance 0)
		)
		(min_thickness 0.25)
		(keepout
			(tracks allowed)
			(vias allowed)
			(pads allowed)
			(copperpour allowed)
			(footprints allowed)
		)
		(placement
			(enabled no)
			(sheetname "")
		)
		(fill
			(thermal_gap 0.5)
			(thermal_bridge_width 0.5)
			(island_removal_mode 0)
		)
		(polygon
			(pts
				(xy 91.651074 -338.759292) (xy 91.651074 -339.605112) (xy 91.343734 -339.605112) (xy 91.343734 -338.759292)
			)
		)
	)
	(zone
		(layer "In12.Cu")
		(hatch none 0.5)
		(connect_pads
			(clearance 0)
		)
		(min_thickness 0.25)
		(keepout
			(tracks not_allowed)
			(vias allowed)
			(pads allowed)
			(copperpour not_allowed)
			(footprints allowed)
		)
		(placement
			(enabled no)
			(sheetname "")
		)
		(fill
			(thermal_gap 0.5)
			(thermal_bridge_width 0.5)
			(island_removal_mode 0)
		)
		(polygon
			(pts
				(arc
					(start 316.141862 -436.160418)
					(mid 316.16418 -436.2143)
					(end 316.218062 -436.236618)
				)
				(arc
					(start 317.157862 -436.236618)
					(mid 317.211744 -436.2143)
					(end 317.234062 -436.160418)
				)
				(arc
					(start 317.234062 -433.618894)
					(mid 317.211744 -433.565012)
					(end 317.157862 -433.542694)
				)
				(arc
					(start 316.218062 -433.542694)
					(mid 316.16418 -433.565012)
					(end 316.141862 -433.618894)
				)
				(arc
					(start 316.141862 -434.34635)
					(mid 316.143861 -434.363691)
					(end 316.149736 -434.380132)
				)
				(arc
					(start 316.383162 -434.856382)
					(mid 316.390945 -434.88991)
					(end 316.383162 -434.923438)
				)
				(arc
					(start 316.149736 -435.399688)
					(mid 316.143841 -435.416124)
					(end 316.141862 -435.43347)
				)
			)
		)
	)
	(zone
		(layer "In12.Cu")
		(hatch none 0.5)
		(connect_pads
			(clearance 0)
		)
		(min_thickness 0.25)
		(keepout
			(tracks not_allowed)
			(vias allowed)
			(pads allowed)
			(copperpour not_allowed)
			(footprints allowed)
		)
		(placement
			(enabled no)
			(sheetname "")
		)
		(fill
			(thermal_gap 0.5)
			(thermal_bridge_width 0.5)
			(island_removal_mode 0)
		)
		(polygon
			(pts
				(arc
					(start 339.141816 -435.16042)
					(mid 339.164134 -435.214302)
					(end 339.218016 -435.23662)
				)
				(arc
					(start 340.157816 -435.23662)
					(mid 340.211698 -435.214302)
					(end 340.234016 -435.16042)
				)
				(arc
					(start 340.234016 -432.618896)
					(mid 340.211698 -432.565014)
					(end 340.157816 -432.542696)
				)
				(arc
					(start 339.218016 -432.542696)
					(mid 339.164134 -432.565014)
					(end 339.141816 -432.618896)
				)
				(arc
					(start 339.141816 -433.346352)
					(mid 339.143815 -433.363693)
					(end 339.14969 -433.380134)
				)
				(arc
					(start 339.383116 -433.856384)
					(mid 339.390899 -433.889912)
					(end 339.383116 -433.92344)
				)
				(arc
					(start 339.14969 -434.39969)
					(mid 339.143795 -434.416126)
					(end 339.141816 -434.433472)
				)
			)
		)
	)
	(zone
		(layer "In12.Cu")
		(hatch none 0.5)
		(connect_pads
			(clearance 0)
		)
		(min_thickness 0.25)
		(keepout
			(tracks not_allowed)
			(vias allowed)
			(pads allowed)
			(copperpour not_allowed)
			(footprints allowed)
		)
		(placement
			(enabled no)
			(sheetname "")
		)
		(fill
			(thermal_gap 0.5)
			(thermal_bridge_width 0.5)
			(island_removal_mode 0)
		)
		(polygon
			(pts
				(arc
					(start 400.24177 -436.160418)
					(mid 400.264088 -436.2143)
					(end 400.31797 -436.236618)
				)
				(arc
					(start 401.25777 -436.236618)
					(mid 401.311652 -436.2143)
					(end 401.33397 -436.160418)
				)
				(arc
					(start 401.33397 -433.618894)
					(mid 401.311652 -433.565012)
					(end 401.25777 -433.542694)
				)
				(arc
					(start 400.31797 -433.542694)
					(mid 400.264088 -433.565012)
					(end 400.24177 -433.618894)
				)
				(arc
					(start 400.24177 -434.34635)
					(mid 400.243769 -434.363691)
					(end 400.249644 -434.380132)
				)
				(arc
					(start 400.48307 -434.856382)
					(mid 400.490853 -434.88991)
					(end 400.48307 -434.923438)
				)
				(arc
					(start 400.249644 -435.399688)
					(mid 400.243749 -435.416124)
					(end 400.24177 -435.43347)
				)
			)
		)
	)
	(zone
		(layer "In12.Cu")
		(hatch none 0.5)
		(connect_pads
			(clearance 0)
		)
		(min_thickness 0.25)
		(keepout
			(tracks not_allowed)
			(vias allowed)
			(pads allowed)
			(copperpour not_allowed)
			(footprints allowed)
		)
		(placement
			(enabled no)
			(sheetname "")
		)
		(fill
			(thermal_gap 0.5)
			(thermal_bridge_width 0.5)
			(island_removal_mode 0)
		)
		(polygon
			(pts
				(arc
					(start 137.241788 -435.16042)
					(mid 137.264106 -435.214302)
					(end 137.317988 -435.23662)
				)
				(arc
					(start 138.257788 -435.23662)
					(mid 138.31167 -435.214302)
					(end 138.333988 -435.16042)
				)
				(arc
					(start 138.333988 -432.618896)
					(mid 138.31167 -432.565014)
					(end 138.257788 -432.542696)
				)
				(arc
					(start 137.317988 -432.542696)
					(mid 137.264106 -432.565014)
					(end 137.241788 -432.618896)
				)
				(arc
					(start 137.241788 -433.346352)
					(mid 137.243787 -433.363693)
					(end 137.249662 -433.380134)
				)
				(arc
					(start 137.483088 -433.856384)
					(mid 137.490871 -433.889912)
					(end 137.483088 -433.92344)
				)
				(arc
					(start 137.249662 -434.39969)
					(mid 137.243767 -434.416126)
					(end 137.241788 -434.433472)
				)
			)
		)
	)
	(zone
		(layer "In12.Cu")
		(hatch none 0.5)
		(connect_pads
			(clearance 0)
		)
		(min_thickness 0.25)
		(keepout
			(tracks not_allowed)
			(vias allowed)
			(pads allowed)
			(copperpour not_allowed)
			(footprints allowed)
		)
		(placement
			(enabled no)
			(sheetname "")
		)
		(fill
			(thermal_gap 0.5)
			(thermal_bridge_width 0.5)
			(island_removal_mode 0)
		)
		(polygon
			(pts
				(arc
					(start 339.141562 -438.76087)
					(mid 339.16388 -438.814752)
					(end 339.217762 -438.83707)
				)
				(arc
					(start 340.157562 -438.83707)
					(mid 340.211444 -438.814752)
					(end 340.233762 -438.76087)
				)
				(arc
					(start 340.233762 -436.219346)
					(mid 340.211444 -436.165464)
					(end 340.157562 -436.143146)
				)
				(arc
					(start 339.217762 -436.143146)
					(mid 339.16388 -436.165464)
					(end 339.141562 -436.219346)
				)
			)
		)
	)
	(zone
		(layer "In12.Cu")
		(hatch none 0.5)
		(connect_pads
			(clearance 0)
		)
		(min_thickness 0.25)
		(keepout
			(tracks not_allowed)
			(vias allowed)
			(pads allowed)
			(copperpour not_allowed)
			(footprints allowed)
		)
		(placement
			(enabled no)
			(sheetname "")
		)
		(fill
			(thermal_gap 0.5)
			(thermal_bridge_width 0.5)
			(island_removal_mode 0)
		)
		(polygon
			(pts
				(arc
					(start 335.14157 -438.76087)
					(mid 335.163888 -438.814752)
					(end 335.21777 -438.83707)
				)
				(arc
					(start 336.15757 -438.83707)
					(mid 336.211452 -438.814752)
					(end 336.23377 -438.76087)
				)
				(arc
					(start 336.23377 -436.219346)
					(mid 336.211452 -436.165464)
					(end 336.15757 -436.143146)
				)
				(arc
					(start 335.21777 -436.143146)
					(mid 335.163888 -436.165464)
					(end 335.14157 -436.219346)
				)
			)
		)
	)
	(zone
		(layer "In12.Cu")
		(hatch none 0.5)
		(connect_pads
			(clearance 0)
		)
		(min_thickness 0.25)
		(keepout
			(tracks not_allowed)
			(vias allowed)
			(pads allowed)
			(copperpour not_allowed)
			(footprints allowed)
		)
		(placement
			(enabled no)
			(sheetname "")
		)
		(fill
			(thermal_gap 0.5)
			(thermal_bridge_width 0.5)
			(island_removal_mode 0)
		)
		(polygon
			(pts
				(arc
					(start 314.141866 -435.16042)
					(mid 314.164184 -435.214302)
					(end 314.218066 -435.23662)
				)
				(arc
					(start 315.157866 -435.23662)
					(mid 315.211748 -435.214302)
					(end 315.234066 -435.16042)
				)
				(arc
					(start 315.234066 -432.618896)
					(mid 315.211748 -432.565014)
					(end 315.157866 -432.542696)
				)
				(arc
					(start 314.218066 -432.542696)
					(mid 314.164184 -432.565014)
					(end 314.141866 -432.618896)
				)
				(arc
					(start 314.141866 -433.346352)
					(mid 314.143865 -433.363693)
					(end 314.14974 -433.380134)
				)
				(arc
					(start 314.383166 -433.856384)
					(mid 314.390949 -433.889912)
					(end 314.383166 -433.92344)
				)
				(arc
					(start 314.14974 -434.39969)
					(mid 314.143845 -434.416126)
					(end 314.141866 -434.433472)
				)
			)
		)
	)
	(zone
		(layer "In12.Cu")
		(hatch none 0.5)
		(connect_pads
			(clearance 0)
		)
		(min_thickness 0.25)
		(keepout
			(tracks not_allowed)
			(vias allowed)
			(pads allowed)
			(copperpour not_allowed)
			(footprints allowed)
		)
		(placement
			(enabled no)
			(sheetname "")
		)
		(fill
			(thermal_gap 0.5)
			(thermal_bridge_width 0.5)
			(island_removal_mode 0)
		)
		(polygon
			(pts
				(arc
					(start 131.2418 -436.160418)
					(mid 131.264118 -436.2143)
					(end 131.318 -436.236618)
				)
				(arc
					(start 132.2578 -436.236618)
					(mid 132.311682 -436.2143)
					(end 132.334 -436.160418)
				)
				(arc
					(start 132.334 -433.618894)
					(mid 132.311682 -433.565012)
					(end 132.2578 -433.542694)
				)
				(arc
					(start 131.318 -433.542694)
					(mid 131.264118 -433.565012)
					(end 131.2418 -433.618894)
				)
				(arc
					(start 131.2418 -434.34635)
					(mid 131.243799 -434.363691)
					(end 131.249674 -434.380132)
				)
				(arc
					(start 131.4831 -434.856382)
					(mid 131.490883 -434.88991)
					(end 131.4831 -434.923438)
				)
				(arc
					(start 131.249674 -435.399688)
					(mid 131.243779 -435.416124)
					(end 131.2418 -435.43347)
				)
			)
		)
	)
	(zone
		(layer "In12.Cu")
		(hatch none 0.5)
		(connect_pads
			(clearance 0)
		)
		(min_thickness 0.25)
		(keepout
			(tracks not_allowed)
			(vias allowed)
			(pads allowed)
			(copperpour not_allowed)
			(footprints allowed)
		)
		(placement
			(enabled no)
			(sheetname "")
		)
		(fill
			(thermal_gap 0.5)
			(thermal_bridge_width 0.5)
			(island_removal_mode 0)
		)
		(polygon
			(pts
				(arc
					(start 331.141832 -435.16042)
					(mid 331.16415 -435.214302)
					(end 331.218032 -435.23662)
				)
				(arc
					(start 332.157832 -435.23662)
					(mid 332.211714 -435.214302)
					(end 332.234032 -435.16042)
				)
				(arc
					(start 332.234032 -432.618896)
					(mid 332.211714 -432.565014)
					(end 332.157832 -432.542696)
				)
				(arc
					(start 331.218032 -432.542696)
					(mid 331.16415 -432.565014)
					(end 331.141832 -432.618896)
				)
				(arc
					(start 331.141832 -433.346352)
					(mid 331.143831 -433.363693)
					(end 331.149706 -433.380134)
				)
				(arc
					(start 331.383132 -433.856384)
					(mid 331.390915 -433.889912)
					(end 331.383132 -433.92344)
				)
				(arc
					(start 331.149706 -434.39969)
					(mid 331.143811 -434.416126)
					(end 331.141832 -434.433472)
				)
			)
		)
	)
	(zone
		(layer "In12.Cu")
		(hatch none 0.5)
		(connect_pads
			(clearance 0)
		)
		(min_thickness 0.25)
		(keepout
			(tracks not_allowed)
			(vias allowed)
			(pads allowed)
			(copperpour not_allowed)
			(footprints allowed)
		)
		(placement
			(enabled no)
			(sheetname "")
		)
		(fill
			(thermal_gap 0.5)
			(thermal_bridge_width 0.5)
			(island_removal_mode 0)
		)
		(polygon
			(pts
				(arc
					(start 337.141566 -439.760868)
					(mid 337.163884 -439.81475)
					(end 337.217766 -439.837068)
				)
				(arc
					(start 338.157566 -439.837068)
					(mid 338.211448 -439.81475)
					(end 338.233766 -439.760868)
				)
				(arc
					(start 338.233766 -437.219344)
					(mid 338.211448 -437.165462)
					(end 338.157566 -437.143144)
				)
				(arc
					(start 337.217766 -437.143144)
					(mid 337.163884 -437.165462)
					(end 337.141566 -437.219344)
				)
			)
		)
	)
	(zone
		(layer "In12.Cu")
		(hatch none 0.5)
		(connect_pads
			(clearance 0)
		)
		(min_thickness 0.25)
		(keepout
			(tracks not_allowed)
			(vias allowed)
			(pads allowed)
			(copperpour not_allowed)
			(footprints allowed)
		)
		(placement
			(enabled no)
			(sheetname "")
		)
		(fill
			(thermal_gap 0.5)
			(thermal_bridge_width 0.5)
			(island_removal_mode 0)
		)
		(polygon
			(pts
				(arc
					(start 127.241808 -436.160418)
					(mid 127.264126 -436.2143)
					(end 127.318008 -436.236618)
				)
				(arc
					(start 128.257808 -436.236618)
					(mid 128.31169 -436.2143)
					(end 128.334008 -436.160418)
				)
				(arc
					(start 128.334008 -433.618894)
					(mid 128.31169 -433.565012)
					(end 128.257808 -433.542694)
				)
				(arc
					(start 127.318008 -433.542694)
					(mid 127.264126 -433.565012)
					(end 127.241808 -433.618894)
				)
				(arc
					(start 127.241808 -434.34635)
					(mid 127.243807 -434.363691)
					(end 127.249682 -434.380132)
				)
				(arc
					(start 127.483108 -434.856382)
					(mid 127.490891 -434.88991)
					(end 127.483108 -434.923438)
				)
				(arc
					(start 127.249682 -435.399688)
					(mid 127.243787 -435.416124)
					(end 127.241808 -435.43347)
				)
			)
		)
	)
	(zone
		(layer "In12.Cu")
		(hatch none 0.5)
		(connect_pads
			(clearance 0)
		)
		(min_thickness 0.25)
		(keepout
			(tracks not_allowed)
			(vias allowed)
			(pads allowed)
			(copperpour not_allowed)
			(footprints allowed)
		)
		(placement
			(enabled no)
			(sheetname "")
		)
		(fill
			(thermal_gap 0.5)
			(thermal_bridge_width 0.5)
			(island_removal_mode 0)
		)
		(polygon
			(pts
				(arc
					(start 318.14135 -438.76087)
					(mid 318.163668 -438.814752)
					(end 318.21755 -438.83707)
				)
				(arc
					(start 319.15735 -438.83707)
					(mid 319.211232 -438.814752)
					(end 319.23355 -438.76087)
				)
				(arc
					(start 319.23355 -436.219346)
					(mid 319.211232 -436.165464)
					(end 319.15735 -436.143146)
				)
				(arc
					(start 318.21755 -436.143146)
					(mid 318.163668 -436.165464)
					(end 318.14135 -436.219346)
				)
			)
		)
	)
	(zone
		(layer "In12.Cu")
		(hatch none 0.5)
		(connect_pads
			(clearance 0)
		)
		(min_thickness 0.25)
		(keepout
			(tracks not_allowed)
			(vias allowed)
			(pads allowed)
			(copperpour not_allowed)
			(footprints allowed)
		)
		(placement
			(enabled no)
			(sheetname "")
		)
		(fill
			(thermal_gap 0.5)
			(thermal_bridge_width 0.5)
			(island_removal_mode 0)
		)
		(polygon
			(pts
				(arc
					(start 395.24178 -436.160418)
					(mid 395.264098 -436.2143)
					(end 395.31798 -436.236618)
				)
				(arc
					(start 396.25778 -436.236618)
					(mid 396.311662 -436.2143)
					(end 396.33398 -436.160418)
				)
				(arc
					(start 396.33398 -433.618894)
					(mid 396.311662 -433.565012)
					(end 396.25778 -433.542694)
				)
				(arc
					(start 395.31798 -433.542694)
					(mid 395.264098 -433.565012)
					(end 395.24178 -433.618894)
				)
				(arc
					(start 395.24178 -434.34635)
					(mid 395.243779 -434.363691)
					(end 395.249654 -434.380132)
				)
				(arc
					(start 395.48308 -434.856382)
					(mid 395.490863 -434.88991)
					(end 395.48308 -434.923438)
				)
				(arc
					(start 395.249654 -435.399688)
					(mid 395.243759 -435.416124)
					(end 395.24178 -435.43347)
				)
			)
		)
	)
	(zone
		(layer "In12.Cu")
		(hatch none 0.5)
		(connect_pads
			(clearance 0)
		)
		(min_thickness 0.25)
		(keepout
			(tracks not_allowed)
			(vias allowed)
			(pads allowed)
			(copperpour not_allowed)
			(footprints allowed)
		)
		(placement
			(enabled no)
			(sheetname "")
		)
		(fill
			(thermal_gap 0.5)
			(thermal_bridge_width 0.5)
			(island_removal_mode 0)
		)
		(polygon
			(pts
				(arc
					(start 68.14185 -436.160418)
					(mid 68.164168 -436.2143)
					(end 68.21805 -436.236618)
				)
				(arc
					(start 69.15785 -436.236618)
					(mid 69.211732 -436.2143)
					(end 69.23405 -436.160418)
				)
				(arc
					(start 69.23405 -433.618894)
					(mid 69.211732 -433.565012)
					(end 69.15785 -433.542694)
				)
				(arc
					(start 68.21805 -433.542694)
					(mid 68.164168 -433.565012)
					(end 68.14185 -433.618894)
				)
				(arc
					(start 68.14185 -434.34635)
					(mid 68.143849 -434.363691)
					(end 68.149724 -434.380132)
				)
				(arc
					(start 68.38315 -434.856382)
					(mid 68.390933 -434.88991)
					(end 68.38315 -434.923438)
				)
				(arc
					(start 68.149724 -435.399688)
					(mid 68.143829 -435.416124)
					(end 68.14185 -435.43347)
				)
			)
		)
	)
	(zone
		(layer "In12.Cu")
		(hatch none 0.5)
		(connect_pads
			(clearance 0)
		)
		(min_thickness 0.25)
		(keepout
			(tracks not_allowed)
			(vias allowed)
			(pads allowed)
			(copperpour not_allowed)
			(footprints allowed)
		)
		(placement
			(enabled no)
			(sheetname "")
		)
		(fill
			(thermal_gap 0.5)
			(thermal_bridge_width 0.5)
			(island_removal_mode 0)
		)
		(polygon
			(pts
				(arc
					(start 79.141828 -435.16042)
					(mid 79.164146 -435.214302)
					(end 79.218028 -435.23662)
				)
				(arc
					(start 80.157828 -435.23662)
					(mid 80.21171 -435.214302)
					(end 80.234028 -435.16042)
				)
				(arc
					(start 80.234028 -432.618896)
					(mid 80.21171 -432.565014)
					(end 80.157828 -432.542696)
				)
				(arc
					(start 79.218028 -432.542696)
					(mid 79.164146 -432.565014)
					(end 79.141828 -432.618896)
				)
				(arc
					(start 79.141828 -433.346352)
					(mid 79.143827 -433.363693)
					(end 79.149702 -433.380134)
				)
				(arc
					(start 79.383128 -433.856384)
					(mid 79.390911 -433.889912)
					(end 79.383128 -433.92344)
				)
				(arc
					(start 79.149702 -434.39969)
					(mid 79.143807 -434.416126)
					(end 79.141828 -434.433472)
				)
			)
		)
	)
	(zone
		(layer "In12.Cu")
		(hatch none 0.5)
		(connect_pads
			(clearance 0)
		)
		(min_thickness 0.25)
		(keepout
			(tracks not_allowed)
			(vias allowed)
			(pads allowed)
			(copperpour not_allowed)
			(footprints allowed)
		)
		(placement
			(enabled no)
			(sheetname "")
		)
		(fill
			(thermal_gap 0.5)
			(thermal_bridge_width 0.5)
			(island_removal_mode 0)
		)
		(polygon
			(pts
				(arc
					(start 131.241546 -439.760868)
					(mid 131.263864 -439.81475)
					(end 131.317746 -439.837068)
				)
				(arc
					(start 132.257546 -439.837068)
					(mid 132.311428 -439.81475)
					(end 132.333746 -439.760868)
				)
				(arc
					(start 132.333746 -437.219344)
					(mid 132.311428 -437.165462)
					(end 132.257546 -437.143144)
				)
				(arc
					(start 131.317746 -437.143144)
					(mid 131.263864 -437.165462)
					(end 131.241546 -437.219344)
				)
			)
		)
	)
	(zone
		(layer "In12.Cu")
		(hatch none 0.5)
		(connect_pads
			(clearance 0)
		)
		(min_thickness 0.25)
		(keepout
			(tracks not_allowed)
			(vias allowed)
			(pads allowed)
			(copperpour not_allowed)
			(footprints allowed)
		)
		(placement
			(enabled no)
			(sheetname "")
		)
		(fill
			(thermal_gap 0.5)
			(thermal_bridge_width 0.5)
			(island_removal_mode 0)
		)
		(polygon
			(pts
				(arc
					(start 318.141858 -435.16042)
					(mid 318.164176 -435.214302)
					(end 318.218058 -435.23662)
				)
				(arc
					(start 319.157858 -435.23662)
					(mid 319.21174 -435.214302)
					(end 319.234058 -435.16042)
				)
				(arc
					(start 319.234058 -432.618896)
					(mid 319.21174 -432.565014)
					(end 319.157858 -432.542696)
				)
				(arc
					(start 318.218058 -432.542696)
					(mid 318.164176 -432.565014)
					(end 318.141858 -432.618896)
				)
				(arc
					(start 318.141858 -433.346352)
					(mid 318.143857 -433.363693)
					(end 318.149732 -433.380134)
				)
				(arc
					(start 318.383158 -433.856384)
					(mid 318.390941 -433.889912)
					(end 318.383158 -433.92344)
				)
				(arc
					(start 318.149732 -434.39969)
					(mid 318.143837 -434.416126)
					(end 318.141858 -434.433472)
				)
			)
		)
	)
	(zone
		(layer "In12.Cu")
		(hatch none 0.5)
		(connect_pads
			(clearance 0)
		)
		(min_thickness 0.25)
		(keepout
			(tracks not_allowed)
			(vias allowed)
			(pads allowed)
			(copperpour not_allowed)
			(footprints allowed)
		)
		(placement
			(enabled no)
			(sheetname "")
		)
		(fill
			(thermal_gap 0.5)
			(thermal_bridge_width 0.5)
			(island_removal_mode 0)
		)
		(polygon
			(pts
				(arc
					(start 320.141346 -439.760868)
					(mid 320.163664 -439.81475)
					(end 320.217546 -439.837068)
				)
				(arc
					(start 321.157346 -439.837068)
					(mid 321.211228 -439.81475)
					(end 321.233546 -439.760868)
				)
				(arc
					(start 321.233546 -437.219344)
					(mid 321.211228 -437.165462)
					(end 321.157346 -437.143144)
				)
				(arc
					(start 320.217546 -437.143144)
					(mid 320.163664 -437.165462)
					(end 320.141346 -437.219344)
				)
			)
		)
	)
	(zone
		(layer "In12.Cu")
		(hatch none 0.5)
		(connect_pads
			(clearance 0)
		)
		(min_thickness 0.25)
		(keepout
			(tracks not_allowed)
			(vias allowed)
			(pads allowed)
			(copperpour not_allowed)
			(footprints allowed)
		)
		(placement
			(enabled no)
			(sheetname "")
		)
		(fill
			(thermal_gap 0.5)
			(thermal_bridge_width 0.5)
			(island_removal_mode 0)
		)
		(polygon
			(pts
				(arc
					(start 148.241766 -436.160418)
					(mid 148.264084 -436.2143)
					(end 148.317966 -436.236618)
				)
				(arc
					(start 149.257766 -436.236618)
					(mid 149.311648 -436.2143)
					(end 149.333966 -436.160418)
				)
				(arc
					(start 149.333966 -433.618894)
					(mid 149.311648 -433.565012)
					(end 149.257766 -433.542694)
				)
				(arc
					(start 148.317966 -433.542694)
					(mid 148.264084 -433.565012)
					(end 148.241766 -433.618894)
				)
				(arc
					(start 148.241766 -434.34635)
					(mid 148.243765 -434.363691)
					(end 148.24964 -434.380132)
				)
				(arc
					(start 148.483066 -434.856382)
					(mid 148.490849 -434.88991)
					(end 148.483066 -434.923438)
				)
				(arc
					(start 148.24964 -435.399688)
					(mid 148.243745 -435.416124)
					(end 148.241766 -435.43347)
				)
			)
		)
	)
	(zone
		(layer "In12.Cu")
		(hatch none 0.5)
		(connect_pads
			(clearance 0)
		)
		(min_thickness 0.25)
		(keepout
			(tracks not_allowed)
			(vias allowed)
			(pads allowed)
			(copperpour not_allowed)
			(footprints allowed)
		)
		(placement
			(enabled no)
			(sheetname "")
		)
		(fill
			(thermal_gap 0.5)
			(thermal_bridge_width 0.5)
			(island_removal_mode 0)
		)
		(polygon
			(pts
				(arc
					(start 408.241754 -439.760868)
					(mid 408.264072 -439.81475)
					(end 408.317954 -439.837068)
				)
				(arc
					(start 409.257754 -439.837068)
					(mid 409.311636 -439.81475)
					(end 409.333954 -439.760868)
				)
				(arc
					(start 409.333954 -437.219344)
					(mid 409.311636 -437.165462)
					(end 409.257754 -437.143144)
				)
				(arc
					(start 408.317954 -437.143144)
					(mid 408.264072 -437.165462)
					(end 408.241754 -437.219344)
				)
			)
		)
	)
	(zone
		(layer "In12.Cu")
		(hatch none 0.5)
		(connect_pads
			(clearance 0)
		)
		(min_thickness 0.25)
		(keepout
			(tracks allowed)
			(vias allowed)
			(pads allowed)
			(copperpour allowed)
			(footprints allowed)
		)
		(placement
			(enabled no)
			(sheetname "")
		)
		(fill
			(thermal_gap 0.5)
			(thermal_bridge_width 0.5)
			(island_removal_mode 0)
		)
		(polygon
			(pts
				(xy 81.600294 -335.876392) (xy 81.600294 -336.722212) (xy 81.292954 -336.722212) (xy 81.292954 -335.876392)
			)
		)
	)
	(zone
		(layer "In12.Cu")
		(hatch none 0.5)
		(connect_pads
			(clearance 0)
		)
		(min_thickness 0.25)
		(keepout
			(tracks not_allowed)
			(vias allowed)
			(pads allowed)
			(copperpour not_allowed)
			(footprints allowed)
		)
		(placement
			(enabled no)
			(sheetname "")
		)
		(fill
			(thermal_gap 0.5)
			(thermal_bridge_width 0.5)
			(island_removal_mode 0)
		)
		(polygon
			(pts
				(arc
					(start 324.141846 -436.160418)
					(mid 324.164164 -436.2143)
					(end 324.218046 -436.236618)
				)
				(arc
					(start 325.157846 -436.236618)
					(mid 325.211728 -436.2143)
					(end 325.234046 -436.160418)
				)
				(arc
					(start 325.234046 -433.618894)
					(mid 325.211728 -433.565012)
					(end 325.157846 -433.542694)
				)
				(arc
					(start 324.218046 -433.542694)
					(mid 324.164164 -433.565012)
					(end 324.141846 -433.618894)
				)
				(arc
					(start 324.141846 -434.34635)
					(mid 324.143845 -434.363691)
					(end 324.14972 -434.380132)
				)
				(arc
					(start 324.383146 -434.856382)
					(mid 324.390929 -434.88991)
					(end 324.383146 -434.923438)
				)
				(arc
					(start 324.14972 -435.399688)
					(mid 324.143825 -435.416124)
					(end 324.141846 -435.43347)
				)
			)
		)
	)
	(zone
		(layer "In12.Cu")
		(hatch none 0.5)
		(connect_pads
			(clearance 0)
		)
		(min_thickness 0.25)
		(keepout
			(tracks not_allowed)
			(vias allowed)
			(pads allowed)
			(copperpour not_allowed)
			(footprints allowed)
		)
		(placement
			(enabled no)
			(sheetname "")
		)
		(fill
			(thermal_gap 0.5)
			(thermal_bridge_width 0.5)
			(island_removal_mode 0)
		)
		(polygon
			(pts
				(arc
					(start 404.241762 -436.160418)
					(mid 404.26408 -436.2143)
					(end 404.317962 -436.236618)
				)
				(arc
					(start 405.257762 -436.236618)
					(mid 405.311644 -436.2143)
					(end 405.333962 -436.160418)
				)
				(arc
					(start 405.333962 -433.618894)
					(mid 405.311644 -433.565012)
					(end 405.257762 -433.542694)
				)
				(arc
					(start 404.317962 -433.542694)
					(mid 404.26408 -433.565012)
					(end 404.241762 -433.618894)
				)
				(arc
					(start 404.241762 -434.34635)
					(mid 404.243761 -434.363691)
					(end 404.249636 -434.380132)
				)
				(arc
					(start 404.483062 -434.856382)
					(mid 404.490845 -434.88991)
					(end 404.483062 -434.923438)
				)
				(arc
					(start 404.249636 -435.399688)
					(mid 404.243741 -435.416124)
					(end 404.241762 -435.43347)
				)
			)
		)
	)
	(zone
		(layer "In12.Cu")
		(hatch none 0.5)
		(connect_pads
			(clearance 0)
		)
		(min_thickness 0.25)
		(keepout
			(tracks not_allowed)
			(vias allowed)
			(pads allowed)
			(copperpour not_allowed)
			(footprints allowed)
		)
		(placement
			(enabled no)
			(sheetname "")
		)
		(fill
			(thermal_gap 0.5)
			(thermal_bridge_width 0.5)
			(island_removal_mode 0)
		)
		(polygon
			(pts
				(arc
					(start 144.241774 -436.160418)
					(mid 144.264092 -436.2143)
					(end 144.317974 -436.236618)
				)
				(arc
					(start 145.257774 -436.236618)
					(mid 145.311656 -436.2143)
					(end 145.333974 -436.160418)
				)
				(arc
					(start 145.333974 -433.618894)
					(mid 145.311656 -433.565012)
					(end 145.257774 -433.542694)
				)
				(arc
					(start 144.317974 -433.542694)
					(mid 144.264092 -433.565012)
					(end 144.241774 -433.618894)
				)
				(arc
					(start 144.241774 -434.34635)
					(mid 144.243773 -434.363691)
					(end 144.249648 -434.380132)
				)
				(arc
					(start 144.483074 -434.856382)
					(mid 144.490857 -434.88991)
					(end 144.483074 -434.923438)
				)
				(arc
					(start 144.249648 -435.399688)
					(mid 144.243753 -435.416124)
					(end 144.241774 -435.43347)
				)
			)
		)
	)
	(zone
		(layer "In12.Cu")
		(hatch none 0.5)
		(connect_pads
			(clearance 0)
		)
		(min_thickness 0.25)
		(keepout
			(tracks not_allowed)
			(vias allowed)
			(pads allowed)
			(copperpour not_allowed)
			(footprints allowed)
		)
		(placement
			(enabled no)
			(sheetname "")
		)
		(fill
			(thermal_gap 0.5)
			(thermal_bridge_width 0.5)
			(island_removal_mode 0)
		)
		(polygon
			(pts
				(arc
					(start 341.141812 -436.160418)
					(mid 341.16413 -436.2143)
					(end 341.218012 -436.236618)
				)
				(arc
					(start 342.157812 -436.236618)
					(mid 342.211694 -436.2143)
					(end 342.234012 -436.160418)
				)
				(arc
					(start 342.234012 -433.618894)
					(mid 342.211694 -433.565012)
					(end 342.157812 -433.542694)
				)
				(arc
					(start 341.218012 -433.542694)
					(mid 341.16413 -433.565012)
					(end 341.141812 -433.618894)
				)
				(arc
					(start 341.141812 -434.34635)
					(mid 341.143811 -434.363691)
					(end 341.149686 -434.380132)
				)
				(arc
					(start 341.383112 -434.856382)
					(mid 341.390895 -434.88991)
					(end 341.383112 -434.923438)
				)
				(arc
					(start 341.149686 -435.399688)
					(mid 341.143791 -435.416124)
					(end 341.141812 -435.43347)
				)
			)
		)
	)
	(zone
		(layer "In12.Cu")
		(hatch none 0.5)
		(connect_pads
			(clearance 0)
		)
		(min_thickness 0.25)
		(keepout
			(tracks allowed)
			(vias allowed)
			(pads allowed)
			(copperpour allowed)
			(footprints allowed)
		)
		(placement
			(enabled no)
			(sheetname "")
		)
		(fill
			(thermal_gap 0.5)
			(thermal_bridge_width 0.5)
			(island_removal_mode 0)
		)
		(polygon
			(pts
				(xy 33.088834 -350.387412) (xy 33.088834 -351.233232) (xy 32.781494 -351.233232) (xy 32.781494 -350.387412)
			)
		)
	)
	(zone
		(layer "In12.Cu")
		(hatch none 0.5)
		(connect_pads
			(clearance 0)
		)
		(min_thickness 0.25)
		(keepout
			(tracks not_allowed)
			(vias allowed)
			(pads allowed)
			(copperpour not_allowed)
			(footprints allowed)
		)
		(placement
			(enabled no)
			(sheetname "")
		)
		(fill
			(thermal_gap 0.5)
			(thermal_bridge_width 0.5)
			(island_removal_mode 0)
		)
		(polygon
			(pts
				(arc
					(start 387.241542 -439.760868)
					(mid 387.26386 -439.81475)
					(end 387.317742 -439.837068)
				)
				(arc
					(start 388.257542 -439.837068)
					(mid 388.311424 -439.81475)
					(end 388.333742 -439.760868)
				)
				(arc
					(start 388.333742 -437.219344)
					(mid 388.311424 -437.165462)
					(end 388.257542 -437.143144)
				)
				(arc
					(start 387.317742 -437.143144)
					(mid 387.26386 -437.165462)
					(end 387.241542 -437.219344)
				)
			)
		)
	)
	(zone
		(layer "In12.Cu")
		(hatch none 0.5)
		(connect_pads
			(clearance 0)
		)
		(min_thickness 0.25)
		(keepout
			(tracks not_allowed)
			(vias allowed)
			(pads allowed)
			(copperpour not_allowed)
			(footprints allowed)
		)
		(placement
			(enabled no)
			(sheetname "")
		)
		(fill
			(thermal_gap 0.5)
			(thermal_bridge_width 0.5)
			(island_removal_mode 0)
		)
		(polygon
			(pts
				(arc
					(start 335.141824 -435.16042)
					(mid 335.164142 -435.214302)
					(end 335.218024 -435.23662)
				)
				(arc
					(start 336.157824 -435.23662)
					(mid 336.211706 -435.214302)
					(end 336.234024 -435.16042)
				)
				(arc
					(start 336.234024 -432.618896)
					(mid 336.211706 -432.565014)
					(end 336.157824 -432.542696)
				)
				(arc
					(start 335.218024 -432.542696)
					(mid 335.164142 -432.565014)
					(end 335.141824 -432.618896)
				)
				(arc
					(start 335.141824 -433.346352)
					(mid 335.143823 -433.363693)
					(end 335.149698 -433.380134)
				)
				(arc
					(start 335.383124 -433.856384)
					(mid 335.390907 -433.889912)
					(end 335.383124 -433.92344)
				)
				(arc
					(start 335.149698 -434.39969)
					(mid 335.143803 -434.416126)
					(end 335.141824 -434.433472)
				)
			)
		)
	)
	(zone
		(layer "In12.Cu")
		(hatch none 0.5)
		(connect_pads
			(clearance 0)
		)
		(min_thickness 0.25)
		(keepout
			(tracks not_allowed)
			(vias allowed)
			(pads allowed)
			(copperpour not_allowed)
			(footprints allowed)
		)
		(placement
			(enabled no)
			(sheetname "")
		)
		(fill
			(thermal_gap 0.5)
			(thermal_bridge_width 0.5)
			(island_removal_mode 0)
		)
		(polygon
			(pts
				(arc
					(start 412.241746 -436.160418)
					(mid 412.264064 -436.2143)
					(end 412.317946 -436.236618)
				)
				(arc
					(start 413.257746 -436.236618)
					(mid 413.311628 -436.2143)
					(end 413.333946 -436.160418)
				)
				(arc
					(start 413.333946 -433.618894)
					(mid 413.311628 -433.565012)
					(end 413.257746 -433.542694)
				)
				(arc
					(start 412.317946 -433.542694)
					(mid 412.264064 -433.565012)
					(end 412.241746 -433.618894)
				)
				(arc
					(start 412.241746 -434.34635)
					(mid 412.243745 -434.363691)
					(end 412.24962 -434.380132)
				)
				(arc
					(start 412.483046 -434.856382)
					(mid 412.490829 -434.88991)
					(end 412.483046 -434.923438)
				)
				(arc
					(start 412.24962 -435.399688)
					(mid 412.243725 -435.416124)
					(end 412.241746 -435.43347)
				)
			)
		)
	)
	(zone
		(layer "In12.Cu")
		(hatch none 0.5)
		(connect_pads
			(clearance 0)
		)
		(min_thickness 0.25)
		(keepout
			(tracks allowed)
			(vias allowed)
			(pads allowed)
			(copperpour allowed)
			(footprints allowed)
		)
		(placement
			(enabled no)
			(sheetname "")
		)
		(fill
			(thermal_gap 0.5)
			(thermal_bridge_width 0.5)
			(island_removal_mode 0)
		)
		(polygon
			(pts
				(xy 23.060914 -347.585792) (xy 23.060914 -348.431612) (xy 22.753574 -348.431612) (xy 22.753574 -347.585792)
			)
		)
	)
	(zone
		(layer "In12.Cu")
		(hatch none 0.5)
		(connect_pads
			(clearance 0)
		)
		(min_thickness 0.25)
		(keepout
			(tracks not_allowed)
			(vias allowed)
			(pads allowed)
			(copperpour not_allowed)
			(footprints allowed)
		)
		(placement
			(enabled no)
			(sheetname "")
		)
		(fill
			(thermal_gap 0.5)
			(thermal_bridge_width 0.5)
			(island_removal_mode 0)
		)
		(polygon
			(pts
				(arc
					(start 139.241784 -436.160418)
					(mid 139.264102 -436.2143)
					(end 139.317984 -436.236618)
				)
				(arc
					(start 140.257784 -436.236618)
					(mid 140.311666 -436.2143)
					(end 140.333984 -436.160418)
				)
				(arc
					(start 140.333984 -433.618894)
					(mid 140.311666 -433.565012)
					(end 140.257784 -433.542694)
				)
				(arc
					(start 139.317984 -433.542694)
					(mid 139.264102 -433.565012)
					(end 139.241784 -433.618894)
				)
				(arc
					(start 139.241784 -434.34635)
					(mid 139.243783 -434.363691)
					(end 139.249658 -434.380132)
				)
				(arc
					(start 139.483084 -434.856382)
					(mid 139.490867 -434.88991)
					(end 139.483084 -434.923438)
				)
				(arc
					(start 139.249658 -435.399688)
					(mid 139.243763 -435.416124)
					(end 139.241784 -435.43347)
				)
			)
		)
	)
	(zone
		(layer "In12.Cu")
		(hatch none 0.5)
		(connect_pads
			(clearance 0)
		)
		(min_thickness 0.25)
		(keepout
			(tracks not_allowed)
			(vias allowed)
			(pads allowed)
			(copperpour not_allowed)
			(footprints allowed)
		)
		(placement
			(enabled no)
			(sheetname "")
		)
		(fill
			(thermal_gap 0.5)
			(thermal_bridge_width 0.5)
			(island_removal_mode 0)
		)
		(polygon
			(pts
				(arc
					(start 89.141808 -436.160418)
					(mid 89.164126 -436.2143)
					(end 89.218008 -436.236618)
				)
				(arc
					(start 90.157808 -436.236618)
					(mid 90.21169 -436.2143)
					(end 90.234008 -436.160418)
				)
				(arc
					(start 90.234008 -433.618894)
					(mid 90.21169 -433.565012)
					(end 90.157808 -433.542694)
				)
				(arc
					(start 89.218008 -433.542694)
					(mid 89.164126 -433.565012)
					(end 89.141808 -433.618894)
				)
				(arc
					(start 89.141808 -434.34635)
					(mid 89.143807 -434.363691)
					(end 89.149682 -434.380132)
				)
				(arc
					(start 89.383108 -434.856382)
					(mid 89.390891 -434.88991)
					(end 89.383108 -434.923438)
				)
				(arc
					(start 89.149682 -435.399688)
					(mid 89.143787 -435.416124)
					(end 89.141808 -435.43347)
				)
			)
		)
	)
	(zone
		(layer "In12.Cu")
		(hatch none 0.5)
		(connect_pads
			(clearance 0)
		)
		(min_thickness 0.25)
		(keepout
			(tracks not_allowed)
			(vias allowed)
			(pads allowed)
			(copperpour not_allowed)
			(footprints allowed)
		)
		(placement
			(enabled no)
			(sheetname "")
		)
		(fill
			(thermal_gap 0.5)
			(thermal_bridge_width 0.5)
			(island_removal_mode 0)
		)
		(polygon
			(pts
				(arc
					(start 389.241792 -435.16042)
					(mid 389.26411 -435.214302)
					(end 389.317992 -435.23662)
				)
				(arc
					(start 390.257792 -435.23662)
					(mid 390.311674 -435.214302)
					(end 390.333992 -435.16042)
				)
				(arc
					(start 390.333992 -432.618896)
					(mid 390.311674 -432.565014)
					(end 390.257792 -432.542696)
				)
				(arc
					(start 389.317992 -432.542696)
					(mid 389.26411 -432.565014)
					(end 389.241792 -432.618896)
				)
				(arc
					(start 389.241792 -433.346352)
					(mid 389.243791 -433.363693)
					(end 389.249666 -433.380134)
				)
				(arc
					(start 389.483092 -433.856384)
					(mid 389.490875 -433.889912)
					(end 389.483092 -433.92344)
				)
				(arc
					(start 389.249666 -434.39969)
					(mid 389.243771 -434.416126)
					(end 389.241792 -434.433472)
				)
			)
		)
	)
	(zone
		(layer "In12.Cu")
		(hatch none 0.5)
		(connect_pads
			(clearance 0)
		)
		(min_thickness 0.25)
		(keepout
			(tracks not_allowed)
			(vias allowed)
			(pads allowed)
			(copperpour not_allowed)
			(footprints allowed)
		)
		(placement
			(enabled no)
			(sheetname "")
		)
		(fill
			(thermal_gap 0.5)
			(thermal_bridge_width 0.5)
			(island_removal_mode 0)
		)
		(polygon
			(pts
				(arc
					(start 400.24177 -439.760868)
					(mid 400.264088 -439.81475)
					(end 400.31797 -439.837068)
				)
				(arc
					(start 401.25777 -439.837068)
					(mid 401.311652 -439.81475)
					(end 401.33397 -439.760868)
				)
				(arc
					(start 401.33397 -437.219344)
					(mid 401.311652 -437.165462)
					(end 401.25777 -437.143144)
				)
				(arc
					(start 400.31797 -437.143144)
					(mid 400.264088 -437.165462)
					(end 400.24177 -437.219344)
				)
			)
		)
	)
	(zone
		(layer "In12.Cu")
		(hatch none 0.5)
		(connect_pads
			(clearance 0)
		)
		(min_thickness 0.25)
		(keepout
			(tracks not_allowed)
			(vias allowed)
			(pads allowed)
			(copperpour not_allowed)
			(footprints allowed)
		)
		(placement
			(enabled no)
			(sheetname "")
		)
		(fill
			(thermal_gap 0.5)
			(thermal_bridge_width 0.5)
			(island_removal_mode 0)
		)
		(polygon
			(pts
				(arc
					(start 127.241554 -439.760868)
					(mid 127.263872 -439.81475)
					(end 127.317754 -439.837068)
				)
				(arc
					(start 128.257554 -439.837068)
					(mid 128.311436 -439.81475)
					(end 128.333754 -439.760868)
				)
				(arc
					(start 128.333754 -437.219344)
					(mid 128.311436 -437.165462)
					(end 128.257554 -437.143144)
				)
				(arc
					(start 127.317754 -437.143144)
					(mid 127.263872 -437.165462)
					(end 127.241554 -437.219344)
				)
			)
		)
	)
	(zone
		(layer "In12.Cu")
		(hatch none 0.5)
		(connect_pads
			(clearance 0)
		)
		(min_thickness 0.25)
		(keepout
			(tracks allowed)
			(vias allowed)
			(pads allowed)
			(copperpour allowed)
			(footprints allowed)
		)
		(placement
			(enabled no)
			(sheetname "")
		)
		(fill
			(thermal_gap 0.5)
			(thermal_bridge_width 0.5)
			(island_removal_mode 0)
		)
		(polygon
			(pts
				(xy 31.315914 -347.601032) (xy 31.315914 -348.446852) (xy 31.008574 -348.446852) (xy 31.008574 -347.601032)
			)
		)
	)
	(zone
		(layer "In12.Cu")
		(hatch none 0.5)
		(connect_pads
			(clearance 0)
		)
		(min_thickness 0.25)
		(keepout
			(tracks not_allowed)
			(vias allowed)
			(pads allowed)
			(copperpour not_allowed)
			(footprints allowed)
		)
		(placement
			(enabled no)
			(sheetname "")
		)
		(fill
			(thermal_gap 0.5)
			(thermal_bridge_width 0.5)
			(island_removal_mode 0)
		)
		(polygon
			(pts
				(arc
					(start 135.241538 -439.760868)
					(mid 135.263856 -439.81475)
					(end 135.317738 -439.837068)
				)
				(arc
					(start 136.257538 -439.837068)
					(mid 136.31142 -439.81475)
					(end 136.333738 -439.760868)
				)
				(arc
					(start 136.333738 -437.219344)
					(mid 136.31142 -437.165462)
					(end 136.257538 -437.143144)
				)
				(arc
					(start 135.317738 -437.143144)
					(mid 135.263856 -437.165462)
					(end 135.241538 -437.219344)
				)
			)
		)
	)
	(zone
		(layer "In12.Cu")
		(hatch none 0.5)
		(connect_pads
			(clearance 0)
		)
		(min_thickness 0.25)
		(keepout
			(tracks not_allowed)
			(vias allowed)
			(pads allowed)
			(copperpour not_allowed)
			(footprints allowed)
		)
		(placement
			(enabled no)
			(sheetname "")
		)
		(fill
			(thermal_gap 0.5)
			(thermal_bridge_width 0.5)
			(island_removal_mode 0)
		)
		(polygon
			(pts
				(arc
					(start 322.141342 -438.76087)
					(mid 322.16366 -438.814752)
					(end 322.217542 -438.83707)
				)
				(arc
					(start 323.157342 -438.83707)
					(mid 323.211224 -438.814752)
					(end 323.233542 -438.76087)
				)
				(arc
					(start 323.233542 -436.219346)
					(mid 323.211224 -436.165464)
					(end 323.157342 -436.143146)
				)
				(arc
					(start 322.217542 -436.143146)
					(mid 322.16366 -436.165464)
					(end 322.141342 -436.219346)
				)
			)
		)
	)
	(zone
		(layer "In12.Cu")
		(hatch none 0.5)
		(connect_pads
			(clearance 0)
		)
		(min_thickness 0.25)
		(keepout
			(tracks not_allowed)
			(vias allowed)
			(pads allowed)
			(copperpour not_allowed)
			(footprints allowed)
		)
		(placement
			(enabled no)
			(sheetname "")
		)
		(fill
			(thermal_gap 0.5)
			(thermal_bridge_width 0.5)
			(island_removal_mode 0)
		)
		(polygon
			(pts
				(arc
					(start 87.141812 -435.16042)
					(mid 87.16413 -435.214302)
					(end 87.218012 -435.23662)
				)
				(arc
					(start 88.157812 -435.23662)
					(mid 88.211694 -435.214302)
					(end 88.234012 -435.16042)
				)
				(arc
					(start 88.234012 -432.618896)
					(mid 88.211694 -432.565014)
					(end 88.157812 -432.542696)
				)
				(arc
					(start 87.218012 -432.542696)
					(mid 87.16413 -432.565014)
					(end 87.141812 -432.618896)
				)
				(arc
					(start 87.141812 -433.346352)
					(mid 87.143811 -433.363693)
					(end 87.149686 -433.380134)
				)
				(arc
					(start 87.383112 -433.856384)
					(mid 87.390895 -433.889912)
					(end 87.383112 -433.92344)
				)
				(arc
					(start 87.149686 -434.39969)
					(mid 87.143791 -434.416126)
					(end 87.141812 -434.433472)
				)
			)
		)
	)
	(zone
		(layer "In12.Cu")
		(hatch none 0.5)
		(connect_pads
			(clearance 0)
		)
		(min_thickness 0.25)
		(keepout
			(tracks allowed)
			(vias allowed)
			(pads allowed)
			(copperpour allowed)
			(footprints allowed)
		)
		(placement
			(enabled no)
			(sheetname "")
		)
		(fill
			(thermal_gap 0.5)
			(thermal_bridge_width 0.5)
			(island_removal_mode 0)
		)
		(polygon
			(pts
				(xy 48.029114 -347.631512) (xy 48.029114 -348.477332) (xy 47.721774 -348.477332) (xy 47.721774 -347.631512)
			)
		)
	)
	(zone
		(layer "In12.Cu")
		(hatch none 0.5)
		(connect_pads
			(clearance 0)
		)
		(min_thickness 0.25)
		(keepout
			(tracks not_allowed)
			(vias allowed)
			(pads allowed)
			(copperpour not_allowed)
			(footprints allowed)
		)
		(placement
			(enabled no)
			(sheetname "")
		)
		(fill
			(thermal_gap 0.5)
			(thermal_bridge_width 0.5)
			(island_removal_mode 0)
		)
		(polygon
			(pts
				(arc
					(start 343.141554 -438.76087)
					(mid 343.163872 -438.814752)
					(end 343.217754 -438.83707)
				)
				(arc
					(start 344.157554 -438.83707)
					(mid 344.211436 -438.814752)
					(end 344.233754 -438.76087)
				)
				(arc
					(start 344.233754 -436.219346)
					(mid 344.211436 -436.165464)
					(end 344.157554 -436.143146)
				)
				(arc
					(start 343.217754 -436.143146)
					(mid 343.163872 -436.165464)
					(end 343.141554 -436.219346)
				)
			)
		)
	)
	(zone
		(layer "In12.Cu")
		(hatch none 0.5)
		(connect_pads
			(clearance 0)
		)
		(min_thickness 0.25)
		(keepout
			(tracks not_allowed)
			(vias allowed)
			(pads allowed)
			(copperpour not_allowed)
			(footprints allowed)
		)
		(placement
			(enabled no)
			(sheetname "")
		)
		(fill
			(thermal_gap 0.5)
			(thermal_bridge_width 0.5)
			(island_removal_mode 0)
		)
		(polygon
			(pts
				(arc
					(start 75.141836 -435.16042)
					(mid 75.164154 -435.214302)
					(end 75.218036 -435.23662)
				)
				(arc
					(start 76.157836 -435.23662)
					(mid 76.211718 -435.214302)
					(end 76.234036 -435.16042)
				)
				(arc
					(start 76.234036 -432.618896)
					(mid 76.211718 -432.565014)
					(end 76.157836 -432.542696)
				)
				(arc
					(start 75.218036 -432.542696)
					(mid 75.164154 -432.565014)
					(end 75.141836 -432.618896)
				)
				(arc
					(start 75.141836 -433.346352)
					(mid 75.143835 -433.363693)
					(end 75.14971 -433.380134)
				)
				(arc
					(start 75.383136 -433.856384)
					(mid 75.390919 -433.889912)
					(end 75.383136 -433.92344)
				)
				(arc
					(start 75.14971 -434.39969)
					(mid 75.143815 -434.416126)
					(end 75.141836 -434.433472)
				)
			)
		)
	)
	(zone
		(layer "In12.Cu")
		(hatch none 0.5)
		(connect_pads
			(clearance 0)
		)
		(min_thickness 0.25)
		(keepout
			(tracks not_allowed)
			(vias allowed)
			(pads allowed)
			(copperpour not_allowed)
			(footprints allowed)
		)
		(placement
			(enabled no)
			(sheetname "")
		)
		(fill
			(thermal_gap 0.5)
			(thermal_bridge_width 0.5)
			(island_removal_mode 0)
		)
		(polygon
			(pts
				(arc
					(start 142.241778 -435.16042)
					(mid 142.264096 -435.214302)
					(end 142.317978 -435.23662)
				)
				(arc
					(start 143.257778 -435.23662)
					(mid 143.31166 -435.214302)
					(end 143.333978 -435.16042)
				)
				(arc
					(start 143.333978 -432.618896)
					(mid 143.31166 -432.565014)
					(end 143.257778 -432.542696)
				)
				(arc
					(start 142.317978 -432.542696)
					(mid 142.264096 -432.565014)
					(end 142.241778 -432.618896)
				)
				(arc
					(start 142.241778 -433.346352)
					(mid 142.243777 -433.363693)
					(end 142.249652 -433.380134)
				)
				(arc
					(start 142.483078 -433.856384)
					(mid 142.490861 -433.889912)
					(end 142.483078 -433.92344)
				)
				(arc
					(start 142.249652 -434.39969)
					(mid 142.243757 -434.416126)
					(end 142.241778 -434.433472)
				)
			)
		)
	)
	(zone
		(layer "In12.Cu")
		(hatch none 0.5)
		(connect_pads
			(clearance 0)
		)
		(min_thickness 0.25)
		(keepout
			(tracks allowed)
			(vias allowed)
			(pads allowed)
			(copperpour allowed)
			(footprints allowed)
		)
		(placement
			(enabled no)
			(sheetname "")
		)
		(fill
			(thermal_gap 0.5)
			(thermal_bridge_width 0.5)
			(island_removal_mode 0)
		)
		(polygon
			(pts
				(xy 49.735994 -350.433132) (xy 49.735994 -351.278952) (xy 49.428654 -351.278952) (xy 49.428654 -350.433132)
			)
		)
	)
	(zone
		(layer "In12.Cu")
		(hatch none 0.5)
		(connect_pads
			(clearance 0)
		)
		(min_thickness 0.25)
		(keepout
			(tracks not_allowed)
			(vias allowed)
			(pads allowed)
			(copperpour not_allowed)
			(footprints allowed)
		)
		(placement
			(enabled no)
			(sheetname "")
		)
		(fill
			(thermal_gap 0.5)
			(thermal_bridge_width 0.5)
			(island_removal_mode 0)
		)
		(polygon
			(pts
				(arc
					(start 385.2418 -435.16042)
					(mid 385.264118 -435.214302)
					(end 385.318 -435.23662)
				)
				(arc
					(start 386.2578 -435.23662)
					(mid 386.311682 -435.214302)
					(end 386.334 -435.16042)
				)
				(arc
					(start 386.334 -432.618896)
					(mid 386.311682 -432.565014)
					(end 386.2578 -432.542696)
				)
				(arc
					(start 385.318 -432.542696)
					(mid 385.264118 -432.565014)
					(end 385.2418 -432.618896)
				)
				(arc
					(start 385.2418 -433.346352)
					(mid 385.243799 -433.363693)
					(end 385.249674 -433.380134)
				)
				(arc
					(start 385.4831 -433.856384)
					(mid 385.490883 -433.889912)
					(end 385.4831 -433.92344)
				)
				(arc
					(start 385.249674 -434.39969)
					(mid 385.243779 -434.416126)
					(end 385.2418 -434.433472)
				)
			)
		)
	)
	(zone
		(layer "In12.Cu")
		(hatch none 0.5)
		(connect_pads
			(clearance 0)
		)
		(min_thickness 0.25)
		(keepout
			(tracks allowed)
			(vias allowed)
			(pads allowed)
			(copperpour allowed)
			(footprints allowed)
		)
		(placement
			(enabled no)
			(sheetname "")
		)
		(fill
			(thermal_gap 0.5)
			(thermal_bridge_width 0.5)
			(island_removal_mode 0)
		)
		(polygon
			(pts
				(xy 83.307174 -338.695792) (xy 83.307174 -339.541612) (xy 82.999834 -339.541612) (xy 82.999834 -338.695792)
			)
		)
	)
	(zone
		(layer "In12.Cu")
		(hatch none 0.5)
		(connect_pads
			(clearance 0)
		)
		(min_thickness 0.25)
		(keepout
			(tracks not_allowed)
			(vias allowed)
			(pads allowed)
			(copperpour not_allowed)
			(footprints allowed)
		)
		(placement
			(enabled no)
			(sheetname "")
		)
		(fill
			(thermal_gap 0.5)
			(thermal_bridge_width 0.5)
			(island_removal_mode 0)
		)
		(polygon
			(pts
				(arc
					(start 152.241758 -439.760868)
					(mid 152.264076 -439.81475)
					(end 152.317958 -439.837068)
				)
				(arc
					(start 153.257758 -439.837068)
					(mid 153.31164 -439.81475)
					(end 153.333958 -439.760868)
				)
				(arc
					(start 153.333958 -437.219344)
					(mid 153.31164 -437.165462)
					(end 153.257758 -437.143144)
				)
				(arc
					(start 152.317958 -437.143144)
					(mid 152.264076 -437.165462)
					(end 152.241758 -437.219344)
				)
			)
		)
	)
	(zone
		(layer "In12.Cu")
		(hatch none 0.5)
		(connect_pads
			(clearance 0)
		)
		(min_thickness 0.25)
		(keepout
			(tracks not_allowed)
			(vias allowed)
			(pads allowed)
			(copperpour not_allowed)
			(footprints allowed)
		)
		(placement
			(enabled no)
			(sheetname "")
		)
		(fill
			(thermal_gap 0.5)
			(thermal_bridge_width 0.5)
			(island_removal_mode 0)
		)
		(polygon
			(pts
				(arc
					(start 129.241804 -435.16042)
					(mid 129.264122 -435.214302)
					(end 129.318004 -435.23662)
				)
				(arc
					(start 130.257804 -435.23662)
					(mid 130.311686 -435.214302)
					(end 130.334004 -435.16042)
				)
				(arc
					(start 130.334004 -432.618896)
					(mid 130.311686 -432.565014)
					(end 130.257804 -432.542696)
				)
				(arc
					(start 129.318004 -432.542696)
					(mid 129.264122 -432.565014)
					(end 129.241804 -432.618896)
				)
				(arc
					(start 129.241804 -433.346352)
					(mid 129.243803 -433.363693)
					(end 129.249678 -433.380134)
				)
				(arc
					(start 129.483104 -433.856384)
					(mid 129.490887 -433.889912)
					(end 129.483104 -433.92344)
				)
				(arc
					(start 129.249678 -434.39969)
					(mid 129.243783 -434.416126)
					(end 129.241804 -434.433472)
				)
			)
		)
	)
	(zone
		(layer "In12.Cu")
		(hatch none 0.5)
		(connect_pads
			(clearance 0)
		)
		(min_thickness 0.25)
		(keepout
			(tracks not_allowed)
			(vias allowed)
			(pads allowed)
			(copperpour not_allowed)
			(footprints allowed)
		)
		(placement
			(enabled no)
			(sheetname "")
		)
		(fill
			(thermal_gap 0.5)
			(thermal_bridge_width 0.5)
			(island_removal_mode 0)
		)
		(polygon
			(pts
				(arc
					(start 156.24175 -436.160418)
					(mid 156.264068 -436.2143)
					(end 156.31795 -436.236618)
				)
				(arc
					(start 157.25775 -436.236618)
					(mid 157.311632 -436.2143)
					(end 157.33395 -436.160418)
				)
				(arc
					(start 157.33395 -433.618894)
					(mid 157.311632 -433.565012)
					(end 157.25775 -433.542694)
				)
				(arc
					(start 156.31795 -433.542694)
					(mid 156.264068 -433.565012)
					(end 156.24175 -433.618894)
				)
				(arc
					(start 156.24175 -434.34635)
					(mid 156.243749 -434.363691)
					(end 156.249624 -434.380132)
				)
				(arc
					(start 156.48305 -434.856382)
					(mid 156.490833 -434.88991)
					(end 156.48305 -434.923438)
				)
				(arc
					(start 156.249624 -435.399688)
					(mid 156.243729 -435.416124)
					(end 156.24175 -435.43347)
				)
			)
		)
	)
	(zone
		(layer "In12.Cu")
		(hatch none 0.5)
		(connect_pads
			(clearance 0)
		)
		(min_thickness 0.25)
		(keepout
			(tracks not_allowed)
			(vias allowed)
			(pads allowed)
			(copperpour not_allowed)
			(footprints allowed)
		)
		(placement
			(enabled no)
			(sheetname "")
		)
		(fill
			(thermal_gap 0.5)
			(thermal_bridge_width 0.5)
			(island_removal_mode 0)
		)
		(polygon
			(pts
				(xy 220.00845 -402.746972) (xy 220.00845 -401.10664) (xy 221.724474 -401.10664) (xy 221.724474 -402.746972)
			)
		)
	)
	(zone
		(layer "In12.Cu")
		(hatch none 0.5)
		(connect_pads
			(clearance 0)
		)
		(min_thickness 0.25)
		(keepout
			(tracks not_allowed)
			(vias allowed)
			(pads allowed)
			(copperpour not_allowed)
			(footprints allowed)
		)
		(placement
			(enabled no)
			(sheetname "")
		)
		(fill
			(thermal_gap 0.5)
			(thermal_bridge_width 0.5)
			(island_removal_mode 0)
		)
		(polygon
			(pts
				(arc
					(start 410.24175 -435.16042)
					(mid 410.264068 -435.214302)
					(end 410.31795 -435.23662)
				)
				(arc
					(start 411.25775 -435.23662)
					(mid 411.311632 -435.214302)
					(end 411.33395 -435.16042)
				)
				(arc
					(start 411.33395 -432.618896)
					(mid 411.311632 -432.565014)
					(end 411.25775 -432.542696)
				)
				(arc
					(start 410.31795 -432.542696)
					(mid 410.264068 -432.565014)
					(end 410.24175 -432.618896)
				)
				(arc
					(start 410.24175 -433.346352)
					(mid 410.243749 -433.363693)
					(end 410.249624 -433.380134)
				)
				(arc
					(start 410.48305 -433.856384)
					(mid 410.490833 -433.889912)
					(end 410.48305 -433.92344)
				)
				(arc
					(start 410.249624 -434.39969)
					(mid 410.243729 -434.416126)
					(end 410.24175 -434.433472)
				)
			)
		)
	)
	(zone
		(layer "In12.Cu")
		(hatch none 0.5)
		(connect_pads
			(clearance 0)
		)
		(min_thickness 0.25)
		(keepout
			(tracks not_allowed)
			(vias allowed)
			(pads allowed)
			(copperpour not_allowed)
			(footprints allowed)
		)
		(placement
			(enabled no)
			(sheetname "")
		)
		(fill
			(thermal_gap 0.5)
			(thermal_bridge_width 0.5)
			(island_removal_mode 0)
		)
		(polygon
			(pts
				(arc
					(start 408.241754 -436.160418)
					(mid 408.264072 -436.2143)
					(end 408.317954 -436.236618)
				)
				(arc
					(start 409.257754 -436.236618)
					(mid 409.311636 -436.2143)
					(end 409.333954 -436.160418)
				)
				(arc
					(start 409.333954 -433.618894)
					(mid 409.311636 -433.565012)
					(end 409.257754 -433.542694)
				)
				(arc
					(start 408.317954 -433.542694)
					(mid 408.264072 -433.565012)
					(end 408.241754 -433.618894)
				)
				(arc
					(start 408.241754 -434.34635)
					(mid 408.243753 -434.363691)
					(end 408.249628 -434.380132)
				)
				(arc
					(start 408.483054 -434.856382)
					(mid 408.490837 -434.88991)
					(end 408.483054 -434.923438)
				)
				(arc
					(start 408.249628 -435.399688)
					(mid 408.243733 -435.416124)
					(end 408.241754 -435.43347)
				)
			)
		)
	)
	(zone
		(layer "In12.Cu")
		(hatch none 0.5)
		(connect_pads
			(clearance 0)
		)
		(min_thickness 0.25)
		(keepout
			(tracks not_allowed)
			(vias allowed)
			(pads allowed)
			(copperpour not_allowed)
			(footprints allowed)
		)
		(placement
			(enabled no)
			(sheetname "")
		)
		(fill
			(thermal_gap 0.5)
			(thermal_bridge_width 0.5)
			(island_removal_mode 0)
		)
		(polygon
			(pts
				(arc
					(start 135.241792 -436.160418)
					(mid 135.26411 -436.2143)
					(end 135.317992 -436.236618)
				)
				(arc
					(start 136.257792 -436.236618)
					(mid 136.311674 -436.2143)
					(end 136.333992 -436.160418)
				)
				(arc
					(start 136.333992 -433.618894)
					(mid 136.311674 -433.565012)
					(end 136.257792 -433.542694)
				)
				(arc
					(start 135.317992 -433.542694)
					(mid 135.26411 -433.565012)
					(end 135.241792 -433.618894)
				)
				(arc
					(start 135.241792 -434.34635)
					(mid 135.243791 -434.363691)
					(end 135.249666 -434.380132)
				)
				(arc
					(start 135.483092 -434.856382)
					(mid 135.490875 -434.88991)
					(end 135.483092 -434.923438)
				)
				(arc
					(start 135.249666 -435.399688)
					(mid 135.243771 -435.416124)
					(end 135.241792 -435.43347)
				)
			)
		)
	)
	(zone
		(layer "In12.Cu")
		(hatch none 0.5)
		(connect_pads
			(clearance 0)
		)
		(min_thickness 0.25)
		(keepout
			(tracks not_allowed)
			(vias allowed)
			(pads allowed)
			(copperpour not_allowed)
			(footprints allowed)
		)
		(placement
			(enabled no)
			(sheetname "")
		)
		(fill
			(thermal_gap 0.5)
			(thermal_bridge_width 0.5)
			(island_removal_mode 0)
		)
		(polygon
			(pts
				(arc
					(start 125.241812 -435.16042)
					(mid 125.26413 -435.214302)
					(end 125.318012 -435.23662)
				)
				(arc
					(start 126.257812 -435.23662)
					(mid 126.311694 -435.214302)
					(end 126.334012 -435.16042)
				)
				(arc
					(start 126.334012 -432.618896)
					(mid 126.311694 -432.565014)
					(end 126.257812 -432.542696)
				)
				(arc
					(start 125.318012 -432.542696)
					(mid 125.26413 -432.565014)
					(end 125.241812 -432.618896)
				)
				(arc
					(start 125.241812 -433.346352)
					(mid 125.243811 -433.363693)
					(end 125.249686 -433.380134)
				)
				(arc
					(start 125.483112 -433.856384)
					(mid 125.490895 -433.889912)
					(end 125.483112 -433.92344)
				)
				(arc
					(start 125.249686 -434.39969)
					(mid 125.243791 -434.416126)
					(end 125.241812 -434.433472)
				)
			)
		)
	)
	(zone
		(layer "In12.Cu")
		(hatch none 0.5)
		(connect_pads
			(clearance 0)
		)
		(min_thickness 0.25)
		(keepout
			(tracks not_allowed)
			(vias allowed)
			(pads allowed)
			(copperpour not_allowed)
			(footprints allowed)
		)
		(placement
			(enabled no)
			(sheetname "")
		)
		(fill
			(thermal_gap 0.5)
			(thermal_bridge_width 0.5)
			(island_removal_mode 0)
		)
		(polygon
			(pts
				(arc
					(start 381.241554 -438.76087)
					(mid 381.263872 -438.814752)
					(end 381.317754 -438.83707)
				)
				(arc
					(start 382.257554 -438.83707)
					(mid 382.311436 -438.814752)
					(end 382.333754 -438.76087)
				)
				(arc
					(start 382.333754 -436.219346)
					(mid 382.311436 -436.165464)
					(end 382.257554 -436.143146)
				)
				(arc
					(start 381.317754 -436.143146)
					(mid 381.263872 -436.165464)
					(end 381.241554 -436.219346)
				)
			)
		)
	)
	(zone
		(layer "In12.Cu")
		(hatch none 0.5)
		(connect_pads
			(clearance 0)
		)
		(min_thickness 0.25)
		(keepout
			(tracks not_allowed)
			(vias allowed)
			(pads allowed)
			(copperpour not_allowed)
			(footprints allowed)
		)
		(placement
			(enabled no)
			(sheetname "")
		)
		(fill
			(thermal_gap 0.5)
			(thermal_bridge_width 0.5)
			(island_removal_mode 0)
		)
		(polygon
			(pts
				(arc
					(start 152.241758 -436.160418)
					(mid 152.264076 -436.2143)
					(end 152.317958 -436.236618)
				)
				(arc
					(start 153.257758 -436.236618)
					(mid 153.31164 -436.2143)
					(end 153.333958 -436.160418)
				)
				(arc
					(start 153.333958 -433.618894)
					(mid 153.31164 -433.565012)
					(end 153.257758 -433.542694)
				)
				(arc
					(start 152.317958 -433.542694)
					(mid 152.264076 -433.565012)
					(end 152.241758 -433.618894)
				)
				(arc
					(start 152.241758 -434.34635)
					(mid 152.243757 -434.363691)
					(end 152.249632 -434.380132)
				)
				(arc
					(start 152.483058 -434.856382)
					(mid 152.490841 -434.88991)
					(end 152.483058 -434.923438)
				)
				(arc
					(start 152.249632 -435.399688)
					(mid 152.243737 -435.416124)
					(end 152.241758 -435.43347)
				)
			)
		)
	)
	(zone
		(layer "In12.Cu")
		(hatch none 0.5)
		(connect_pads
			(clearance 0)
		)
		(min_thickness 0.25)
		(keepout
			(tracks not_allowed)
			(vias allowed)
			(pads allowed)
			(copperpour not_allowed)
			(footprints allowed)
		)
		(placement
			(enabled no)
			(sheetname "")
		)
		(fill
			(thermal_gap 0.5)
			(thermal_bridge_width 0.5)
			(island_removal_mode 0)
		)
		(polygon
			(pts
				(arc
					(start 381.241808 -435.16042)
					(mid 381.264126 -435.214302)
					(end 381.318008 -435.23662)
				)
				(arc
					(start 382.257808 -435.23662)
					(mid 382.31169 -435.214302)
					(end 382.334008 -435.16042)
				)
				(arc
					(start 382.334008 -432.618896)
					(mid 382.31169 -432.565014)
					(end 382.257808 -432.542696)
				)
				(arc
					(start 381.318008 -432.542696)
					(mid 381.264126 -432.565014)
					(end 381.241808 -432.618896)
				)
				(arc
					(start 381.241808 -433.346352)
					(mid 381.243807 -433.363693)
					(end 381.249682 -433.380134)
				)
				(arc
					(start 381.483108 -433.856384)
					(mid 381.490891 -433.889912)
					(end 381.483108 -433.92344)
				)
				(arc
					(start 381.249682 -434.39969)
					(mid 381.243787 -434.416126)
					(end 381.241808 -434.433472)
				)
			)
		)
	)
	(zone
		(layer "In12.Cu")
		(hatch none 0.5)
		(connect_pads
			(clearance 0)
		)
		(min_thickness 0.25)
		(keepout
			(tracks not_allowed)
			(vias allowed)
			(pads allowed)
			(copperpour not_allowed)
			(footprints allowed)
		)
		(placement
			(enabled no)
			(sheetname "")
		)
		(fill
			(thermal_gap 0.5)
			(thermal_bridge_width 0.5)
			(island_removal_mode 0)
		)
		(polygon
			(pts
				(arc
					(start 125.241558 -438.76087)
					(mid 125.263876 -438.814752)
					(end 125.317758 -438.83707)
				)
				(arc
					(start 126.257558 -438.83707)
					(mid 126.31144 -438.814752)
					(end 126.333758 -438.76087)
				)
				(arc
					(start 126.333758 -436.219346)
					(mid 126.31144 -436.165464)
					(end 126.257558 -436.143146)
				)
				(arc
					(start 125.317758 -436.143146)
					(mid 125.263876 -436.165464)
					(end 125.241558 -436.219346)
				)
			)
		)
	)
	(zone
		(layer "In12.Cu")
		(hatch none 0.5)
		(connect_pads
			(clearance 0)
		)
		(min_thickness 0.25)
		(keepout
			(tracks not_allowed)
			(vias allowed)
			(pads allowed)
			(copperpour not_allowed)
			(footprints allowed)
		)
		(placement
			(enabled no)
			(sheetname "")
		)
		(fill
			(thermal_gap 0.5)
			(thermal_bridge_width 0.5)
			(island_removal_mode 0)
		)
		(polygon
			(pts
				(arc
					(start 139.24153 -439.760868)
					(mid 139.263848 -439.81475)
					(end 139.31773 -439.837068)
				)
				(arc
					(start 140.25753 -439.837068)
					(mid 140.311412 -439.81475)
					(end 140.33373 -439.760868)
				)
				(arc
					(start 140.33373 -437.219344)
					(mid 140.311412 -437.165462)
					(end 140.25753 -437.143144)
				)
				(arc
					(start 139.31773 -437.143144)
					(mid 139.263848 -437.165462)
					(end 139.24153 -437.219344)
				)
			)
		)
	)
	(zone
		(layer "In12.Cu")
		(hatch none 0.5)
		(connect_pads
			(clearance 0)
		)
		(min_thickness 0.25)
		(keepout
			(tracks not_allowed)
			(vias allowed)
			(pads allowed)
			(copperpour not_allowed)
			(footprints allowed)
		)
		(placement
			(enabled no)
			(sheetname "")
		)
		(fill
			(thermal_gap 0.5)
			(thermal_bridge_width 0.5)
			(island_removal_mode 0)
		)
		(polygon
			(pts
				(arc
					(start 406.241758 -435.16042)
					(mid 406.264076 -435.214302)
					(end 406.317958 -435.23662)
				)
				(arc
					(start 407.257758 -435.23662)
					(mid 407.31164 -435.214302)
					(end 407.333958 -435.16042)
				)
				(arc
					(start 407.333958 -432.618896)
					(mid 407.31164 -432.565014)
					(end 407.257758 -432.542696)
				)
				(arc
					(start 406.317958 -432.542696)
					(mid 406.264076 -432.565014)
					(end 406.241758 -432.618896)
				)
				(arc
					(start 406.241758 -433.346352)
					(mid 406.243757 -433.363693)
					(end 406.249632 -433.380134)
				)
				(arc
					(start 406.483058 -433.856384)
					(mid 406.490841 -433.889912)
					(end 406.483058 -433.92344)
				)
				(arc
					(start 406.249632 -434.39969)
					(mid 406.243737 -434.416126)
					(end 406.241758 -434.433472)
				)
			)
		)
	)
	(zone
		(layer "In12.Cu")
		(hatch none 0.5)
		(connect_pads
			(clearance 0)
		)
		(min_thickness 0.25)
		(keepout
			(tracks not_allowed)
			(vias allowed)
			(pads allowed)
			(copperpour not_allowed)
			(footprints allowed)
		)
		(placement
			(enabled no)
			(sheetname "")
		)
		(fill
			(thermal_gap 0.5)
			(thermal_bridge_width 0.5)
			(island_removal_mode 0)
		)
		(polygon
			(pts
				(arc
					(start 150.241762 -438.76087)
					(mid 150.26408 -438.814752)
					(end 150.317962 -438.83707)
				)
				(arc
					(start 151.257762 -438.83707)
					(mid 151.311644 -438.814752)
					(end 151.333962 -438.76087)
				)
				(arc
					(start 151.333962 -436.219346)
					(mid 151.311644 -436.165464)
					(end 151.257762 -436.143146)
				)
				(arc
					(start 150.317962 -436.143146)
					(mid 150.26408 -436.165464)
					(end 150.241762 -436.219346)
				)
			)
		)
	)
	(zone
		(layer "In12.Cu")
		(hatch none 0.5)
		(connect_pads
			(clearance 0)
		)
		(min_thickness 0.25)
		(keepout
			(tracks not_allowed)
			(vias allowed)
			(pads allowed)
			(copperpour not_allowed)
			(footprints allowed)
		)
		(placement
			(enabled no)
			(sheetname "")
		)
		(fill
			(thermal_gap 0.5)
			(thermal_bridge_width 0.5)
			(island_removal_mode 0)
		)
		(polygon
			(pts
				(arc
					(start 314.141358 -438.76087)
					(mid 314.163676 -438.814752)
					(end 314.217558 -438.83707)
				)
				(arc
					(start 315.157358 -438.83707)
					(mid 315.21124 -438.814752)
					(end 315.233558 -438.76087)
				)
				(arc
					(start 315.233558 -436.219346)
					(mid 315.21124 -436.165464)
					(end 315.157358 -436.143146)
				)
				(arc
					(start 314.217558 -436.143146)
					(mid 314.163676 -436.165464)
					(end 314.141358 -436.219346)
				)
			)
		)
	)
	(zone
		(layer "In12.Cu")
		(hatch none 0.5)
		(connect_pads
			(clearance 0)
		)
		(min_thickness 0.25)
		(keepout
			(tracks not_allowed)
			(vias allowed)
			(pads allowed)
			(copperpour not_allowed)
			(footprints allowed)
		)
		(placement
			(enabled no)
			(sheetname "")
		)
		(fill
			(thermal_gap 0.5)
			(thermal_bridge_width 0.5)
			(island_removal_mode 0)
		)
		(polygon
			(pts
				(arc
					(start 391.241788 -436.160418)
					(mid 391.264106 -436.2143)
					(end 391.317988 -436.236618)
				)
				(arc
					(start 392.257788 -436.236618)
					(mid 392.31167 -436.2143)
					(end 392.333988 -436.160418)
				)
				(arc
					(start 392.333988 -433.618894)
					(mid 392.31167 -433.565012)
					(end 392.257788 -433.542694)
				)
				(arc
					(start 391.317988 -433.542694)
					(mid 391.264106 -433.565012)
					(end 391.241788 -433.618894)
				)
				(arc
					(start 391.241788 -434.34635)
					(mid 391.243787 -434.363691)
					(end 391.249662 -434.380132)
				)
				(arc
					(start 391.483088 -434.856382)
					(mid 391.490871 -434.88991)
					(end 391.483088 -434.923438)
				)
				(arc
					(start 391.249662 -435.399688)
					(mid 391.243767 -435.416124)
					(end 391.241788 -435.43347)
				)
			)
		)
	)
	(zone
		(layer "In12.Cu")
		(hatch none 0.5)
		(connect_pads
			(clearance 0)
		)
		(min_thickness 0.25)
		(keepout
			(tracks not_allowed)
			(vias allowed)
			(pads allowed)
			(copperpour not_allowed)
			(footprints allowed)
		)
		(placement
			(enabled no)
			(sheetname "")
		)
		(fill
			(thermal_gap 0.5)
			(thermal_bridge_width 0.5)
			(island_removal_mode 0)
		)
		(polygon
			(pts
				(arc
					(start 156.24175 -439.760868)
					(mid 156.264068 -439.81475)
					(end 156.31795 -439.837068)
				)
				(arc
					(start 157.25775 -439.837068)
					(mid 157.311632 -439.81475)
					(end 157.33395 -439.760868)
				)
				(arc
					(start 157.33395 -437.219344)
					(mid 157.311632 -437.165462)
					(end 157.25775 -437.143144)
				)
				(arc
					(start 156.31795 -437.143144)
					(mid 156.264068 -437.165462)
					(end 156.24175 -437.219344)
				)
			)
		)
	)
	(zone
		(layer "In12.Cu")
		(hatch none 0.5)
		(connect_pads
			(clearance 0)
		)
		(min_thickness 0.25)
		(keepout
			(tracks not_allowed)
			(vias allowed)
			(pads allowed)
			(copperpour not_allowed)
			(footprints allowed)
		)
		(placement
			(enabled no)
			(sheetname "")
		)
		(fill
			(thermal_gap 0.5)
			(thermal_bridge_width 0.5)
			(island_removal_mode 0)
		)
		(polygon
			(pts
				(arc
					(start 129.24155 -438.76087)
					(mid 129.263868 -438.814752)
					(end 129.31775 -438.83707)
				)
				(arc
					(start 130.25755 -438.83707)
					(mid 130.311432 -438.814752)
					(end 130.33375 -438.76087)
				)
				(arc
					(start 130.33375 -436.219346)
					(mid 130.311432 -436.165464)
					(end 130.25755 -436.143146)
				)
				(arc
					(start 129.31775 -436.143146)
					(mid 129.263868 -436.165464)
					(end 129.24155 -436.219346)
				)
			)
		)
	)
	(zone
		(layer "In12.Cu")
		(hatch none 0.5)
		(connect_pads
			(clearance 0)
		)
		(min_thickness 0.25)
		(keepout
			(tracks not_allowed)
			(vias allowed)
			(pads allowed)
			(copperpour not_allowed)
			(footprints allowed)
		)
		(placement
			(enabled no)
			(sheetname "")
		)
		(fill
			(thermal_gap 0.5)
			(thermal_bridge_width 0.5)
			(island_removal_mode 0)
		)
		(polygon
			(pts
				(arc
					(start 83.14182 -435.16042)
					(mid 83.164138 -435.214302)
					(end 83.21802 -435.23662)
				)
				(arc
					(start 84.15782 -435.23662)
					(mid 84.211702 -435.214302)
					(end 84.23402 -435.16042)
				)
				(arc
					(start 84.23402 -432.618896)
					(mid 84.211702 -432.565014)
					(end 84.15782 -432.542696)
				)
				(arc
					(start 83.21802 -432.542696)
					(mid 83.164138 -432.565014)
					(end 83.14182 -432.618896)
				)
				(arc
					(start 83.14182 -433.346352)
					(mid 83.143819 -433.363693)
					(end 83.149694 -433.380134)
				)
				(arc
					(start 83.38312 -433.856384)
					(mid 83.390903 -433.889912)
					(end 83.38312 -433.92344)
				)
				(arc
					(start 83.149694 -434.39969)
					(mid 83.143799 -434.416126)
					(end 83.14182 -434.433472)
				)
			)
		)
	)
	(zone
		(layer "In12.Cu")
		(hatch none 0.5)
		(connect_pads
			(clearance 0)
		)
		(min_thickness 0.25)
		(keepout
			(tracks allowed)
			(vias allowed)
			(pads allowed)
			(copperpour allowed)
			(footprints allowed)
		)
		(placement
			(enabled no)
			(sheetname "")
		)
		(fill
			(thermal_gap 0.5)
			(thermal_bridge_width 0.5)
			(island_removal_mode 0)
		)
		(polygon
			(pts
				(xy 39.690294 -347.634052) (xy 39.690294 -348.479872) (xy 39.382954 -348.479872) (xy 39.382954 -347.634052)
			)
		)
	)
	(zone
		(layer "In12.Cu")
		(hatch none 0.5)
		(connect_pads
			(clearance 0)
		)
		(min_thickness 0.25)
		(keepout
			(tracks not_allowed)
			(vias allowed)
			(pads allowed)
			(copperpour not_allowed)
			(footprints allowed)
		)
		(placement
			(enabled no)
			(sheetname "")
		)
		(fill
			(thermal_gap 0.5)
			(thermal_bridge_width 0.5)
			(island_removal_mode 0)
		)
		(polygon
			(pts
				(arc
					(start 66.141854 -435.16042)
					(mid 66.164172 -435.214302)
					(end 66.218054 -435.23662)
				)
				(arc
					(start 67.157854 -435.23662)
					(mid 67.211736 -435.214302)
					(end 67.234054 -435.16042)
				)
				(arc
					(start 67.234054 -432.618896)
					(mid 67.211736 -432.565014)
					(end 67.157854 -432.542696)
				)
				(arc
					(start 66.218054 -432.542696)
					(mid 66.164172 -432.565014)
					(end 66.141854 -432.618896)
				)
				(arc
					(start 66.141854 -433.346352)
					(mid 66.143853 -433.363693)
					(end 66.149728 -433.380134)
				)
				(arc
					(start 66.383154 -433.856384)
					(mid 66.390937 -433.889912)
					(end 66.383154 -433.92344)
				)
				(arc
					(start 66.149728 -434.39969)
					(mid 66.143833 -434.416126)
					(end 66.141854 -434.433472)
				)
			)
		)
	)
	(zone
		(layer "In12.Cu")
		(hatch none 0.5)
		(connect_pads
			(clearance 0)
		)
		(min_thickness 0.25)
		(keepout
			(tracks not_allowed)
			(vias allowed)
			(pads allowed)
			(copperpour not_allowed)
			(footprints allowed)
		)
		(placement
			(enabled no)
			(sheetname "")
		)
		(fill
			(thermal_gap 0.5)
			(thermal_bridge_width 0.5)
			(island_removal_mode 0)
		)
		(polygon
			(pts
				(arc
					(start 142.241778 -438.76087)
					(mid 142.264096 -438.814752)
					(end 142.317978 -438.83707)
				)
				(arc
					(start 143.257778 -438.83707)
					(mid 143.31166 -438.814752)
					(end 143.333978 -438.76087)
				)
				(arc
					(start 143.333978 -436.219346)
					(mid 143.31166 -436.165464)
					(end 143.257778 -436.143146)
				)
				(arc
					(start 142.317978 -436.143146)
					(mid 142.264096 -436.165464)
					(end 142.241778 -436.219346)
				)
			)
		)
	)
	(zone
		(layer "In12.Cu")
		(hatch none 0.5)
		(connect_pads
			(clearance 0)
		)
		(min_thickness 0.25)
		(keepout
			(tracks not_allowed)
			(vias allowed)
			(pads allowed)
			(copperpour not_allowed)
			(footprints allowed)
		)
		(placement
			(enabled no)
			(sheetname "")
		)
		(fill
			(thermal_gap 0.5)
			(thermal_bridge_width 0.5)
			(island_removal_mode 0)
		)
		(polygon
			(pts
				(arc
					(start 77.141832 -436.160418)
					(mid 77.16415 -436.2143)
					(end 77.218032 -436.236618)
				)
				(arc
					(start 78.157832 -436.236618)
					(mid 78.211714 -436.2143)
					(end 78.234032 -436.160418)
				)
				(arc
					(start 78.234032 -433.618894)
					(mid 78.211714 -433.565012)
					(end 78.157832 -433.542694)
				)
				(arc
					(start 77.218032 -433.542694)
					(mid 77.16415 -433.565012)
					(end 77.141832 -433.618894)
				)
				(arc
					(start 77.141832 -434.34635)
					(mid 77.143831 -434.363691)
					(end 77.149706 -434.380132)
				)
				(arc
					(start 77.383132 -434.856382)
					(mid 77.390915 -434.88991)
					(end 77.383132 -434.923438)
				)
				(arc
					(start 77.149706 -435.399688)
					(mid 77.143811 -435.416124)
					(end 77.141832 -435.43347)
				)
			)
		)
	)
	(zone
		(layer "In12.Cu")
		(hatch none 0.5)
		(connect_pads
			(clearance 0)
		)
		(min_thickness 0.25)
		(keepout
			(tracks allowed)
			(vias allowed)
			(pads allowed)
			(copperpour allowed)
			(footprints allowed)
		)
		(placement
			(enabled no)
			(sheetname "")
		)
		(fill
			(thermal_gap 0.5)
			(thermal_bridge_width 0.5)
			(island_removal_mode 0)
		)
		(polygon
			(pts
				(xy 58.062114 -350.402652) (xy 58.062114 -351.248472) (xy 57.754774 -351.248472) (xy 57.754774 -350.402652)
			)
		)
	)
	(zone
		(layer "In12.Cu")
		(hatch none 0.5)
		(connect_pads
			(clearance 0)
		)
		(min_thickness 0.25)
		(keepout
			(tracks allowed)
			(vias allowed)
			(pads allowed)
			(copperpour allowed)
			(footprints allowed)
		)
		(placement
			(enabled no)
			(sheetname "")
		)
		(fill
			(thermal_gap 0.5)
			(thermal_bridge_width 0.5)
			(island_removal_mode 0)
		)
		(polygon
			(pts
				(xy 24.793194 -350.445832) (xy 24.793194 -351.291652) (xy 24.485854 -351.291652) (xy 24.485854 -350.445832)
			)
		)
	)
	(zone
		(layer "In12.Cu")
		(hatch none 0.5)
		(connect_pads
			(clearance 0)
		)
		(min_thickness 0.25)
		(keepout
			(tracks allowed)
			(vias allowed)
			(pads allowed)
			(copperpour allowed)
			(footprints allowed)
		)
		(placement
			(enabled no)
			(sheetname "")
		)
		(fill
			(thermal_gap 0.5)
			(thermal_bridge_width 0.5)
			(island_removal_mode 0)
		)
		(polygon
			(pts
				(xy 89.944194 -335.891632) (xy 89.944194 -336.737452) (xy 89.636854 -336.737452) (xy 89.636854 -335.891632)
			)
		)
	)
	(zone
		(layer "In12.Cu")
		(hatch none 0.5)
		(connect_pads
			(clearance 0)
		)
		(min_thickness 0.25)
		(keepout
			(tracks not_allowed)
			(vias allowed)
			(pads allowed)
			(copperpour not_allowed)
			(footprints allowed)
		)
		(placement
			(enabled no)
			(sheetname "")
		)
		(fill
			(thermal_gap 0.5)
			(thermal_bridge_width 0.5)
			(island_removal_mode 0)
		)
		(polygon
			(pts
				(arc
					(start 395.241526 -439.760868)
					(mid 395.263844 -439.81475)
					(end 395.317726 -439.837068)
				)
				(arc
					(start 396.257526 -439.837068)
					(mid 396.311408 -439.81475)
					(end 396.333726 -439.760868)
				)
				(arc
					(start 396.333726 -437.219344)
					(mid 396.311408 -437.165462)
					(end 396.257526 -437.143144)
				)
				(arc
					(start 395.317726 -437.143144)
					(mid 395.263844 -437.165462)
					(end 395.241526 -437.219344)
				)
			)
		)
	)
	(zone
		(layer "In12.Cu")
		(hatch none 0.5)
		(connect_pads
			(clearance 0)
		)
		(min_thickness 0.25)
		(keepout
			(tracks not_allowed)
			(vias allowed)
			(pads allowed)
			(copperpour not_allowed)
			(footprints allowed)
		)
		(placement
			(enabled no)
			(sheetname "")
		)
		(fill
			(thermal_gap 0.5)
			(thermal_bridge_width 0.5)
			(island_removal_mode 0)
		)
		(polygon
			(pts
				(arc
					(start 150.241762 -435.16042)
					(mid 150.26408 -435.214302)
					(end 150.317962 -435.23662)
				)
				(arc
					(start 151.257762 -435.23662)
					(mid 151.311644 -435.214302)
					(end 151.333962 -435.16042)
				)
				(arc
					(start 151.333962 -432.618896)
					(mid 151.311644 -432.565014)
					(end 151.257762 -432.542696)
				)
				(arc
					(start 150.317962 -432.542696)
					(mid 150.26408 -432.565014)
					(end 150.241762 -432.618896)
				)
				(arc
					(start 150.241762 -433.346352)
					(mid 150.243761 -433.363693)
					(end 150.249636 -433.380134)
				)
				(arc
					(start 150.483062 -433.856384)
					(mid 150.490845 -433.889912)
					(end 150.483062 -433.92344)
				)
				(arc
					(start 150.249636 -434.39969)
					(mid 150.243741 -434.416126)
					(end 150.241762 -434.433472)
				)
			)
		)
	)
	(zone
		(layer "In12.Cu")
		(hatch none 0.5)
		(connect_pads
			(clearance 0)
		)
		(min_thickness 0.25)
		(keepout
			(tracks not_allowed)
			(vias allowed)
			(pads allowed)
			(copperpour not_allowed)
			(footprints allowed)
		)
		(placement
			(enabled no)
			(sheetname "")
		)
		(fill
			(thermal_gap 0.5)
			(thermal_bridge_width 0.5)
			(island_removal_mode 0)
		)
		(polygon
			(pts
				(arc
					(start 383.241804 -436.160418)
					(mid 383.264122 -436.2143)
					(end 383.318004 -436.236618)
				)
				(arc
					(start 384.257804 -436.236618)
					(mid 384.311686 -436.2143)
					(end 384.334004 -436.160418)
				)
				(arc
					(start 384.334004 -433.618894)
					(mid 384.311686 -433.565012)
					(end 384.257804 -433.542694)
				)
				(arc
					(start 383.318004 -433.542694)
					(mid 383.264122 -433.565012)
					(end 383.241804 -433.618894)
				)
				(arc
					(start 383.241804 -434.34635)
					(mid 383.243803 -434.363691)
					(end 383.249678 -434.380132)
				)
				(arc
					(start 383.483104 -434.856382)
					(mid 383.490887 -434.88991)
					(end 383.483104 -434.923438)
				)
				(arc
					(start 383.249678 -435.399688)
					(mid 383.243783 -435.416124)
					(end 383.241804 -435.43347)
				)
			)
		)
	)
	(zone
		(layer "In12.Cu")
		(hatch none 0.5)
		(connect_pads
			(clearance 0)
		)
		(min_thickness 0.25)
		(keepout
			(tracks not_allowed)
			(vias allowed)
			(pads allowed)
			(copperpour not_allowed)
			(footprints allowed)
		)
		(placement
			(enabled no)
			(sheetname "")
		)
		(fill
			(thermal_gap 0.5)
			(thermal_bridge_width 0.5)
			(island_removal_mode 0)
		)
		(polygon
			(pts
				(arc
					(start 81.141824 -436.160418)
					(mid 81.164142 -436.2143)
					(end 81.218024 -436.236618)
				)
				(arc
					(start 82.157824 -436.236618)
					(mid 82.211706 -436.2143)
					(end 82.234024 -436.160418)
				)
				(arc
					(start 82.234024 -433.618894)
					(mid 82.211706 -433.565012)
					(end 82.157824 -433.542694)
				)
				(arc
					(start 81.218024 -433.542694)
					(mid 81.164142 -433.565012)
					(end 81.141824 -433.618894)
				)
				(arc
					(start 81.141824 -434.34635)
					(mid 81.143823 -434.363691)
					(end 81.149698 -434.380132)
				)
				(arc
					(start 81.383124 -434.856382)
					(mid 81.390907 -434.88991)
					(end 81.383124 -434.923438)
				)
				(arc
					(start 81.149698 -435.399688)
					(mid 81.143803 -435.416124)
					(end 81.141824 -435.43347)
				)
			)
		)
	)
	(zone
		(layer "In12.Cu")
		(hatch none 0.5)
		(connect_pads
			(clearance 0)
		)
		(min_thickness 0.25)
		(keepout
			(tracks allowed)
			(vias allowed)
			(pads allowed)
			(copperpour allowed)
			(footprints allowed)
		)
		(placement
			(enabled no)
			(sheetname "")
		)
		(fill
			(thermal_gap 0.5)
			(thermal_bridge_width 0.5)
			(island_removal_mode 0)
		)
		(polygon
			(pts
				(xy 74.973434 -338.708492) (xy 74.973434 -339.554312) (xy 74.666094 -339.554312) (xy 74.666094 -338.708492)
			)
		)
	)
	(zone
		(layer "In12.Cu")
		(hatch none 0.5)
		(connect_pads
			(clearance 0)
		)
		(min_thickness 0.25)
		(keepout
			(tracks not_allowed)
			(vias allowed)
			(pads allowed)
			(copperpour not_allowed)
			(footprints allowed)
		)
		(placement
			(enabled no)
			(sheetname "")
		)
		(fill
			(thermal_gap 0.5)
			(thermal_bridge_width 0.5)
			(island_removal_mode 0)
		)
		(polygon
			(pts
				(arc
					(start 85.141816 -436.160418)
					(mid 85.164134 -436.2143)
					(end 85.218016 -436.236618)
				)
				(arc
					(start 86.157816 -436.236618)
					(mid 86.211698 -436.2143)
					(end 86.234016 -436.160418)
				)
				(arc
					(start 86.234016 -433.618894)
					(mid 86.211698 -433.565012)
					(end 86.157816 -433.542694)
				)
				(arc
					(start 85.218016 -433.542694)
					(mid 85.164134 -433.565012)
					(end 85.141816 -433.618894)
				)
				(arc
					(start 85.141816 -434.34635)
					(mid 85.143815 -434.363691)
					(end 85.14969 -434.380132)
				)
				(arc
					(start 85.383116 -434.856382)
					(mid 85.390899 -434.88991)
					(end 85.383116 -434.923438)
				)
				(arc
					(start 85.14969 -435.399688)
					(mid 85.143795 -435.416124)
					(end 85.141816 -435.43347)
				)
			)
		)
	)
	(zone
		(layer "In12.Cu")
		(hatch none 0.5)
		(connect_pads
			(clearance 0)
		)
		(min_thickness 0.25)
		(keepout
			(tracks not_allowed)
			(vias allowed)
			(pads allowed)
			(copperpour not_allowed)
			(footprints allowed)
		)
		(placement
			(enabled no)
			(sheetname "")
		)
		(fill
			(thermal_gap 0.5)
			(thermal_bridge_width 0.5)
			(island_removal_mode 0)
		)
		(polygon
			(pts
				(arc
					(start 324.141338 -438.560972)
					(mid 324.163656 -438.614854)
					(end 324.217538 -438.637172)
				)
				(arc
					(start 325.157338 -438.637172)
					(mid 325.21122 -438.614854)
					(end 325.233538 -438.560972)
				)
				(arc
					(start 325.233538 -436.019448)
					(mid 325.21122 -435.965566)
					(end 325.157338 -435.943248)
				)
				(arc
					(start 324.217538 -435.943248)
					(mid 324.163656 -435.965566)
					(end 324.141338 -436.019448)
				)
			)
		)
	)
	(zone
		(layer "In12.Cu")
		(hatch none 0.5)
		(connect_pads
			(clearance 0)
		)
		(min_thickness 0.25)
		(keepout
			(tracks not_allowed)
			(vias allowed)
			(pads allowed)
			(copperpour not_allowed)
			(footprints allowed)
		)
		(placement
			(enabled no)
			(sheetname "")
		)
		(fill
			(thermal_gap 0.5)
			(thermal_bridge_width 0.5)
			(island_removal_mode 0)
		)
		(polygon
			(pts
				(arc
					(start 404.241762 -439.760868)
					(mid 404.26408 -439.81475)
					(end 404.317962 -439.837068)
				)
				(arc
					(start 405.257762 -439.837068)
					(mid 405.311644 -439.81475)
					(end 405.333962 -439.760868)
				)
				(arc
					(start 405.333962 -437.219344)
					(mid 405.311644 -437.165462)
					(end 405.257762 -437.143144)
				)
				(arc
					(start 404.317962 -437.143144)
					(mid 404.26408 -437.165462)
					(end 404.241762 -437.219344)
				)
			)
		)
	)
	(zone
		(layer "In12.Cu")
		(hatch none 0.5)
		(connect_pads
			(clearance 0)
		)
		(min_thickness 0.25)
		(keepout
			(tracks not_allowed)
			(vias allowed)
			(pads allowed)
			(copperpour not_allowed)
			(footprints allowed)
		)
		(placement
			(enabled no)
			(sheetname "")
		)
		(fill
			(thermal_gap 0.5)
			(thermal_bridge_width 0.5)
			(island_removal_mode 0)
		)
		(polygon
			(pts
				(arc
					(start 328.14133 -439.760868)
					(mid 328.163648 -439.81475)
					(end 328.21753 -439.837068)
				)
				(arc
					(start 329.15733 -439.837068)
					(mid 329.211212 -439.81475)
					(end 329.23353 -439.760868)
				)
				(arc
					(start 329.23353 -437.219344)
					(mid 329.211212 -437.165462)
					(end 329.15733 -437.143144)
				)
				(arc
					(start 328.21753 -437.143144)
					(mid 328.163648 -437.165462)
					(end 328.14133 -437.219344)
				)
			)
		)
	)
	(zone
		(layer "In12.Cu")
		(hatch none 0.5)
		(connect_pads
			(clearance 0)
		)
		(min_thickness 0.25)
		(keepout
			(tracks not_allowed)
			(vias allowed)
			(pads allowed)
			(copperpour not_allowed)
			(footprints allowed)
		)
		(placement
			(enabled no)
			(sheetname "")
		)
		(fill
			(thermal_gap 0.5)
			(thermal_bridge_width 0.5)
			(island_removal_mode 0)
		)
		(polygon
			(pts
				(arc
					(start 383.24155 -439.760868)
					(mid 383.263868 -439.81475)
					(end 383.31775 -439.837068)
				)
				(arc
					(start 384.25755 -439.837068)
					(mid 384.311432 -439.81475)
					(end 384.33375 -439.760868)
				)
				(arc
					(start 384.33375 -437.219344)
					(mid 384.311432 -437.165462)
					(end 384.25755 -437.143144)
				)
				(arc
					(start 383.31775 -437.143144)
					(mid 383.263868 -437.165462)
					(end 383.24155 -437.219344)
				)
			)
		)
	)
	(zone
		(layer "In12.Cu")
		(hatch none 0.5)
		(connect_pads
			(clearance 0)
		)
		(min_thickness 0.25)
		(keepout
			(tracks not_allowed)
			(vias allowed)
			(pads allowed)
			(copperpour not_allowed)
			(footprints allowed)
		)
		(placement
			(enabled no)
			(sheetname "")
		)
		(fill
			(thermal_gap 0.5)
			(thermal_bridge_width 0.5)
			(island_removal_mode 0)
		)
		(polygon
			(pts
				(arc
					(start 320.141854 -436.160418)
					(mid 320.164172 -436.2143)
					(end 320.218054 -436.236618)
				)
				(arc
					(start 321.157854 -436.236618)
					(mid 321.211736 -436.2143)
					(end 321.234054 -436.160418)
				)
				(arc
					(start 321.234054 -433.618894)
					(mid 321.211736 -433.565012)
					(end 321.157854 -433.542694)
				)
				(arc
					(start 320.218054 -433.542694)
					(mid 320.164172 -433.565012)
					(end 320.141854 -433.618894)
				)
				(arc
					(start 320.141854 -434.34635)
					(mid 320.143853 -434.363691)
					(end 320.149728 -434.380132)
				)
				(arc
					(start 320.383154 -434.856382)
					(mid 320.390937 -434.88991)
					(end 320.383154 -434.923438)
				)
				(arc
					(start 320.149728 -435.399688)
					(mid 320.143833 -435.416124)
					(end 320.141854 -435.43347)
				)
			)
		)
	)
	(zone
		(layer "In12.Cu")
		(hatch none 0.5)
		(connect_pads
			(clearance 0)
		)
		(min_thickness 0.25)
		(keepout
			(tracks not_allowed)
			(vias allowed)
			(pads allowed)
			(copperpour not_allowed)
			(footprints allowed)
		)
		(placement
			(enabled no)
			(sheetname "")
		)
		(fill
			(thermal_gap 0.5)
			(thermal_bridge_width 0.5)
			(island_removal_mode 0)
		)
		(polygon
			(pts
				(arc
					(start 345.141804 -436.160418)
					(mid 345.164122 -436.2143)
					(end 345.218004 -436.236618)
				)
				(arc
					(start 346.157804 -436.236618)
					(mid 346.211686 -436.2143)
					(end 346.234004 -436.160418)
				)
				(arc
					(start 346.234004 -433.618894)
					(mid 346.211686 -433.565012)
					(end 346.157804 -433.542694)
				)
				(arc
					(start 345.218004 -433.542694)
					(mid 345.164122 -433.565012)
					(end 345.141804 -433.618894)
				)
				(arc
					(start 345.141804 -434.34635)
					(mid 345.143803 -434.363691)
					(end 345.149678 -434.380132)
				)
				(arc
					(start 345.383104 -434.856382)
					(mid 345.390887 -434.88991)
					(end 345.383104 -434.923438)
				)
				(arc
					(start 345.149678 -435.399688)
					(mid 345.143783 -435.416124)
					(end 345.141804 -435.43347)
				)
			)
		)
	)
	(zone
		(layer "In12.Cu")
		(hatch none 0.5)
		(connect_pads
			(clearance 0)
		)
		(min_thickness 0.25)
		(keepout
			(tracks not_allowed)
			(vias allowed)
			(pads allowed)
			(copperpour not_allowed)
			(footprints allowed)
		)
		(placement
			(enabled no)
			(sheetname "")
		)
		(fill
			(thermal_gap 0.5)
			(thermal_bridge_width 0.5)
			(island_removal_mode 0)
		)
		(polygon
			(pts
				(arc
					(start 137.241534 -438.76087)
					(mid 137.263852 -438.814752)
					(end 137.317734 -438.83707)
				)
				(arc
					(start 138.257534 -438.83707)
					(mid 138.311416 -438.814752)
					(end 138.333734 -438.76087)
				)
				(arc
					(start 138.333734 -436.219346)
					(mid 138.311416 -436.165464)
					(end 138.257534 -436.143146)
				)
				(arc
					(start 137.317734 -436.143146)
					(mid 137.263852 -436.165464)
					(end 137.241534 -436.219346)
				)
			)
		)
	)
	(zone
		(layer "In12.Cu")
		(hatch none 0.5)
		(connect_pads
			(clearance 0)
		)
		(min_thickness 0.25)
		(keepout
			(tracks not_allowed)
			(vias allowed)
			(pads allowed)
			(copperpour not_allowed)
			(footprints allowed)
		)
		(placement
			(enabled no)
			(sheetname "")
		)
		(fill
			(thermal_gap 0.5)
			(thermal_bridge_width 0.5)
			(island_removal_mode 0)
		)
		(polygon
			(pts
				(arc
					(start 333.141828 -436.160418)
					(mid 333.164146 -436.2143)
					(end 333.218028 -436.236618)
				)
				(arc
					(start 334.157828 -436.236618)
					(mid 334.21171 -436.2143)
					(end 334.234028 -436.160418)
				)
				(arc
					(start 334.234028 -433.618894)
					(mid 334.21171 -433.565012)
					(end 334.157828 -433.542694)
				)
				(arc
					(start 333.218028 -433.542694)
					(mid 333.164146 -433.565012)
					(end 333.141828 -433.618894)
				)
				(arc
					(start 333.141828 -434.34635)
					(mid 333.143827 -434.363691)
					(end 333.149702 -434.380132)
				)
				(arc
					(start 333.383128 -434.856382)
					(mid 333.390911 -434.88991)
					(end 333.383128 -434.923438)
				)
				(arc
					(start 333.149702 -435.399688)
					(mid 333.143807 -435.416124)
					(end 333.141828 -435.43347)
				)
			)
		)
	)
	(zone
		(layer "In12.Cu")
		(hatch none 0.5)
		(connect_pads
			(clearance 0)
		)
		(min_thickness 0.25)
		(keepout
			(tracks not_allowed)
			(vias allowed)
			(pads allowed)
			(copperpour not_allowed)
			(footprints allowed)
		)
		(placement
			(enabled no)
			(sheetname "")
		)
		(fill
			(thermal_gap 0.5)
			(thermal_bridge_width 0.5)
			(island_removal_mode 0)
		)
		(polygon
			(pts
				(arc
					(start 412.241746 -439.760868)
					(mid 412.264064 -439.81475)
					(end 412.317946 -439.837068)
				)
				(arc
					(start 413.257746 -439.837068)
					(mid 413.311628 -439.81475)
					(end 413.333946 -439.760868)
				)
				(arc
					(start 413.333946 -437.219344)
					(mid 413.311628 -437.165462)
					(end 413.257746 -437.143144)
				)
				(arc
					(start 412.317946 -437.143144)
					(mid 412.264064 -437.165462)
					(end 412.241746 -437.219344)
				)
			)
		)
	)
	(zone
		(layer "In12.Cu")
		(hatch none 0.5)
		(connect_pads
			(clearance 0)
		)
		(min_thickness 0.25)
		(keepout
			(tracks not_allowed)
			(vias allowed)
			(pads allowed)
			(copperpour not_allowed)
			(footprints allowed)
		)
		(placement
			(enabled no)
			(sheetname "")
		)
		(fill
			(thermal_gap 0.5)
			(thermal_bridge_width 0.5)
			(island_removal_mode 0)
		)
		(polygon
			(pts
				(xy 209.33283 -402.74113) (xy 209.33283 -401.125944) (xy 211.048854 -401.125944) (xy 211.048854 -402.74113)
			)
		)
	)
	(zone
		(layer "In12.Cu")
		(hatch none 0.5)
		(connect_pads
			(clearance 0)
		)
		(min_thickness 0.25)
		(keepout
			(tracks not_allowed)
			(vias allowed)
			(pads allowed)
			(copperpour not_allowed)
			(footprints allowed)
		)
		(placement
			(enabled no)
			(sheetname "")
		)
		(fill
			(thermal_gap 0.5)
			(thermal_bridge_width 0.5)
			(island_removal_mode 0)
		)
		(polygon
			(pts
				(arc
					(start 398.241774 -438.76087)
					(mid 398.264092 -438.814752)
					(end 398.317974 -438.83707)
				)
				(arc
					(start 399.257774 -438.83707)
					(mid 399.311656 -438.814752)
					(end 399.333974 -438.76087)
				)
				(arc
					(start 399.333974 -436.219346)
					(mid 399.311656 -436.165464)
					(end 399.257774 -436.143146)
				)
				(arc
					(start 398.317974 -436.143146)
					(mid 398.264092 -436.165464)
					(end 398.241774 -436.219346)
				)
			)
		)
	)
	(zone
		(layer "In12.Cu")
		(hatch none 0.5)
		(connect_pads
			(clearance 0)
		)
		(min_thickness 0.25)
		(keepout
			(tracks not_allowed)
			(vias allowed)
			(pads allowed)
			(copperpour not_allowed)
			(footprints allowed)
		)
		(placement
			(enabled no)
			(sheetname "")
		)
		(fill
			(thermal_gap 0.5)
			(thermal_bridge_width 0.5)
			(island_removal_mode 0)
		)
		(polygon
			(pts
				(arc
					(start 328.141838 -436.160418)
					(mid 328.164156 -436.2143)
					(end 328.218038 -436.236618)
				)
				(arc
					(start 329.157838 -436.236618)
					(mid 329.21172 -436.2143)
					(end 329.234038 -436.160418)
				)
				(arc
					(start 329.234038 -433.618894)
					(mid 329.21172 -433.565012)
					(end 329.157838 -433.542694)
				)
				(arc
					(start 328.218038 -433.542694)
					(mid 328.164156 -433.565012)
					(end 328.141838 -433.618894)
				)
				(arc
					(start 328.141838 -434.34635)
					(mid 328.143837 -434.363691)
					(end 328.149712 -434.380132)
				)
				(arc
					(start 328.383138 -434.856382)
					(mid 328.390921 -434.88991)
					(end 328.383138 -434.923438)
				)
				(arc
					(start 328.149712 -435.399688)
					(mid 328.143817 -435.416124)
					(end 328.141838 -435.43347)
				)
			)
		)
	)
	(zone
		(layer "In12.Cu")
		(hatch none 0.5)
		(connect_pads
			(clearance 0)
		)
		(min_thickness 0.25)
		(keepout
			(tracks not_allowed)
			(vias allowed)
			(pads allowed)
			(copperpour not_allowed)
			(footprints allowed)
		)
		(placement
			(enabled no)
			(sheetname "")
		)
		(fill
			(thermal_gap 0.5)
			(thermal_bridge_width 0.5)
			(island_removal_mode 0)
		)
		(polygon
			(pts
				(arc
					(start 60.141866 -436.160418)
					(mid 60.164184 -436.2143)
					(end 60.218066 -436.236618)
				)
				(arc
					(start 61.157866 -436.236618)
					(mid 61.211748 -436.2143)
					(end 61.234066 -436.160418)
				)
				(arc
					(start 61.234066 -433.618894)
					(mid 61.211748 -433.565012)
					(end 61.157866 -433.542694)
				)
				(arc
					(start 60.218066 -433.542694)
					(mid 60.164184 -433.565012)
					(end 60.141866 -433.618894)
				)
				(arc
					(start 60.141866 -434.34635)
					(mid 60.143865 -434.363691)
					(end 60.14974 -434.380132)
				)
				(arc
					(start 60.383166 -434.856382)
					(mid 60.390949 -434.88991)
					(end 60.383166 -434.923438)
				)
				(arc
					(start 60.14974 -435.399688)
					(mid 60.143845 -435.416124)
					(end 60.141866 -435.43347)
				)
			)
		)
	)
	(zone
		(layer "In12.Cu")
		(hatch none 0.5)
		(connect_pads
			(clearance 0)
		)
		(min_thickness 0.25)
		(keepout
			(tracks not_allowed)
			(vias allowed)
			(pads allowed)
			(copperpour not_allowed)
			(footprints allowed)
		)
		(placement
			(enabled no)
			(sheetname "")
		)
		(fill
			(thermal_gap 0.5)
			(thermal_bridge_width 0.5)
			(island_removal_mode 0)
		)
		(polygon
			(pts
				(arc
					(start 391.241534 -439.760868)
					(mid 391.263852 -439.81475)
					(end 391.317734 -439.837068)
				)
				(arc
					(start 392.257534 -439.837068)
					(mid 392.311416 -439.81475)
					(end 392.333734 -439.760868)
				)
				(arc
					(start 392.333734 -437.219344)
					(mid 392.311416 -437.165462)
					(end 392.257534 -437.143144)
				)
				(arc
					(start 391.317734 -437.143144)
					(mid 391.263852 -437.165462)
					(end 391.241534 -437.219344)
				)
			)
		)
	)
	(zone
		(layer "In12.Cu")
		(hatch none 0.5)
		(connect_pads
			(clearance 0)
		)
		(min_thickness 0.25)
		(keepout
			(tracks not_allowed)
			(vias allowed)
			(pads allowed)
			(copperpour not_allowed)
			(footprints allowed)
		)
		(placement
			(enabled no)
			(sheetname "")
		)
		(fill
			(thermal_gap 0.5)
			(thermal_bridge_width 0.5)
			(island_removal_mode 0)
		)
		(polygon
			(pts
				(arc
					(start 144.241774 -439.760868)
					(mid 144.264092 -439.81475)
					(end 144.317974 -439.837068)
				)
				(arc
					(start 145.257774 -439.837068)
					(mid 145.311656 -439.81475)
					(end 145.333974 -439.760868)
				)
				(arc
					(start 145.333974 -437.219344)
					(mid 145.311656 -437.165462)
					(end 145.257774 -437.143144)
				)
				(arc
					(start 144.317974 -437.143144)
					(mid 144.264092 -437.165462)
					(end 144.241774 -437.219344)
				)
			)
		)
	)
	(zone
		(layer "In12.Cu")
		(hatch none 0.5)
		(connect_pads
			(clearance 0)
		)
		(min_thickness 0.25)
		(keepout
			(tracks allowed)
			(vias allowed)
			(pads allowed)
			(copperpour allowed)
			(footprints allowed)
		)
		(placement
			(enabled no)
			(sheetname "")
		)
		(fill
			(thermal_gap 0.5)
			(thermal_bridge_width 0.5)
			(island_removal_mode 0)
		)
		(polygon
			(pts
				(xy 56.324754 -347.631512) (xy 56.324754 -348.477332) (xy 56.017414 -348.477332) (xy 56.017414 -347.631512)
			)
		)
	)
	(zone
		(layer "In12.Cu")
		(hatch none 0.5)
		(connect_pads
			(clearance 0)
		)
		(min_thickness 0.25)
		(keepout
			(tracks not_allowed)
			(vias allowed)
			(pads allowed)
			(copperpour not_allowed)
			(footprints allowed)
		)
		(placement
			(enabled no)
			(sheetname "")
		)
		(fill
			(thermal_gap 0.5)
			(thermal_bridge_width 0.5)
			(island_removal_mode 0)
		)
		(polygon
			(pts
				(arc
					(start 154.241754 -435.16042)
					(mid 154.264072 -435.214302)
					(end 154.317954 -435.23662)
				)
				(arc
					(start 155.257754 -435.23662)
					(mid 155.311636 -435.214302)
					(end 155.333954 -435.16042)
				)
				(arc
					(start 155.333954 -432.618896)
					(mid 155.311636 -432.565014)
					(end 155.257754 -432.542696)
				)
				(arc
					(start 154.317954 -432.542696)
					(mid 154.264072 -432.565014)
					(end 154.241754 -432.618896)
				)
				(arc
					(start 154.241754 -433.346352)
					(mid 154.243753 -433.363693)
					(end 154.249628 -433.380134)
				)
				(arc
					(start 154.483054 -433.856384)
					(mid 154.490837 -433.889912)
					(end 154.483054 -433.92344)
				)
				(arc
					(start 154.249628 -434.39969)
					(mid 154.243733 -434.416126)
					(end 154.241754 -434.433472)
				)
			)
		)
	)
	(zone
		(layer "In12.Cu")
		(hatch none 0.5)
		(connect_pads
			(clearance 0)
		)
		(min_thickness 0.25)
		(keepout
			(tracks not_allowed)
			(vias allowed)
			(pads allowed)
			(copperpour not_allowed)
			(footprints allowed)
		)
		(placement
			(enabled no)
			(sheetname "")
		)
		(fill
			(thermal_gap 0.5)
			(thermal_bridge_width 0.5)
			(island_removal_mode 0)
		)
		(polygon
			(pts
				(arc
					(start 393.241784 -435.16042)
					(mid 393.264102 -435.214302)
					(end 393.317984 -435.23662)
				)
				(arc
					(start 394.257784 -435.23662)
					(mid 394.311666 -435.214302)
					(end 394.333984 -435.16042)
				)
				(arc
					(start 394.333984 -432.618896)
					(mid 394.311666 -432.565014)
					(end 394.257784 -432.542696)
				)
				(arc
					(start 393.317984 -432.542696)
					(mid 393.264102 -432.565014)
					(end 393.241784 -432.618896)
				)
				(arc
					(start 393.241784 -433.346352)
					(mid 393.243783 -433.363693)
					(end 393.249658 -433.380134)
				)
				(arc
					(start 393.483084 -433.856384)
					(mid 393.490867 -433.889912)
					(end 393.483084 -433.92344)
				)
				(arc
					(start 393.249658 -434.39969)
					(mid 393.243763 -434.416126)
					(end 393.241784 -434.433472)
				)
			)
		)
	)
	(zone
		(layer "In12.Cu")
		(hatch none 0.5)
		(connect_pads
			(clearance 0)
		)
		(min_thickness 0.25)
		(keepout
			(tracks not_allowed)
			(vias allowed)
			(pads allowed)
			(copperpour not_allowed)
			(footprints allowed)
		)
		(placement
			(enabled no)
			(sheetname "")
		)
		(fill
			(thermal_gap 0.5)
			(thermal_bridge_width 0.5)
			(island_removal_mode 0)
		)
		(polygon
			(pts
				(arc
					(start 146.24177 -438.76087)
					(mid 146.264088 -438.814752)
					(end 146.31797 -438.83707)
				)
				(arc
					(start 147.25777 -438.83707)
					(mid 147.311652 -438.814752)
					(end 147.33397 -438.76087)
				)
				(arc
					(start 147.33397 -436.219346)
					(mid 147.311652 -436.165464)
					(end 147.25777 -436.143146)
				)
				(arc
					(start 146.31797 -436.143146)
					(mid 146.264088 -436.165464)
					(end 146.24177 -436.219346)
				)
			)
		)
	)
	(zone
		(layer "In12.Cu")
		(hatch none 0.5)
		(connect_pads
			(clearance 0)
		)
		(min_thickness 0.25)
		(keepout
			(tracks not_allowed)
			(vias allowed)
			(pads allowed)
			(copperpour not_allowed)
			(footprints allowed)
		)
		(placement
			(enabled no)
			(sheetname "")
		)
		(fill
			(thermal_gap 0.5)
			(thermal_bridge_width 0.5)
			(island_removal_mode 0)
		)
		(polygon
			(pts
				(arc
					(start 326.141334 -438.76087)
					(mid 326.163652 -438.814752)
					(end 326.217534 -438.83707)
				)
				(arc
					(start 327.157334 -438.83707)
					(mid 327.211216 -438.814752)
					(end 327.233534 -438.76087)
				)
				(arc
					(start 327.233534 -436.219346)
					(mid 327.211216 -436.165464)
					(end 327.157334 -436.143146)
				)
				(arc
					(start 326.217534 -436.143146)
					(mid 326.163652 -436.165464)
					(end 326.141334 -436.219346)
				)
			)
		)
	)
	(zone
		(layer "In12.Cu")
		(hatch none 0.5)
		(connect_pads
			(clearance 0)
		)
		(min_thickness 0.25)
		(keepout
			(tracks not_allowed)
			(vias allowed)
			(pads allowed)
			(copperpour not_allowed)
			(footprints allowed)
		)
		(placement
			(enabled no)
			(sheetname "")
		)
		(fill
			(thermal_gap 0.5)
			(thermal_bridge_width 0.5)
			(island_removal_mode 0)
		)
		(polygon
			(pts
				(arc
					(start 146.24177 -435.16042)
					(mid 146.264088 -435.214302)
					(end 146.31797 -435.23662)
				)
				(arc
					(start 147.25777 -435.23662)
					(mid 147.311652 -435.214302)
					(end 147.33397 -435.16042)
				)
				(arc
					(start 147.33397 -432.618896)
					(mid 147.311652 -432.565014)
					(end 147.25777 -432.542696)
				)
				(arc
					(start 146.31797 -432.542696)
					(mid 146.264088 -432.565014)
					(end 146.24177 -432.618896)
				)
				(arc
					(start 146.24177 -433.346352)
					(mid 146.243769 -433.363693)
					(end 146.249644 -433.380134)
				)
				(arc
					(start 146.48307 -433.856384)
					(mid 146.490853 -433.889912)
					(end 146.48307 -433.92344)
				)
				(arc
					(start 146.249644 -434.39969)
					(mid 146.243749 -434.416126)
					(end 146.24177 -434.433472)
				)
			)
		)
	)
	(zone
		(layer "In12.Cu")
		(hatch none 0.5)
		(connect_pads
			(clearance 0)
		)
		(min_thickness 0.25)
		(keepout
			(tracks allowed)
			(vias allowed)
			(pads allowed)
			(copperpour allowed)
			(footprints allowed)
		)
		(placement
			(enabled no)
			(sheetname "")
		)
		(fill
			(thermal_gap 0.5)
			(thermal_bridge_width 0.5)
			(island_removal_mode 0)
		)
		(polygon
			(pts
				(xy 73.266554 -335.906872) (xy 73.266554 -336.752692) (xy 72.959214 -336.752692) (xy 72.959214 -335.906872)
			)
		)
	)
	(zone
		(layer "In12.Cu")
		(hatch none 0.5)
		(connect_pads
			(clearance 0)
		)
		(min_thickness 0.25)
		(keepout
			(tracks allowed)
			(vias allowed)
			(pads allowed)
			(copperpour allowed)
			(footprints allowed)
		)
		(placement
			(enabled no)
			(sheetname "")
		)
		(fill
			(thermal_gap 0.5)
			(thermal_bridge_width 0.5)
			(island_removal_mode 0)
		)
		(polygon
			(pts
				(xy 41.430194 -350.453452) (xy 41.430194 -351.299272) (xy 41.122854 -351.299272) (xy 41.122854 -350.453452)
			)
		)
	)
	(zone
		(layer "In12.Cu")
		(hatch none 0.5)
		(connect_pads
			(clearance 0)
		)
		(min_thickness 0.25)
		(keepout
			(tracks not_allowed)
			(vias allowed)
			(pads allowed)
			(copperpour not_allowed)
			(footprints allowed)
		)
		(placement
			(enabled no)
			(sheetname "")
		)
		(fill
			(thermal_gap 0.5)
			(thermal_bridge_width 0.5)
			(island_removal_mode 0)
		)
		(polygon
			(pts
				(arc
					(start 148.241766 -439.760868)
					(mid 148.264084 -439.81475)
					(end 148.317966 -439.837068)
				)
				(arc
					(start 149.257766 -439.837068)
					(mid 149.311648 -439.81475)
					(end 149.333966 -439.760868)
				)
				(arc
					(start 149.333966 -437.219344)
					(mid 149.311648 -437.165462)
					(end 149.257766 -437.143144)
				)
				(arc
					(start 148.317966 -437.143144)
					(mid 148.264084 -437.165462)
					(end 148.241766 -437.219344)
				)
			)
		)
	)
	(zone
		(layer "In12.Cu")
		(hatch none 0.5)
		(connect_pads
			(clearance 0)
		)
		(min_thickness 0.25)
		(keepout
			(tracks not_allowed)
			(vias allowed)
			(pads allowed)
			(copperpour not_allowed)
			(footprints allowed)
		)
		(placement
			(enabled no)
			(sheetname "")
		)
		(fill
			(thermal_gap 0.5)
			(thermal_bridge_width 0.5)
			(island_removal_mode 0)
		)
		(polygon
			(pts
				(arc
					(start 402.241766 -435.16042)
					(mid 402.264084 -435.214302)
					(end 402.317966 -435.23662)
				)
				(arc
					(start 403.257766 -435.23662)
					(mid 403.311648 -435.214302)
					(end 403.333966 -435.16042)
				)
				(arc
					(start 403.333966 -432.618896)
					(mid 403.311648 -432.565014)
					(end 403.257766 -432.542696)
				)
				(arc
					(start 402.317966 -432.542696)
					(mid 402.264084 -432.565014)
					(end 402.241766 -432.618896)
				)
				(arc
					(start 402.241766 -433.346352)
					(mid 402.243765 -433.363693)
					(end 402.24964 -433.380134)
				)
				(arc
					(start 402.483066 -433.856384)
					(mid 402.490849 -433.889912)
					(end 402.483066 -433.92344)
				)
				(arc
					(start 402.24964 -434.39969)
					(mid 402.243745 -434.416126)
					(end 402.241766 -434.433472)
				)
			)
		)
	)
	(zone
		(layer "In12.Cu")
		(hatch none 0.5)
		(connect_pads
			(clearance 0)
		)
		(min_thickness 0.25)
		(keepout
			(tracks not_allowed)
			(vias allowed)
			(pads allowed)
			(copperpour not_allowed)
			(footprints allowed)
		)
		(placement
			(enabled no)
			(sheetname "")
		)
		(fill
			(thermal_gap 0.5)
			(thermal_bridge_width 0.5)
			(island_removal_mode 0)
		)
		(polygon
			(pts
				(arc
					(start 387.241796 -436.160418)
					(mid 387.264114 -436.2143)
					(end 387.317996 -436.236618)
				)
				(arc
					(start 388.257796 -436.236618)
					(mid 388.311678 -436.2143)
					(end 388.333996 -436.160418)
				)
				(arc
					(start 388.333996 -433.618894)
					(mid 388.311678 -433.565012)
					(end 388.257796 -433.542694)
				)
				(arc
					(start 387.317996 -433.542694)
					(mid 387.264114 -433.565012)
					(end 387.241796 -433.618894)
				)
				(arc
					(start 387.241796 -434.34635)
					(mid 387.243795 -434.363691)
					(end 387.24967 -434.380132)
				)
				(arc
					(start 387.483096 -434.856382)
					(mid 387.490879 -434.88991)
					(end 387.483096 -434.923438)
				)
				(arc
					(start 387.24967 -435.399688)
					(mid 387.243775 -435.416124)
					(end 387.241796 -435.43347)
				)
			)
		)
	)
	(zone
		(layer "In12.Cu")
		(hatch none 0.5)
		(connect_pads
			(clearance 0)
		)
		(min_thickness 0.25)
		(keepout
			(tracks not_allowed)
			(vias allowed)
			(pads allowed)
			(copperpour not_allowed)
			(footprints allowed)
		)
		(placement
			(enabled no)
			(sheetname "")
		)
		(fill
			(thermal_gap 0.5)
			(thermal_bridge_width 0.5)
			(island_removal_mode 0)
		)
		(polygon
			(pts
				(arc
					(start 326.141842 -435.16042)
					(mid 326.16416 -435.214302)
					(end 326.218042 -435.23662)
				)
				(arc
					(start 327.157842 -435.23662)
					(mid 327.211724 -435.214302)
					(end 327.234042 -435.16042)
				)
				(arc
					(start 327.234042 -432.618896)
					(mid 327.211724 -432.565014)
					(end 327.157842 -432.542696)
				)
				(arc
					(start 326.218042 -432.542696)
					(mid 326.16416 -432.565014)
					(end 326.141842 -432.618896)
				)
				(arc
					(start 326.141842 -433.346352)
					(mid 326.143841 -433.363693)
					(end 326.149716 -433.380134)
				)
				(arc
					(start 326.383142 -433.856384)
					(mid 326.390925 -433.889912)
					(end 326.383142 -433.92344)
				)
				(arc
					(start 326.149716 -434.39969)
					(mid 326.143821 -434.416126)
					(end 326.141842 -434.433472)
				)
			)
		)
	)
	(zone
		(layer "In12.Cu")
		(hatch none 0.5)
		(connect_pads
			(clearance 0)
		)
		(min_thickness 0.25)
		(keepout
			(tracks not_allowed)
			(vias allowed)
			(pads allowed)
			(copperpour not_allowed)
			(footprints allowed)
		)
		(placement
			(enabled no)
			(sheetname "")
		)
		(fill
			(thermal_gap 0.5)
			(thermal_bridge_width 0.5)
			(island_removal_mode 0)
		)
		(polygon
			(pts
				(arc
					(start 398.241774 -435.16042)
					(mid 398.264092 -435.214302)
					(end 398.317974 -435.23662)
				)
				(arc
					(start 399.257774 -435.23662)
					(mid 399.311656 -435.214302)
					(end 399.333974 -435.16042)
				)
				(arc
					(start 399.333974 -432.618896)
					(mid 399.311656 -432.565014)
					(end 399.257774 -432.542696)
				)
				(arc
					(start 398.317974 -432.542696)
					(mid 398.264092 -432.565014)
					(end 398.241774 -432.618896)
				)
				(arc
					(start 398.241774 -433.346352)
					(mid 398.243773 -433.363693)
					(end 398.249648 -433.380134)
				)
				(arc
					(start 398.483074 -433.856384)
					(mid 398.490857 -433.889912)
					(end 398.483074 -433.92344)
				)
				(arc
					(start 398.249648 -434.39969)
					(mid 398.243753 -434.416126)
					(end 398.241774 -434.433472)
				)
			)
		)
	)
	(zone
		(layer "In12.Cu")
		(hatch none 0.5)
		(connect_pads
			(clearance 0)
		)
		(min_thickness 0.25)
		(keepout
			(tracks not_allowed)
			(vias allowed)
			(pads allowed)
			(copperpour not_allowed)
			(footprints allowed)
		)
		(placement
			(enabled no)
			(sheetname "")
		)
		(fill
			(thermal_gap 0.5)
			(thermal_bridge_width 0.5)
			(island_removal_mode 0)
		)
		(polygon
			(pts
				(arc
					(start 385.241546 -438.76087)
					(mid 385.263864 -438.814752)
					(end 385.317746 -438.83707)
				)
				(arc
					(start 386.257546 -438.83707)
					(mid 386.311428 -438.814752)
					(end 386.333746 -438.76087)
				)
				(arc
					(start 386.333746 -436.219346)
					(mid 386.311428 -436.165464)
					(end 386.257546 -436.143146)
				)
				(arc
					(start 385.317746 -436.143146)
					(mid 385.263864 -436.165464)
					(end 385.241546 -436.219346)
				)
			)
		)
	)
	(zone
		(layer "In12.Cu")
		(hatch none 0.5)
		(connect_pads
			(clearance 0)
		)
		(min_thickness 0.25)
		(keepout
			(tracks not_allowed)
			(vias allowed)
			(pads allowed)
			(copperpour not_allowed)
			(footprints allowed)
		)
		(placement
			(enabled no)
			(sheetname "")
		)
		(fill
			(thermal_gap 0.5)
			(thermal_bridge_width 0.5)
			(island_removal_mode 0)
		)
		(polygon
			(pts
				(arc
					(start 70.141846 -435.16042)
					(mid 70.164164 -435.214302)
					(end 70.218046 -435.23662)
				)
				(arc
					(start 71.157846 -435.23662)
					(mid 71.211728 -435.214302)
					(end 71.234046 -435.16042)
				)
				(arc
					(start 71.234046 -432.618896)
					(mid 71.211728 -432.565014)
					(end 71.157846 -432.542696)
				)
				(arc
					(start 70.218046 -432.542696)
					(mid 70.164164 -432.565014)
					(end 70.141846 -432.618896)
				)
				(arc
					(start 70.141846 -433.346352)
					(mid 70.143845 -433.363693)
					(end 70.14972 -433.380134)
				)
				(arc
					(start 70.383146 -433.856384)
					(mid 70.390929 -433.889912)
					(end 70.383146 -433.92344)
				)
				(arc
					(start 70.14972 -434.39969)
					(mid 70.143825 -434.416126)
					(end 70.141846 -434.433472)
				)
			)
		)
	)
	(zone
		(layer "In13.Cu")
		(hatch none 0.5)
		(connect_pads
			(clearance 0)
		)
		(min_thickness 0.25)
		(keepout
			(tracks allowed)
			(vias allowed)
			(pads allowed)
			(copperpour allowed)
			(footprints allowed)
		)
		(placement
			(enabled no)
			(sheetname "")
		)
		(fill
			(thermal_gap 0.5)
			(thermal_bridge_width 0.5)
			(island_removal_mode 0)
		)
		(polygon
			(pts
				(xy 207.795876 -400.915378) (xy 207.795876 -398.986502) (xy 212.814408 -398.986502) (xy 212.814408 -400.915378)
			)
		)
	)
	(zone
		(layer "In13.Cu")
		(hatch none 0.5)
		(connect_pads
			(clearance 0)
		)
		(min_thickness 0.25)
		(keepout
			(tracks allowed)
			(vias allowed)
			(pads allowed)
			(copperpour allowed)
			(footprints allowed)
		)
		(placement
			(enabled no)
			(sheetname "")
		)
		(fill
			(thermal_gap 0.5)
			(thermal_bridge_width 0.5)
			(island_removal_mode 0)
		)
		(polygon
			(pts
				(xy 229.161086 -401.039076) (xy 229.161086 -399.1102) (xy 234.179618 -399.1102) (xy 234.179618 -401.039076)
			)
		)
	)
	(zone
		(layer "In13.Cu")
		(hatch none 0.5)
		(connect_pads
			(clearance 0)
		)
		(min_thickness 0.25)
		(keepout
			(tracks allowed)
			(vias allowed)
			(pads allowed)
			(copperpour allowed)
			(footprints allowed)
		)
		(placement
			(enabled no)
			(sheetname "")
		)
		(fill
			(thermal_gap 0.5)
			(thermal_bridge_width 0.5)
			(island_removal_mode 0)
		)
		(polygon
			(pts
				(xy 259.514594 -394.180822) (xy 259.514594 -393.647676) (xy 260.818376 -393.647676) (xy 260.818376 -394.180822)
			)
		)
	)
	(zone
		(layer "In13.Cu")
		(hatch none 0.5)
		(connect_pads
			(clearance 0)
		)
		(min_thickness 0.25)
		(keepout
			(tracks allowed)
			(vias allowed)
			(pads allowed)
			(copperpour allowed)
			(footprints allowed)
		)
		(placement
			(enabled no)
			(sheetname "")
		)
		(fill
			(thermal_gap 0.5)
			(thermal_bridge_width 0.5)
			(island_removal_mode 0)
		)
		(polygon
			(pts
				(xy 251.488194 -394.180822) (xy 251.488194 -393.647676) (xy 252.791976 -393.647676) (xy 252.791976 -394.180822)
			)
		)
	)
	(zone
		(layer "In13.Cu")
		(hatch none 0.5)
		(connect_pads
			(clearance 0)
		)
		(min_thickness 0.25)
		(keepout
			(tracks allowed)
			(vias allowed)
			(pads allowed)
			(copperpour allowed)
			(footprints allowed)
		)
		(placement
			(enabled no)
			(sheetname "")
		)
		(fill
			(thermal_gap 0.5)
			(thermal_bridge_width 0.5)
			(island_removal_mode 0)
		)
		(polygon
			(pts
				(xy 267.540994 -394.180822) (xy 267.540994 -393.647676) (xy 268.844776 -393.647676) (xy 268.844776 -394.180822)
			)
		)
	)
	(zone
		(layer "In13.Cu")
		(hatch none 0.5)
		(connect_pads
			(clearance 0)
		)
		(min_thickness 0.25)
		(keepout
			(tracks allowed)
			(vias allowed)
			(pads allowed)
			(copperpour allowed)
			(footprints allowed)
		)
		(placement
			(enabled no)
			(sheetname "")
		)
		(fill
			(thermal_gap 0.5)
			(thermal_bridge_width 0.5)
			(island_removal_mode 0)
		)
		(polygon
			(pts
				(xy 227.60051 -401.437602) (xy 227.60051 -400.904456) (xy 228.096572 -400.904456) (xy 228.096572 -401.437602)
			)
		)
	)
	(zone
		(layer "In13.Cu")
		(hatch none 0.5)
		(connect_pads
			(clearance 0)
		)
		(min_thickness 0.25)
		(keepout
			(tracks allowed)
			(vias allowed)
			(pads allowed)
			(copperpour allowed)
			(footprints allowed)
		)
		(placement
			(enabled no)
			(sheetname "")
		)
		(fill
			(thermal_gap 0.5)
			(thermal_bridge_width 0.5)
			(island_removal_mode 0)
		)
		(polygon
			(pts
				(xy 216.93251 -401.437602) (xy 216.93251 -400.904456) (xy 217.428572 -400.904456) (xy 217.428572 -401.437602)
			)
		)
	)
	(zone
		(layer "In13.Cu")
		(hatch none 0.5)
		(connect_pads
			(clearance 0)
		)
		(min_thickness 0.25)
		(keepout
			(tracks allowed)
			(vias allowed)
			(pads allowed)
			(copperpour allowed)
			(footprints allowed)
		)
		(placement
			(enabled no)
			(sheetname "")
		)
		(fill
			(thermal_gap 0.5)
			(thermal_bridge_width 0.5)
			(island_removal_mode 0)
		)
		(polygon
			(pts
				(xy 243.458746 -394.176758) (xy 243.458746 -393.643612) (xy 244.762528 -393.643612) (xy 244.762528 -394.176758)
			)
		)
	)
	(zone
		(layer "In13.Cu")
		(hatch none 0.5)
		(connect_pads
			(clearance 0)
		)
		(min_thickness 0.25)
		(keepout
			(tracks not_allowed)
			(vias allowed)
			(pads allowed)
			(copperpour not_allowed)
			(footprints allowed)
		)
		(placement
			(enabled no)
			(sheetname "")
		)
		(fill
			(thermal_gap 0.5)
			(thermal_bridge_width 0.5)
			(island_removal_mode 0)
		)
		(polygon
			(pts
				(arc
					(start 219.48902 -360.764074)
					(mid 207.8609 -360.764074)
					(end 219.48902 -360.764074)
				)
			)
		)
	)
	(zone
		(layer "In13.Cu")
		(hatch none 0.5)
		(connect_pads
			(clearance 0)
		)
		(min_thickness 0.25)
		(keepout
			(tracks allowed)
			(vias allowed)
			(pads allowed)
			(copperpour allowed)
			(footprints allowed)
		)
		(placement
			(enabled no)
			(sheetname "")
		)
		(fill
			(thermal_gap 0.5)
			(thermal_bridge_width 0.5)
			(island_removal_mode 0)
		)
		(polygon
			(pts
				(xy 218.467432 -401.027138) (xy 218.467432 -399.098262) (xy 223.485964 -399.098262) (xy 223.485964 -401.027138)
			)
		)
	)
	(zone
		(layer "In13.Cu")
		(hatch none 0.5)
		(connect_pads
			(clearance 0)
		)
		(min_thickness 0.25)
		(keepout
			(tracks allowed)
			(vias allowed)
			(pads allowed)
			(copperpour allowed)
			(footprints allowed)
		)
		(placement
			(enabled no)
			(sheetname "")
		)
		(fill
			(thermal_gap 0.5)
			(thermal_bridge_width 0.5)
			(island_removal_mode 0)
		)
		(polygon
			(pts
				(xy 197.328536 -400.754596) (xy 197.328536 -398.82572) (xy 202.347068 -398.82572) (xy 202.347068 -400.754596)
			)
		)
	)
	(zone
		(layer "In13.Cu")
		(hatch none 0.5)
		(connect_pads
			(clearance 0)
		)
		(min_thickness 0.25)
		(keepout
			(tracks allowed)
			(vias allowed)
			(pads allowed)
			(copperpour allowed)
			(footprints allowed)
		)
		(placement
			(enabled no)
			(sheetname "")
		)
		(fill
			(thermal_gap 0.5)
			(thermal_bridge_width 0.5)
			(island_removal_mode 0)
		)
		(polygon
			(pts
				(xy 206.26451 -401.437602) (xy 206.26451 -400.904456) (xy 206.760572 -400.904456) (xy 206.760572 -401.437602)
			)
		)
	)
	(zone
		(layer "In13.Cu")
		(hatch none 0.5)
		(connect_pads
			(clearance 0)
		)
		(min_thickness 0.25)
		(keepout
			(tracks allowed)
			(vias allowed)
			(pads allowed)
			(copperpour allowed)
			(footprints allowed)
		)
		(placement
			(enabled no)
			(sheetname "")
		)
		(fill
			(thermal_gap 0.5)
			(thermal_bridge_width 0.5)
			(island_removal_mode 0)
		)
		(polygon
			(pts
				(xy 276.567646 -394.166598) (xy 276.567646 -393.633452) (xy 277.871428 -393.633452) (xy 277.871428 -394.166598)
			)
		)
	)
	(zone
		(layer "In13.Cu")
		(hatch none 0.5)
		(connect_pads
			(clearance 0)
		)
		(min_thickness 0.25)
		(keepout
			(tracks not_allowed)
			(vias allowed)
			(pads allowed)
			(copperpour not_allowed)
			(footprints allowed)
		)
		(placement
			(enabled no)
			(sheetname "")
		)
		(fill
			(thermal_gap 0.5)
			(thermal_bridge_width 0.5)
			(island_removal_mode 0)
		)
		(polygon
			(pts
				(arc
					(start 109.758734 -13.429742)
					(mid 109.773613 -13.393821)
					(end 109.809534 -13.378942)
				)
				(arc
					(start 116.603526 -13.378942)
					(mid 116.639447 -13.393821)
					(end 116.654326 -13.429742)
				)
				(arc
					(start 116.654326 -18.328386)
					(mid 116.639447 -18.364307)
					(end 116.603526 -18.379186)
				)
				(arc
					(start 109.809534 -18.379186)
					(mid 109.773613 -18.364307)
					(end 109.758734 -18.328386)
				)
			)
		)
	)
	(zone
		(layers "In13.Cu" "In15.Cu")
		(hatch none 0.5)
		(connect_pads
			(clearance 0)
		)
		(min_thickness 0.25)
		(keepout
			(tracks not_allowed)
			(vias allowed)
			(pads allowed)
			(copperpour not_allowed)
			(footprints allowed)
		)
		(placement
			(enabled no)
			(sheetname "")
		)
		(fill yes
			(thermal_gap 0.5)
			(thermal_bridge_width 0.5)
			(island_removal_mode 0)
		)
		(polygon
			(pts
				(arc
					(start 378.631958 -162.59683)
					(mid 377.107958 -162.59683)
					(end 378.631958 -162.59683)
				)
			)
		)
	)
	(zone
		(layers "In13.Cu" "In15.Cu")
		(hatch none 0.5)
		(connect_pads
			(clearance 0)
		)
		(min_thickness 0.25)
		(keepout
			(tracks not_allowed)
			(vias allowed)
			(pads allowed)
			(copperpour not_allowed)
			(footprints allowed)
		)
		(placement
			(enabled no)
			(sheetname "")
		)
		(fill yes
			(thermal_gap 0.5)
			(thermal_bridge_width 0.5)
			(island_removal_mode 0)
		)
		(polygon
			(pts
				(arc
					(start 93.149674 -165.962076)
					(mid 91.625674 -165.962076)
					(end 93.149674 -165.962076)
				)
			)
		)
	)
	(zone
		(layers "In13.Cu" "In15.Cu")
		(hatch none 0.5)
		(connect_pads
			(clearance 0)
		)
		(min_thickness 0.25)
		(keepout
			(tracks not_allowed)
			(vias allowed)
			(pads allowed)
			(copperpour not_allowed)
			(footprints allowed)
		)
		(placement
			(enabled no)
			(sheetname "")
		)
		(fill yes
			(thermal_gap 0.5)
			(thermal_bridge_width 0.5)
			(island_removal_mode 0)
		)
		(polygon
			(pts
				(xy 286.236664 -363.456474) (xy 286.236664 -362.385102) (xy 289.508946 -362.385102) (xy 289.508946 -363.456474)
			)
		)
	)
	(zone
		(layers "In13.Cu" "In15.Cu")
		(hatch none 0.5)
		(connect_pads
			(clearance 0)
		)
		(min_thickness 0.25)
		(keepout
			(tracks not_allowed)
			(vias allowed)
			(pads allowed)
			(copperpour not_allowed)
			(footprints allowed)
		)
		(placement
			(enabled no)
			(sheetname "")
		)
		(fill yes
			(thermal_gap 0.5)
			(thermal_bridge_width 0.5)
			(island_removal_mode 0)
		)
		(polygon
			(pts
				(arc
					(start 110.902496 -150.941786)
					(mid 109.378496 -150.941786)
					(end 110.902496 -150.941786)
				)
			)
		)
	)
	(zone
		(layers "In13.Cu" "In15.Cu")
		(hatch none 0.5)
		(connect_pads
			(clearance 0)
		)
		(min_thickness 0.25)
		(keepout
			(tracks not_allowed)
			(vias allowed)
			(pads allowed)
			(copperpour not_allowed)
			(footprints allowed)
		)
		(placement
			(enabled no)
			(sheetname "")
		)
		(fill yes
			(thermal_gap 0.5)
			(thermal_bridge_width 0.5)
			(island_removal_mode 0)
		)
		(polygon
			(pts
				(arc
					(start 360.34726 -152.71242)
					(mid 358.82326 -152.71242)
					(end 360.34726 -152.71242)
				)
			)
		)
	)
	(zone
		(layers "In13.Cu" "In15.Cu")
		(hatch none 0.5)
		(connect_pads
			(clearance 0)
		)
		(min_thickness 0.25)
		(keepout
			(tracks not_allowed)
			(vias allowed)
			(pads allowed)
			(copperpour not_allowed)
			(footprints allowed)
		)
		(placement
			(enabled no)
			(sheetname "")
		)
		(fill yes
			(thermal_gap 0.5)
			(thermal_bridge_width 0.5)
			(island_removal_mode 0)
		)
		(polygon
			(pts
				(arc
					(start 83.751674 -165.962076)
					(mid 82.227674 -165.962076)
					(end 83.751674 -165.962076)
				)
			)
		)
	)
	(zone
		(layers "In13.Cu" "In15.Cu")
		(hatch none 0.5)
		(connect_pads
			(clearance 0)
		)
		(min_thickness 0.25)
		(keepout
			(tracks not_allowed)
			(vias allowed)
			(pads allowed)
			(copperpour not_allowed)
			(footprints allowed)
		)
		(placement
			(enabled no)
			(sheetname "")
		)
		(fill yes
			(thermal_gap 0.5)
			(thermal_bridge_width 0.5)
			(island_removal_mode 0)
		)
		(polygon
			(pts
				(arc
					(start 387.968998 -162.65271)
					(mid 386.444998 -162.65271)
					(end 387.968998 -162.65271)
				)
			)
		)
	)
	(zone
		(layer "In14.Cu")
		(hatch none 0.5)
		(connect_pads
			(clearance 0)
		)
		(min_thickness 0.25)
		(keepout
			(tracks not_allowed)
			(vias allowed)
			(pads allowed)
			(copperpour not_allowed)
			(footprints allowed)
		)
		(placement
			(enabled no)
			(sheetname "")
		)
		(fill
			(thermal_gap 0.5)
			(thermal_bridge_width 0.5)
			(island_removal_mode 0)
		)
		(polygon
			(pts
				(arc
					(start 387.241796 -436.160672)
					(mid 387.264114 -436.214554)
					(end 387.317996 -436.236872)
				)
				(arc
					(start 388.257796 -436.236872)
					(mid 388.311678 -436.214554)
					(end 388.333996 -436.160672)
				)
				(arc
					(start 388.333996 -433.619148)
					(mid 388.311678 -433.565266)
					(end 388.257796 -433.542948)
				)
				(arc
					(start 387.317996 -433.542948)
					(mid 387.264114 -433.565266)
					(end 387.241796 -433.619148)
				)
				(arc
					(start 387.241796 -434.346604)
					(mid 387.243795 -434.363945)
					(end 387.24967 -434.380386)
				)
				(arc
					(start 387.483096 -434.856636)
					(mid 387.490879 -434.890164)
					(end 387.483096 -434.923692)
				)
				(arc
					(start 387.24967 -435.399942)
					(mid 387.243775 -435.416378)
					(end 387.241796 -435.433724)
				)
			)
		)
	)
	(zone
		(layer "In14.Cu")
		(hatch none 0.5)
		(connect_pads
			(clearance 0)
		)
		(min_thickness 0.25)
		(keepout
			(tracks not_allowed)
			(vias allowed)
			(pads allowed)
			(copperpour not_allowed)
			(footprints allowed)
		)
		(placement
			(enabled no)
			(sheetname "")
		)
		(fill
			(thermal_gap 0.5)
			(thermal_bridge_width 0.5)
			(island_removal_mode 0)
		)
		(polygon
			(pts
				(arc
					(start 148.24202 -436.160672)
					(mid 148.264338 -436.214554)
					(end 148.31822 -436.236872)
				)
				(arc
					(start 149.25802 -436.236872)
					(mid 149.311902 -436.214554)
					(end 149.33422 -436.160672)
				)
				(arc
					(start 149.33422 -433.619148)
					(mid 149.311902 -433.565266)
					(end 149.25802 -433.542948)
				)
				(arc
					(start 148.31822 -433.542948)
					(mid 148.264338 -433.565266)
					(end 148.24202 -433.619148)
				)
				(arc
					(start 148.24202 -434.346604)
					(mid 148.244019 -434.363945)
					(end 148.249894 -434.380386)
				)
				(arc
					(start 148.48332 -434.856636)
					(mid 148.491103 -434.890164)
					(end 148.48332 -434.923692)
				)
				(arc
					(start 148.249894 -435.399942)
					(mid 148.243999 -435.416378)
					(end 148.24202 -435.433724)
				)
			)
		)
	)
	(zone
		(layer "In14.Cu")
		(hatch none 0.5)
		(connect_pads
			(clearance 0)
		)
		(min_thickness 0.25)
		(keepout
			(tracks not_allowed)
			(vias allowed)
			(pads allowed)
			(copperpour not_allowed)
			(footprints allowed)
		)
		(placement
			(enabled no)
			(sheetname "")
		)
		(fill
			(thermal_gap 0.5)
			(thermal_bridge_width 0.5)
			(island_removal_mode 0)
		)
		(polygon
			(pts
				(arc
					(start 383.241804 -436.160672)
					(mid 383.264122 -436.214554)
					(end 383.318004 -436.236872)
				)
				(arc
					(start 384.257804 -436.236872)
					(mid 384.311686 -436.214554)
					(end 384.334004 -436.160672)
				)
				(arc
					(start 384.334004 -433.619148)
					(mid 384.311686 -433.565266)
					(end 384.257804 -433.542948)
				)
				(arc
					(start 383.318004 -433.542948)
					(mid 383.264122 -433.565266)
					(end 383.241804 -433.619148)
				)
				(arc
					(start 383.241804 -434.346604)
					(mid 383.243803 -434.363945)
					(end 383.249678 -434.380386)
				)
				(arc
					(start 383.483104 -434.856636)
					(mid 383.490887 -434.890164)
					(end 383.483104 -434.923692)
				)
				(arc
					(start 383.249678 -435.399942)
					(mid 383.243783 -435.416378)
					(end 383.241804 -435.433724)
				)
			)
		)
	)
	(zone
		(layer "In14.Cu")
		(hatch none 0.5)
		(connect_pads
			(clearance 0)
		)
		(min_thickness 0.25)
		(keepout
			(tracks not_allowed)
			(vias allowed)
			(pads allowed)
			(copperpour not_allowed)
			(footprints allowed)
		)
		(placement
			(enabled no)
			(sheetname "")
		)
		(fill
			(thermal_gap 0.5)
			(thermal_bridge_width 0.5)
			(island_removal_mode 0)
		)
		(polygon
			(pts
				(arc
					(start 345.141804 -436.160672)
					(mid 345.164122 -436.214554)
					(end 345.218004 -436.236872)
				)
				(arc
					(start 346.157804 -436.236872)
					(mid 346.211686 -436.214554)
					(end 346.234004 -436.160672)
				)
				(arc
					(start 346.234004 -433.619148)
					(mid 346.211686 -433.565266)
					(end 346.157804 -433.542948)
				)
				(arc
					(start 345.218004 -433.542948)
					(mid 345.164122 -433.565266)
					(end 345.141804 -433.619148)
				)
				(arc
					(start 345.141804 -434.346604)
					(mid 345.143803 -434.363945)
					(end 345.149678 -434.380386)
				)
				(arc
					(start 345.383104 -434.856636)
					(mid 345.390887 -434.890164)
					(end 345.383104 -434.923692)
				)
				(arc
					(start 345.149678 -435.399942)
					(mid 345.143783 -435.416378)
					(end 345.141804 -435.433724)
				)
			)
		)
	)
	(zone
		(layer "In14.Cu")
		(hatch none 0.5)
		(connect_pads
			(clearance 0)
		)
		(min_thickness 0.25)
		(keepout
			(tracks not_allowed)
			(vias allowed)
			(pads allowed)
			(copperpour not_allowed)
			(footprints allowed)
		)
		(placement
			(enabled no)
			(sheetname "")
		)
		(fill
			(thermal_gap 0.5)
			(thermal_bridge_width 0.5)
			(island_removal_mode 0)
		)
		(polygon
			(pts
				(arc
					(start 150.241762 -438.760616)
					(mid 150.26408 -438.814498)
					(end 150.317962 -438.836816)
				)
				(arc
					(start 151.257762 -438.836816)
					(mid 151.311644 -438.814498)
					(end 151.333962 -438.760616)
				)
				(arc
					(start 151.333962 -436.219092)
					(mid 151.311644 -436.16521)
					(end 151.257762 -436.142892)
				)
				(arc
					(start 150.317962 -436.142892)
					(mid 150.26408 -436.16521)
					(end 150.241762 -436.219092)
				)
				(arc
					(start 150.241762 -436.946548)
					(mid 150.243761 -436.963889)
					(end 150.249636 -436.98033)
				)
				(arc
					(start 150.483062 -437.45658)
					(mid 150.490845 -437.490108)
					(end 150.483062 -437.523636)
				)
				(arc
					(start 150.249636 -437.999886)
					(mid 150.243741 -438.016322)
					(end 150.241762 -438.033668)
				)
			)
		)
	)
	(zone
		(layer "In14.Cu")
		(hatch none 0.5)
		(connect_pads
			(clearance 0)
		)
		(min_thickness 0.25)
		(keepout
			(tracks not_allowed)
			(vias allowed)
			(pads allowed)
			(copperpour not_allowed)
			(footprints allowed)
		)
		(placement
			(enabled no)
			(sheetname "")
		)
		(fill
			(thermal_gap 0.5)
			(thermal_bridge_width 0.5)
			(island_removal_mode 0)
		)
		(polygon
			(pts
				(arc
					(start 127.241808 -436.160672)
					(mid 127.264126 -436.214554)
					(end 127.318008 -436.236872)
				)
				(arc
					(start 128.257808 -436.236872)
					(mid 128.31169 -436.214554)
					(end 128.334008 -436.160672)
				)
				(arc
					(start 128.334008 -433.619148)
					(mid 128.31169 -433.565266)
					(end 128.257808 -433.542948)
				)
				(arc
					(start 127.318008 -433.542948)
					(mid 127.264126 -433.565266)
					(end 127.241808 -433.619148)
				)
				(arc
					(start 127.241808 -434.346604)
					(mid 127.243807 -434.363945)
					(end 127.249682 -434.380386)
				)
				(arc
					(start 127.483108 -434.856636)
					(mid 127.490891 -434.890164)
					(end 127.483108 -434.923692)
				)
				(arc
					(start 127.249682 -435.399942)
					(mid 127.243787 -435.416378)
					(end 127.241808 -435.433724)
				)
			)
		)
	)
	(zone
		(layer "In14.Cu")
		(hatch none 0.5)
		(connect_pads
			(clearance 0)
		)
		(min_thickness 0.25)
		(keepout
			(tracks not_allowed)
			(vias allowed)
			(pads allowed)
			(copperpour not_allowed)
			(footprints allowed)
		)
		(placement
			(enabled no)
			(sheetname "")
		)
		(fill
			(thermal_gap 0.5)
			(thermal_bridge_width 0.5)
			(island_removal_mode 0)
		)
		(polygon
			(pts
				(arc
					(start 144.242028 -436.160672)
					(mid 144.264346 -436.214554)
					(end 144.318228 -436.236872)
				)
				(arc
					(start 145.258028 -436.236872)
					(mid 145.31191 -436.214554)
					(end 145.334228 -436.160672)
				)
				(arc
					(start 145.334228 -433.619148)
					(mid 145.31191 -433.565266)
					(end 145.258028 -433.542948)
				)
				(arc
					(start 144.318228 -433.542948)
					(mid 144.264346 -433.565266)
					(end 144.242028 -433.619148)
				)
				(arc
					(start 144.242028 -434.346604)
					(mid 144.244027 -434.363945)
					(end 144.249902 -434.380386)
				)
				(arc
					(start 144.483328 -434.856636)
					(mid 144.491111 -434.890164)
					(end 144.483328 -434.923692)
				)
				(arc
					(start 144.249902 -435.399942)
					(mid 144.244007 -435.416378)
					(end 144.242028 -435.433724)
				)
			)
		)
	)
	(zone
		(layer "In14.Cu")
		(hatch none 0.5)
		(connect_pads
			(clearance 0)
		)
		(min_thickness 0.25)
		(keepout
			(tracks not_allowed)
			(vias allowed)
			(pads allowed)
			(copperpour not_allowed)
			(footprints allowed)
		)
		(placement
			(enabled no)
			(sheetname "")
		)
		(fill
			(thermal_gap 0.5)
			(thermal_bridge_width 0.5)
			(island_removal_mode 0)
		)
		(polygon
			(pts
				(arc
					(start 81.141824 -436.160672)
					(mid 81.164142 -436.214554)
					(end 81.218024 -436.236872)
				)
				(arc
					(start 82.157824 -436.236872)
					(mid 82.211706 -436.214554)
					(end 82.234024 -436.160672)
				)
				(arc
					(start 82.234024 -433.619148)
					(mid 82.211706 -433.565266)
					(end 82.157824 -433.542948)
				)
				(arc
					(start 81.218024 -433.542948)
					(mid 81.164142 -433.565266)
					(end 81.141824 -433.619148)
				)
				(arc
					(start 81.141824 -434.346604)
					(mid 81.143823 -434.363945)
					(end 81.149698 -434.380386)
				)
				(arc
					(start 81.383124 -434.856636)
					(mid 81.390907 -434.890164)
					(end 81.383124 -434.923692)
				)
				(arc
					(start 81.149698 -435.399942)
					(mid 81.143803 -435.416378)
					(end 81.141824 -435.433724)
				)
			)
		)
	)
	(zone
		(layer "In14.Cu")
		(hatch none 0.5)
		(connect_pads
			(clearance 0)
		)
		(min_thickness 0.25)
		(keepout
			(tracks not_allowed)
			(vias allowed)
			(pads allowed)
			(copperpour not_allowed)
			(footprints allowed)
		)
		(placement
			(enabled no)
			(sheetname "")
		)
		(fill
			(thermal_gap 0.5)
			(thermal_bridge_width 0.5)
			(island_removal_mode 0)
		)
		(polygon
			(pts
				(arc
					(start 75.141836 -438.760616)
					(mid 75.164154 -438.814498)
					(end 75.218036 -438.836816)
				)
				(arc
					(start 76.157836 -438.836816)
					(mid 76.211718 -438.814498)
					(end 76.234036 -438.760616)
				)
				(arc
					(start 76.234036 -436.219092)
					(mid 76.211718 -436.16521)
					(end 76.157836 -436.142892)
				)
				(arc
					(start 75.218036 -436.142892)
					(mid 75.164154 -436.16521)
					(end 75.141836 -436.219092)
				)
				(arc
					(start 75.141836 -436.946548)
					(mid 75.143835 -436.963889)
					(end 75.14971 -436.98033)
				)
				(arc
					(start 75.383136 -437.45658)
					(mid 75.390919 -437.490108)
					(end 75.383136 -437.523636)
				)
				(arc
					(start 75.14971 -437.999886)
					(mid 75.143815 -438.016322)
					(end 75.141836 -438.033668)
				)
			)
		)
	)
	(zone
		(layer "In14.Cu")
		(hatch none 0.5)
		(connect_pads
			(clearance 0)
		)
		(min_thickness 0.25)
		(keepout
			(tracks not_allowed)
			(vias allowed)
			(pads allowed)
			(copperpour not_allowed)
			(footprints allowed)
		)
		(placement
			(enabled no)
			(sheetname "")
		)
		(fill
			(thermal_gap 0.5)
			(thermal_bridge_width 0.5)
			(island_removal_mode 0)
		)
		(polygon
			(pts
				(arc
					(start 343.141808 -435.160674)
					(mid 343.164126 -435.214556)
					(end 343.218008 -435.236874)
				)
				(arc
					(start 344.157808 -435.236874)
					(mid 344.21169 -435.214556)
					(end 344.234008 -435.160674)
				)
				(arc
					(start 344.234008 -432.61915)
					(mid 344.21169 -432.565268)
					(end 344.157808 -432.54295)
				)
				(arc
					(start 343.218008 -432.54295)
					(mid 343.164126 -432.565268)
					(end 343.141808 -432.61915)
				)
				(arc
					(start 343.141808 -433.346606)
					(mid 343.143807 -433.363947)
					(end 343.149682 -433.380388)
				)
				(arc
					(start 343.383108 -433.856638)
					(mid 343.390891 -433.890166)
					(end 343.383108 -433.923694)
				)
				(arc
					(start 343.149682 -434.399944)
					(mid 343.143787 -434.41638)
					(end 343.141808 -434.433726)
				)
			)
		)
	)
	(zone
		(layer "In14.Cu")
		(hatch none 0.5)
		(connect_pads
			(clearance 0)
		)
		(min_thickness 0.25)
		(keepout
			(tracks not_allowed)
			(vias allowed)
			(pads allowed)
			(copperpour not_allowed)
			(footprints allowed)
		)
		(placement
			(enabled no)
			(sheetname "")
		)
		(fill
			(thermal_gap 0.5)
			(thermal_bridge_width 0.5)
			(island_removal_mode 0)
		)
		(polygon
			(pts
				(arc
					(start 328.141584 -436.160672)
					(mid 328.163902 -436.214554)
					(end 328.217784 -436.236872)
				)
				(arc
					(start 329.157584 -436.236872)
					(mid 329.211466 -436.214554)
					(end 329.233784 -436.160672)
				)
				(arc
					(start 329.233784 -433.619148)
					(mid 329.211466 -433.565266)
					(end 329.157584 -433.542948)
				)
				(arc
					(start 328.217784 -433.542948)
					(mid 328.163902 -433.565266)
					(end 328.141584 -433.619148)
				)
				(arc
					(start 328.141584 -434.346604)
					(mid 328.143583 -434.363945)
					(end 328.149458 -434.380386)
				)
				(arc
					(start 328.382884 -434.856636)
					(mid 328.390667 -434.890164)
					(end 328.382884 -434.923692)
				)
				(arc
					(start 328.149458 -435.399942)
					(mid 328.143563 -435.416378)
					(end 328.141584 -435.433724)
				)
			)
		)
	)
	(zone
		(layer "In14.Cu")
		(hatch none 0.5)
		(connect_pads
			(clearance 0)
		)
		(min_thickness 0.25)
		(keepout
			(tracks not_allowed)
			(vias allowed)
			(pads allowed)
			(copperpour not_allowed)
			(footprints allowed)
		)
		(placement
			(enabled no)
			(sheetname "")
		)
		(fill
			(thermal_gap 0.5)
			(thermal_bridge_width 0.5)
			(island_removal_mode 0)
		)
		(polygon
			(pts
				(arc
					(start 142.241778 -438.760616)
					(mid 142.264096 -438.814498)
					(end 142.317978 -438.836816)
				)
				(arc
					(start 143.257778 -438.836816)
					(mid 143.31166 -438.814498)
					(end 143.333978 -438.760616)
				)
				(arc
					(start 143.333978 -436.219092)
					(mid 143.31166 -436.16521)
					(end 143.257778 -436.142892)
				)
				(arc
					(start 142.317978 -436.142892)
					(mid 142.264096 -436.16521)
					(end 142.241778 -436.219092)
				)
				(arc
					(start 142.241778 -436.946548)
					(mid 142.243777 -436.963889)
					(end 142.249652 -436.98033)
				)
				(arc
					(start 142.483078 -437.45658)
					(mid 142.490861 -437.490108)
					(end 142.483078 -437.523636)
				)
				(arc
					(start 142.249652 -437.999886)
					(mid 142.243757 -438.016322)
					(end 142.241778 -438.033668)
				)
			)
		)
	)
	(zone
		(layer "In14.Cu")
		(hatch none 0.5)
		(connect_pads
			(clearance 0)
		)
		(min_thickness 0.25)
		(keepout
			(tracks not_allowed)
			(vias allowed)
			(pads allowed)
			(copperpour not_allowed)
			(footprints allowed)
		)
		(placement
			(enabled no)
			(sheetname "")
		)
		(fill
			(thermal_gap 0.5)
			(thermal_bridge_width 0.5)
			(island_removal_mode 0)
		)
		(polygon
			(pts
				(arc
					(start 83.14182 -438.760616)
					(mid 83.164138 -438.814498)
					(end 83.21802 -438.836816)
				)
				(arc
					(start 84.15782 -438.836816)
					(mid 84.211702 -438.814498)
					(end 84.23402 -438.760616)
				)
				(arc
					(start 84.23402 -436.219092)
					(mid 84.211702 -436.16521)
					(end 84.15782 -436.142892)
				)
				(arc
					(start 83.21802 -436.142892)
					(mid 83.164138 -436.16521)
					(end 83.14182 -436.219092)
				)
				(arc
					(start 83.14182 -436.946548)
					(mid 83.143819 -436.963889)
					(end 83.149694 -436.98033)
				)
				(arc
					(start 83.38312 -437.45658)
					(mid 83.390903 -437.490108)
					(end 83.38312 -437.523636)
				)
				(arc
					(start 83.149694 -437.999886)
					(mid 83.143799 -438.016322)
					(end 83.14182 -438.033668)
				)
			)
		)
	)
	(zone
		(layer "In14.Cu")
		(hatch none 0.5)
		(connect_pads
			(clearance 0)
		)
		(min_thickness 0.25)
		(keepout
			(tracks not_allowed)
			(vias allowed)
			(pads allowed)
			(copperpour not_allowed)
			(footprints allowed)
		)
		(placement
			(enabled no)
			(sheetname "")
		)
		(fill
			(thermal_gap 0.5)
			(thermal_bridge_width 0.5)
			(island_removal_mode 0)
		)
		(polygon
			(pts
				(arc
					(start 391.241788 -436.160672)
					(mid 391.264106 -436.214554)
					(end 391.317988 -436.236872)
				)
				(arc
					(start 392.257788 -436.236872)
					(mid 392.31167 -436.214554)
					(end 392.333988 -436.160672)
				)
				(arc
					(start 392.333988 -433.619148)
					(mid 392.31167 -433.565266)
					(end 392.257788 -433.542948)
				)
				(arc
					(start 391.317988 -433.542948)
					(mid 391.264106 -433.565266)
					(end 391.241788 -433.619148)
				)
				(arc
					(start 391.241788 -434.346604)
					(mid 391.243787 -434.363945)
					(end 391.249662 -434.380386)
				)
				(arc
					(start 391.483088 -434.856636)
					(mid 391.490871 -434.890164)
					(end 391.483088 -434.923692)
				)
				(arc
					(start 391.249662 -435.399942)
					(mid 391.243767 -435.416378)
					(end 391.241788 -435.433724)
				)
			)
		)
	)
	(zone
		(layer "In14.Cu")
		(hatch none 0.5)
		(connect_pads
			(clearance 0)
		)
		(min_thickness 0.25)
		(keepout
			(tracks not_allowed)
			(vias allowed)
			(pads allowed)
			(copperpour not_allowed)
			(footprints allowed)
		)
		(placement
			(enabled no)
			(sheetname "")
		)
		(fill
			(thermal_gap 0.5)
			(thermal_bridge_width 0.5)
			(island_removal_mode 0)
		)
		(polygon
			(pts
				(arc
					(start 322.14185 -438.760616)
					(mid 322.164168 -438.814498)
					(end 322.21805 -438.836816)
				)
				(arc
					(start 323.15785 -438.836816)
					(mid 323.211732 -438.814498)
					(end 323.23405 -438.760616)
				)
				(arc
					(start 323.23405 -436.219092)
					(mid 323.211732 -436.16521)
					(end 323.15785 -436.142892)
				)
				(arc
					(start 322.21805 -436.142892)
					(mid 322.164168 -436.16521)
					(end 322.14185 -436.219092)
				)
				(arc
					(start 322.14185 -436.946548)
					(mid 322.143849 -436.963889)
					(end 322.149724 -436.98033)
				)
				(arc
					(start 322.38315 -437.45658)
					(mid 322.390933 -437.490108)
					(end 322.38315 -437.523636)
				)
				(arc
					(start 322.149724 -437.999886)
					(mid 322.143829 -438.016322)
					(end 322.14185 -438.033668)
				)
			)
		)
	)
	(zone
		(layer "In14.Cu")
		(hatch none 0.5)
		(connect_pads
			(clearance 0)
		)
		(min_thickness 0.25)
		(keepout
			(tracks not_allowed)
			(vias allowed)
			(pads allowed)
			(copperpour not_allowed)
			(footprints allowed)
		)
		(placement
			(enabled no)
			(sheetname "")
		)
		(fill
			(thermal_gap 0.5)
			(thermal_bridge_width 0.5)
			(island_removal_mode 0)
		)
		(polygon
			(pts
				(arc
					(start 406.242012 -435.160674)
					(mid 406.26433 -435.214556)
					(end 406.318212 -435.236874)
				)
				(arc
					(start 407.258012 -435.236874)
					(mid 407.311894 -435.214556)
					(end 407.334212 -435.160674)
				)
				(arc
					(start 407.334212 -432.61915)
					(mid 407.311894 -432.565268)
					(end 407.258012 -432.54295)
				)
				(arc
					(start 406.318212 -432.54295)
					(mid 406.26433 -432.565268)
					(end 406.242012 -432.61915)
				)
				(arc
					(start 406.242012 -433.346606)
					(mid 406.244011 -433.363947)
					(end 406.249886 -433.380388)
				)
				(arc
					(start 406.483312 -433.856638)
					(mid 406.491095 -433.890166)
					(end 406.483312 -433.923694)
				)
				(arc
					(start 406.249886 -434.399944)
					(mid 406.243991 -434.41638)
					(end 406.242012 -434.433726)
				)
			)
		)
	)
	(zone
		(layer "In14.Cu")
		(hatch none 0.5)
		(connect_pads
			(clearance 0)
		)
		(min_thickness 0.25)
		(keepout
			(tracks not_allowed)
			(vias allowed)
			(pads allowed)
			(copperpour not_allowed)
			(footprints allowed)
		)
		(placement
			(enabled no)
			(sheetname "")
		)
		(fill
			(thermal_gap 0.5)
			(thermal_bridge_width 0.5)
			(island_removal_mode 0)
		)
		(polygon
			(pts
				(arc
					(start 389.241792 -435.160674)
					(mid 389.26411 -435.214556)
					(end 389.317992 -435.236874)
				)
				(arc
					(start 390.257792 -435.236874)
					(mid 390.311674 -435.214556)
					(end 390.333992 -435.160674)
				)
				(arc
					(start 390.333992 -432.61915)
					(mid 390.311674 -432.565268)
					(end 390.257792 -432.54295)
				)
				(arc
					(start 389.317992 -432.54295)
					(mid 389.26411 -432.565268)
					(end 389.241792 -432.61915)
				)
				(arc
					(start 389.241792 -433.346606)
					(mid 389.243791 -433.363947)
					(end 389.249666 -433.380388)
				)
				(arc
					(start 389.483092 -433.856638)
					(mid 389.490875 -433.890166)
					(end 389.483092 -433.923694)
				)
				(arc
					(start 389.249666 -434.399944)
					(mid 389.243771 -434.41638)
					(end 389.241792 -434.433726)
				)
			)
		)
	)
	(zone
		(layer "In14.Cu")
		(hatch none 0.5)
		(connect_pads
			(clearance 0)
		)
		(min_thickness 0.25)
		(keepout
			(tracks not_allowed)
			(vias allowed)
			(pads allowed)
			(copperpour not_allowed)
			(footprints allowed)
		)
		(placement
			(enabled no)
			(sheetname "")
		)
		(fill
			(thermal_gap 0.5)
			(thermal_bridge_width 0.5)
			(island_removal_mode 0)
		)
		(polygon
			(pts
				(arc
					(start 154.242008 -435.160674)
					(mid 154.264326 -435.214556)
					(end 154.318208 -435.236874)
				)
				(arc
					(start 155.258008 -435.236874)
					(mid 155.31189 -435.214556)
					(end 155.334208 -435.160674)
				)
				(arc
					(start 155.334208 -432.61915)
					(mid 155.31189 -432.565268)
					(end 155.258008 -432.54295)
				)
				(arc
					(start 154.318208 -432.54295)
					(mid 154.264326 -432.565268)
					(end 154.242008 -432.61915)
				)
				(arc
					(start 154.242008 -433.346606)
					(mid 154.244007 -433.363947)
					(end 154.249882 -433.380388)
				)
				(arc
					(start 154.483308 -433.856638)
					(mid 154.491091 -433.890166)
					(end 154.483308 -433.923694)
				)
				(arc
					(start 154.249882 -434.399944)
					(mid 154.243987 -434.41638)
					(end 154.242008 -434.433726)
				)
			)
		)
	)
	(zone
		(layer "In14.Cu")
		(hatch none 0.5)
		(connect_pads
			(clearance 0)
		)
		(min_thickness 0.25)
		(keepout
			(tracks not_allowed)
			(vias allowed)
			(pads allowed)
			(copperpour not_allowed)
			(footprints allowed)
		)
		(placement
			(enabled no)
			(sheetname "")
		)
		(fill
			(thermal_gap 0.5)
			(thermal_bridge_width 0.5)
			(island_removal_mode 0)
		)
		(polygon
			(pts
				(arc
					(start 89.141808 -436.160672)
					(mid 89.164126 -436.214554)
					(end 89.218008 -436.236872)
				)
				(arc
					(start 90.157808 -436.236872)
					(mid 90.21169 -436.214554)
					(end 90.234008 -436.160672)
				)
				(arc
					(start 90.234008 -433.619148)
					(mid 90.21169 -433.565266)
					(end 90.157808 -433.542948)
				)
				(arc
					(start 89.218008 -433.542948)
					(mid 89.164126 -433.565266)
					(end 89.141808 -433.619148)
				)
				(arc
					(start 89.141808 -434.346604)
					(mid 89.143807 -434.363945)
					(end 89.149682 -434.380386)
				)
				(arc
					(start 89.383108 -434.856636)
					(mid 89.390891 -434.890164)
					(end 89.383108 -434.923692)
				)
				(arc
					(start 89.149682 -435.399942)
					(mid 89.143787 -435.416378)
					(end 89.141808 -435.433724)
				)
			)
		)
	)
	(zone
		(layer "In14.Cu")
		(hatch none 0.5)
		(connect_pads
			(clearance 0)
		)
		(min_thickness 0.25)
		(keepout
			(tracks not_allowed)
			(vias allowed)
			(pads allowed)
			(copperpour not_allowed)
			(footprints allowed)
		)
		(placement
			(enabled no)
			(sheetname "")
		)
		(fill
			(thermal_gap 0.5)
			(thermal_bridge_width 0.5)
			(island_removal_mode 0)
		)
		(polygon
			(pts
				(arc
					(start 68.14185 -436.160672)
					(mid 68.164168 -436.214554)
					(end 68.21805 -436.236872)
				)
				(arc
					(start 69.15785 -436.236872)
					(mid 69.211732 -436.214554)
					(end 69.23405 -436.160672)
				)
				(arc
					(start 69.23405 -433.619148)
					(mid 69.211732 -433.565266)
					(end 69.15785 -433.542948)
				)
				(arc
					(start 68.21805 -433.542948)
					(mid 68.164168 -433.565266)
					(end 68.14185 -433.619148)
				)
				(arc
					(start 68.14185 -434.346604)
					(mid 68.143849 -434.363945)
					(end 68.149724 -434.380386)
				)
				(arc
					(start 68.38315 -434.856636)
					(mid 68.390933 -434.890164)
					(end 68.38315 -434.923692)
				)
				(arc
					(start 68.149724 -435.399942)
					(mid 68.143829 -435.416378)
					(end 68.14185 -435.433724)
				)
			)
		)
	)
	(zone
		(layer "In14.Cu")
		(hatch none 0.5)
		(connect_pads
			(clearance 0)
		)
		(min_thickness 0.25)
		(keepout
			(tracks not_allowed)
			(vias allowed)
			(pads allowed)
			(copperpour not_allowed)
			(footprints allowed)
		)
		(placement
			(enabled no)
			(sheetname "")
		)
		(fill
			(thermal_gap 0.5)
			(thermal_bridge_width 0.5)
			(island_removal_mode 0)
		)
		(polygon
			(pts
				(xy 198.698358 -402.699982) (xy 198.698358 -401.11807) (xy 200.380346 -401.11807) (xy 200.380346 -402.699982)
			)
		)
	)
	(zone
		(layer "In14.Cu")
		(hatch none 0.5)
		(connect_pads
			(clearance 0)
		)
		(min_thickness 0.25)
		(keepout
			(tracks not_allowed)
			(vias allowed)
			(pads allowed)
			(copperpour not_allowed)
			(footprints allowed)
		)
		(placement
			(enabled no)
			(sheetname "")
		)
		(fill
			(thermal_gap 0.5)
			(thermal_bridge_width 0.5)
			(island_removal_mode 0)
		)
		(polygon
			(pts
				(arc
					(start 66.141854 -435.160674)
					(mid 66.164172 -435.214556)
					(end 66.218054 -435.236874)
				)
				(arc
					(start 67.157854 -435.236874)
					(mid 67.211736 -435.214556)
					(end 67.234054 -435.160674)
				)
				(arc
					(start 67.234054 -432.61915)
					(mid 67.211736 -432.565268)
					(end 67.157854 -432.54295)
				)
				(arc
					(start 66.218054 -432.54295)
					(mid 66.164172 -432.565268)
					(end 66.141854 -432.61915)
				)
				(arc
					(start 66.141854 -433.346606)
					(mid 66.143853 -433.363947)
					(end 66.149728 -433.380388)
				)
				(arc
					(start 66.383154 -433.856638)
					(mid 66.390937 -433.890166)
					(end 66.383154 -433.923694)
				)
				(arc
					(start 66.149728 -434.399944)
					(mid 66.143833 -434.41638)
					(end 66.141854 -434.433726)
				)
			)
		)
	)
	(zone
		(layer "In14.Cu")
		(hatch none 0.5)
		(connect_pads
			(clearance 0)
		)
		(min_thickness 0.25)
		(keepout
			(tracks not_allowed)
			(vias allowed)
			(pads allowed)
			(copperpour not_allowed)
			(footprints allowed)
		)
		(placement
			(enabled no)
			(sheetname "")
		)
		(fill
			(thermal_gap 0.5)
			(thermal_bridge_width 0.5)
			(island_removal_mode 0)
		)
		(polygon
			(pts
				(arc
					(start 328.141838 -439.760614)
					(mid 328.164156 -439.814496)
					(end 328.218038 -439.836814)
				)
				(arc
					(start 329.157838 -439.836814)
					(mid 329.21172 -439.814496)
					(end 329.234038 -439.760614)
				)
				(arc
					(start 329.234038 -437.21909)
					(mid 329.21172 -437.165208)
					(end 329.157838 -437.14289)
				)
				(arc
					(start 328.218038 -437.14289)
					(mid 328.164156 -437.165208)
					(end 328.141838 -437.21909)
				)
				(arc
					(start 328.141838 -437.946546)
					(mid 328.143837 -437.963887)
					(end 328.149712 -437.980328)
				)
				(arc
					(start 328.383138 -438.456578)
					(mid 328.390921 -438.490106)
					(end 328.383138 -438.523634)
				)
				(arc
					(start 328.149712 -438.999884)
					(mid 328.143817 -439.01632)
					(end 328.141838 -439.033666)
				)
			)
		)
	)
	(zone
		(layer "In14.Cu")
		(hatch none 0.5)
		(connect_pads
			(clearance 0)
		)
		(min_thickness 0.25)
		(keepout
			(tracks not_allowed)
			(vias allowed)
			(pads allowed)
			(copperpour not_allowed)
			(footprints allowed)
		)
		(placement
			(enabled no)
			(sheetname "")
		)
		(fill
			(thermal_gap 0.5)
			(thermal_bridge_width 0.5)
			(island_removal_mode 0)
		)
		(polygon
			(pts
				(arc
					(start 89.141808 -439.760614)
					(mid 89.164126 -439.814496)
					(end 89.218008 -439.836814)
				)
				(arc
					(start 90.157808 -439.836814)
					(mid 90.21169 -439.814496)
					(end 90.234008 -439.760614)
				)
				(arc
					(start 90.234008 -437.21909)
					(mid 90.21169 -437.165208)
					(end 90.157808 -437.14289)
				)
				(arc
					(start 89.218008 -437.14289)
					(mid 89.164126 -437.165208)
					(end 89.141808 -437.21909)
				)
				(arc
					(start 89.141808 -437.946546)
					(mid 89.143807 -437.963887)
					(end 89.149682 -437.980328)
				)
				(arc
					(start 89.383108 -438.456578)
					(mid 89.390891 -438.490106)
					(end 89.383108 -438.523634)
				)
				(arc
					(start 89.149682 -438.999884)
					(mid 89.143787 -439.01632)
					(end 89.141808 -439.033666)
				)
			)
		)
	)
	(zone
		(layer "In14.Cu")
		(hatch none 0.5)
		(connect_pads
			(clearance 0)
		)
		(min_thickness 0.25)
		(keepout
			(tracks not_allowed)
			(vias allowed)
			(pads allowed)
			(copperpour not_allowed)
			(footprints allowed)
		)
		(placement
			(enabled no)
			(sheetname "")
		)
		(fill
			(thermal_gap 0.5)
			(thermal_bridge_width 0.5)
			(island_removal_mode 0)
		)
		(polygon
			(pts
				(arc
					(start 322.141596 -435.160674)
					(mid 322.163914 -435.214556)
					(end 322.217796 -435.236874)
				)
				(arc
					(start 323.157596 -435.236874)
					(mid 323.211478 -435.214556)
					(end 323.233796 -435.160674)
				)
				(arc
					(start 323.233796 -432.61915)
					(mid 323.211478 -432.565268)
					(end 323.157596 -432.54295)
				)
				(arc
					(start 322.217796 -432.54295)
					(mid 322.163914 -432.565268)
					(end 322.141596 -432.61915)
				)
				(arc
					(start 322.141596 -433.346606)
					(mid 322.143595 -433.363947)
					(end 322.14947 -433.380388)
				)
				(arc
					(start 322.382896 -433.856638)
					(mid 322.390679 -433.890166)
					(end 322.382896 -433.923694)
				)
				(arc
					(start 322.14947 -434.399944)
					(mid 322.143575 -434.41638)
					(end 322.141596 -434.433726)
				)
			)
		)
	)
	(zone
		(layer "In14.Cu")
		(hatch none 0.5)
		(connect_pads
			(clearance 0)
		)
		(min_thickness 0.25)
		(keepout
			(tracks not_allowed)
			(vias allowed)
			(pads allowed)
			(copperpour not_allowed)
			(footprints allowed)
		)
		(placement
			(enabled no)
			(sheetname "")
		)
		(fill
			(thermal_gap 0.5)
			(thermal_bridge_width 0.5)
			(island_removal_mode 0)
		)
		(polygon
			(pts
				(arc
					(start 318.141604 -435.160674)
					(mid 318.163922 -435.214556)
					(end 318.217804 -435.236874)
				)
				(arc
					(start 319.157604 -435.236874)
					(mid 319.211486 -435.214556)
					(end 319.233804 -435.160674)
				)
				(arc
					(start 319.233804 -432.61915)
					(mid 319.211486 -432.565268)
					(end 319.157604 -432.54295)
				)
				(arc
					(start 318.217804 -432.54295)
					(mid 318.163922 -432.565268)
					(end 318.141604 -432.61915)
				)
				(arc
					(start 318.141604 -433.346606)
					(mid 318.143603 -433.363947)
					(end 318.149478 -433.380388)
				)
				(arc
					(start 318.382904 -433.856638)
					(mid 318.390687 -433.890166)
					(end 318.382904 -433.923694)
				)
				(arc
					(start 318.149478 -434.399944)
					(mid 318.143583 -434.41638)
					(end 318.141604 -434.433726)
				)
			)
		)
	)
	(zone
		(layer "In14.Cu")
		(hatch none 0.5)
		(connect_pads
			(clearance 0)
		)
		(min_thickness 0.25)
		(keepout
			(tracks not_allowed)
			(vias allowed)
			(pads allowed)
			(copperpour not_allowed)
			(footprints allowed)
		)
		(placement
			(enabled no)
			(sheetname "")
		)
		(fill
			(thermal_gap 0.5)
			(thermal_bridge_width 0.5)
			(island_removal_mode 0)
		)
		(polygon
			(pts
				(arc
					(start 58.14187 -435.160674)
					(mid 58.164188 -435.214556)
					(end 58.21807 -435.236874)
				)
				(arc
					(start 59.15787 -435.236874)
					(mid 59.211752 -435.214556)
					(end 59.23407 -435.160674)
				)
				(arc
					(start 59.23407 -432.61915)
					(mid 59.211752 -432.565268)
					(end 59.15787 -432.54295)
				)
				(arc
					(start 58.21807 -432.54295)
					(mid 58.164188 -432.565268)
					(end 58.14187 -432.61915)
				)
				(arc
					(start 58.14187 -433.346606)
					(mid 58.143869 -433.363947)
					(end 58.149744 -433.380388)
				)
				(arc
					(start 58.38317 -433.856638)
					(mid 58.390953 -433.890166)
					(end 58.38317 -433.923694)
				)
				(arc
					(start 58.149744 -434.399944)
					(mid 58.143849 -434.41638)
					(end 58.14187 -434.433726)
				)
			)
		)
	)
	(zone
		(layer "In14.Cu")
		(hatch none 0.5)
		(connect_pads
			(clearance 0)
		)
		(min_thickness 0.25)
		(keepout
			(tracks not_allowed)
			(vias allowed)
			(pads allowed)
			(copperpour not_allowed)
			(footprints allowed)
		)
		(placement
			(enabled no)
			(sheetname "")
		)
		(fill
			(thermal_gap 0.5)
			(thermal_bridge_width 0.5)
			(island_removal_mode 0)
		)
		(polygon
			(pts
				(arc
					(start 60.141866 -436.160672)
					(mid 60.164184 -436.214554)
					(end 60.218066 -436.236872)
				)
				(arc
					(start 61.157866 -436.236872)
					(mid 61.211748 -436.214554)
					(end 61.234066 -436.160672)
				)
				(arc
					(start 61.234066 -433.619148)
					(mid 61.211748 -433.565266)
					(end 61.157866 -433.542948)
				)
				(arc
					(start 60.218066 -433.542948)
					(mid 60.164184 -433.565266)
					(end 60.141866 -433.619148)
				)
				(arc
					(start 60.141866 -434.346604)
					(mid 60.143865 -434.363945)
					(end 60.14974 -434.380386)
				)
				(arc
					(start 60.383166 -434.856636)
					(mid 60.390949 -434.890164)
					(end 60.383166 -434.923692)
				)
				(arc
					(start 60.14974 -435.399942)
					(mid 60.143845 -435.416378)
					(end 60.141866 -435.433724)
				)
			)
		)
	)
	(zone
		(layer "In14.Cu")
		(hatch none 0.5)
		(connect_pads
			(clearance 0)
		)
		(min_thickness 0.25)
		(keepout
			(tracks not_allowed)
			(vias allowed)
			(pads allowed)
			(copperpour not_allowed)
			(footprints allowed)
		)
		(placement
			(enabled no)
			(sheetname "")
		)
		(fill
			(thermal_gap 0.5)
			(thermal_bridge_width 0.5)
			(island_removal_mode 0)
		)
		(polygon
			(pts
				(arc
					(start 320.1416 -436.160672)
					(mid 320.163918 -436.214554)
					(end 320.2178 -436.236872)
				)
				(arc
					(start 321.1576 -436.236872)
					(mid 321.211482 -436.214554)
					(end 321.2338 -436.160672)
				)
				(arc
					(start 321.2338 -433.619148)
					(mid 321.211482 -433.565266)
					(end 321.1576 -433.542948)
				)
				(arc
					(start 320.2178 -433.542948)
					(mid 320.163918 -433.565266)
					(end 320.1416 -433.619148)
				)
				(arc
					(start 320.1416 -434.346604)
					(mid 320.143599 -434.363945)
					(end 320.149474 -434.380386)
				)
				(arc
					(start 320.3829 -434.856636)
					(mid 320.390683 -434.890164)
					(end 320.3829 -434.923692)
				)
				(arc
					(start 320.149474 -435.399942)
					(mid 320.143579 -435.416378)
					(end 320.1416 -435.433724)
				)
			)
		)
	)
	(zone
		(layer "In14.Cu")
		(hatch none 0.5)
		(connect_pads
			(clearance 0)
		)
		(min_thickness 0.25)
		(keepout
			(tracks not_allowed)
			(vias allowed)
			(pads allowed)
			(copperpour not_allowed)
			(footprints allowed)
		)
		(placement
			(enabled no)
			(sheetname "")
		)
		(fill
			(thermal_gap 0.5)
			(thermal_bridge_width 0.5)
			(island_removal_mode 0)
		)
		(polygon
			(pts
				(arc
					(start 152.241758 -439.760614)
					(mid 152.264076 -439.814496)
					(end 152.317958 -439.836814)
				)
				(arc
					(start 153.257758 -439.836814)
					(mid 153.31164 -439.814496)
					(end 153.333958 -439.760614)
				)
				(arc
					(start 153.333958 -437.21909)
					(mid 153.31164 -437.165208)
					(end 153.257758 -437.14289)
				)
				(arc
					(start 152.317958 -437.14289)
					(mid 152.264076 -437.165208)
					(end 152.241758 -437.21909)
				)
				(arc
					(start 152.241758 -437.946546)
					(mid 152.243757 -437.963887)
					(end 152.249632 -437.980328)
				)
				(arc
					(start 152.483058 -438.456578)
					(mid 152.490841 -438.490106)
					(end 152.483058 -438.523634)
				)
				(arc
					(start 152.249632 -438.999884)
					(mid 152.243737 -439.01632)
					(end 152.241758 -439.033666)
				)
			)
		)
	)
	(zone
		(layer "In14.Cu")
		(hatch none 0.5)
		(connect_pads
			(clearance 0)
		)
		(min_thickness 0.25)
		(keepout
			(tracks not_allowed)
			(vias allowed)
			(pads allowed)
			(copperpour not_allowed)
			(footprints allowed)
		)
		(placement
			(enabled no)
			(sheetname "")
		)
		(fill
			(thermal_gap 0.5)
			(thermal_bridge_width 0.5)
			(island_removal_mode 0)
		)
		(polygon
			(pts
				(arc
					(start 70.141846 -435.160674)
					(mid 70.164164 -435.214556)
					(end 70.218046 -435.236874)
				)
				(arc
					(start 71.157846 -435.236874)
					(mid 71.211728 -435.214556)
					(end 71.234046 -435.160674)
				)
				(arc
					(start 71.234046 -432.61915)
					(mid 71.211728 -432.565268)
					(end 71.157846 -432.54295)
				)
				(arc
					(start 70.218046 -432.54295)
					(mid 70.164164 -432.565268)
					(end 70.141846 -432.61915)
				)
				(arc
					(start 70.141846 -433.346606)
					(mid 70.143845 -433.363947)
					(end 70.14972 -433.380388)
				)
				(arc
					(start 70.383146 -433.856638)
					(mid 70.390929 -433.890166)
					(end 70.383146 -433.923694)
				)
				(arc
					(start 70.14972 -434.399944)
					(mid 70.143825 -434.41638)
					(end 70.141846 -434.433726)
				)
			)
		)
	)
	(zone
		(layer "In14.Cu")
		(hatch none 0.5)
		(connect_pads
			(clearance 0)
		)
		(min_thickness 0.25)
		(keepout
			(tracks not_allowed)
			(vias allowed)
			(pads allowed)
			(copperpour not_allowed)
			(footprints allowed)
		)
		(placement
			(enabled no)
			(sheetname "")
		)
		(fill
			(thermal_gap 0.5)
			(thermal_bridge_width 0.5)
			(island_removal_mode 0)
		)
		(polygon
			(pts
				(arc
					(start 314.141612 -435.160674)
					(mid 314.16393 -435.214556)
					(end 314.217812 -435.236874)
				)
				(arc
					(start 315.157612 -435.236874)
					(mid 315.211494 -435.214556)
					(end 315.233812 -435.160674)
				)
				(arc
					(start 315.233812 -432.61915)
					(mid 315.211494 -432.565268)
					(end 315.157612 -432.54295)
				)
				(arc
					(start 314.217812 -432.54295)
					(mid 314.16393 -432.565268)
					(end 314.141612 -432.61915)
				)
				(arc
					(start 314.141612 -433.346606)
					(mid 314.143611 -433.363947)
					(end 314.149486 -433.380388)
				)
				(arc
					(start 314.382912 -433.856638)
					(mid 314.390695 -433.890166)
					(end 314.382912 -433.923694)
				)
				(arc
					(start 314.149486 -434.399944)
					(mid 314.143591 -434.41638)
					(end 314.141612 -434.433726)
				)
			)
		)
	)
	(zone
		(layer "In14.Cu")
		(hatch none 0.5)
		(connect_pads
			(clearance 0)
		)
		(min_thickness 0.25)
		(keepout
			(tracks not_allowed)
			(vias allowed)
			(pads allowed)
			(copperpour not_allowed)
			(footprints allowed)
		)
		(placement
			(enabled no)
			(sheetname "")
		)
		(fill
			(thermal_gap 0.5)
			(thermal_bridge_width 0.5)
			(island_removal_mode 0)
		)
		(polygon
			(pts
				(arc
					(start 320.141854 -439.760614)
					(mid 320.164172 -439.814496)
					(end 320.218054 -439.836814)
				)
				(arc
					(start 321.157854 -439.836814)
					(mid 321.211736 -439.814496)
					(end 321.234054 -439.760614)
				)
				(arc
					(start 321.234054 -437.21909)
					(mid 321.211736 -437.165208)
					(end 321.157854 -437.14289)
				)
				(arc
					(start 320.218054 -437.14289)
					(mid 320.164172 -437.165208)
					(end 320.141854 -437.21909)
				)
				(arc
					(start 320.141854 -437.946546)
					(mid 320.143853 -437.963887)
					(end 320.149728 -437.980328)
				)
				(arc
					(start 320.383154 -438.456578)
					(mid 320.390937 -438.490106)
					(end 320.383154 -438.523634)
				)
				(arc
					(start 320.149728 -438.999884)
					(mid 320.143833 -439.01632)
					(end 320.141854 -439.033666)
				)
			)
		)
	)
	(zone
		(layer "In14.Cu")
		(hatch none 0.5)
		(connect_pads
			(clearance 0)
		)
		(min_thickness 0.25)
		(keepout
			(tracks not_allowed)
			(vias allowed)
			(pads allowed)
			(copperpour not_allowed)
			(footprints allowed)
		)
		(placement
			(enabled no)
			(sheetname "")
		)
		(fill
			(thermal_gap 0.5)
			(thermal_bridge_width 0.5)
			(island_removal_mode 0)
		)
		(polygon
			(pts
				(arc
					(start 324.141592 -436.160672)
					(mid 324.16391 -436.214554)
					(end 324.217792 -436.236872)
				)
				(arc
					(start 325.157592 -436.236872)
					(mid 325.211474 -436.214554)
					(end 325.233792 -436.160672)
				)
				(arc
					(start 325.233792 -433.619148)
					(mid 325.211474 -433.565266)
					(end 325.157592 -433.542948)
				)
				(arc
					(start 324.217792 -433.542948)
					(mid 324.16391 -433.565266)
					(end 324.141592 -433.619148)
				)
				(arc
					(start 324.141592 -434.346604)
					(mid 324.143591 -434.363945)
					(end 324.149466 -434.380386)
				)
				(arc
					(start 324.382892 -434.856636)
					(mid 324.390675 -434.890164)
					(end 324.382892 -434.923692)
				)
				(arc
					(start 324.149466 -435.399942)
					(mid 324.143571 -435.416378)
					(end 324.141592 -435.433724)
				)
			)
		)
	)
	(zone
		(layer "In14.Cu")
		(hatch none 0.5)
		(connect_pads
			(clearance 0)
		)
		(min_thickness 0.25)
		(keepout
			(tracks not_allowed)
			(vias allowed)
			(pads allowed)
			(copperpour not_allowed)
			(footprints allowed)
		)
		(placement
			(enabled no)
			(sheetname "")
		)
		(fill
			(thermal_gap 0.5)
			(thermal_bridge_width 0.5)
			(island_removal_mode 0)
		)
		(polygon
			(pts
				(arc
					(start 146.24177 -438.760616)
					(mid 146.264088 -438.814498)
					(end 146.31797 -438.836816)
				)
				(arc
					(start 147.25777 -438.836816)
					(mid 147.311652 -438.814498)
					(end 147.33397 -438.760616)
				)
				(arc
					(start 147.33397 -436.219092)
					(mid 147.311652 -436.16521)
					(end 147.25777 -436.142892)
				)
				(arc
					(start 146.31797 -436.142892)
					(mid 146.264088 -436.16521)
					(end 146.24177 -436.219092)
				)
				(arc
					(start 146.24177 -436.946548)
					(mid 146.243769 -436.963889)
					(end 146.249644 -436.98033)
				)
				(arc
					(start 146.48307 -437.45658)
					(mid 146.490853 -437.490108)
					(end 146.48307 -437.523636)
				)
				(arc
					(start 146.249644 -437.999886)
					(mid 146.243749 -438.016322)
					(end 146.24177 -438.033668)
				)
			)
		)
	)
	(zone
		(layer "In14.Cu")
		(hatch none 0.5)
		(connect_pads
			(clearance 0)
		)
		(min_thickness 0.25)
		(keepout
			(tracks not_allowed)
			(vias allowed)
			(pads allowed)
			(copperpour not_allowed)
			(footprints allowed)
		)
		(placement
			(enabled no)
			(sheetname "")
		)
		(fill
			(thermal_gap 0.5)
			(thermal_bridge_width 0.5)
			(island_removal_mode 0)
		)
		(polygon
			(pts
				(arc
					(start 87.141812 -435.160674)
					(mid 87.16413 -435.214556)
					(end 87.218012 -435.236874)
				)
				(arc
					(start 88.157812 -435.236874)
					(mid 88.211694 -435.214556)
					(end 88.234012 -435.160674)
				)
				(arc
					(start 88.234012 -432.61915)
					(mid 88.211694 -432.565268)
					(end 88.157812 -432.54295)
				)
				(arc
					(start 87.218012 -432.54295)
					(mid 87.16413 -432.565268)
					(end 87.141812 -432.61915)
				)
				(arc
					(start 87.141812 -433.346606)
					(mid 87.143811 -433.363947)
					(end 87.149686 -433.380388)
				)
				(arc
					(start 87.383112 -433.856638)
					(mid 87.390895 -433.890166)
					(end 87.383112 -433.923694)
				)
				(arc
					(start 87.149686 -434.399944)
					(mid 87.143791 -434.41638)
					(end 87.141812 -434.433726)
				)
			)
		)
	)
	(zone
		(layer "In14.Cu")
		(hatch none 0.5)
		(connect_pads
			(clearance 0)
		)
		(min_thickness 0.25)
		(keepout
			(tracks not_allowed)
			(vias allowed)
			(pads allowed)
			(copperpour not_allowed)
			(footprints allowed)
		)
		(placement
			(enabled no)
			(sheetname "")
		)
		(fill
			(thermal_gap 0.5)
			(thermal_bridge_width 0.5)
			(island_removal_mode 0)
		)
		(polygon
			(pts
				(arc
					(start 324.141846 -439.760614)
					(mid 324.164164 -439.814496)
					(end 324.218046 -439.836814)
				)
				(arc
					(start 325.157846 -439.836814)
					(mid 325.211728 -439.814496)
					(end 325.234046 -439.760614)
				)
				(arc
					(start 325.234046 -437.21909)
					(mid 325.211728 -437.165208)
					(end 325.157846 -437.14289)
				)
				(arc
					(start 324.218046 -437.14289)
					(mid 324.164164 -437.165208)
					(end 324.141846 -437.21909)
				)
				(arc
					(start 324.141846 -437.946546)
					(mid 324.143845 -437.963887)
					(end 324.14972 -437.980328)
				)
				(arc
					(start 324.383146 -438.456578)
					(mid 324.390929 -438.490106)
					(end 324.383146 -438.523634)
				)
				(arc
					(start 324.14972 -438.999884)
					(mid 324.143825 -439.01632)
					(end 324.141846 -439.033666)
				)
			)
		)
	)
	(zone
		(layer "In14.Cu")
		(hatch none 0.5)
		(connect_pads
			(clearance 0)
		)
		(min_thickness 0.25)
		(keepout
			(tracks not_allowed)
			(vias allowed)
			(pads allowed)
			(copperpour not_allowed)
			(footprints allowed)
		)
		(placement
			(enabled no)
			(sheetname "")
		)
		(fill
			(thermal_gap 0.5)
			(thermal_bridge_width 0.5)
			(island_removal_mode 0)
		)
		(polygon
			(pts
				(arc
					(start 79.141828 -438.760616)
					(mid 79.164146 -438.814498)
					(end 79.218028 -438.836816)
				)
				(arc
					(start 80.157828 -438.836816)
					(mid 80.21171 -438.814498)
					(end 80.234028 -438.760616)
				)
				(arc
					(start 80.234028 -436.219092)
					(mid 80.21171 -436.16521)
					(end 80.157828 -436.142892)
				)
				(arc
					(start 79.218028 -436.142892)
					(mid 79.164146 -436.16521)
					(end 79.141828 -436.219092)
				)
				(arc
					(start 79.141828 -436.946548)
					(mid 79.143827 -436.963889)
					(end 79.149702 -436.98033)
				)
				(arc
					(start 79.383128 -437.45658)
					(mid 79.390911 -437.490108)
					(end 79.383128 -437.523636)
				)
				(arc
					(start 79.149702 -437.999886)
					(mid 79.143807 -438.016322)
					(end 79.141828 -438.033668)
				)
			)
		)
	)
	(zone
		(layer "In14.Cu")
		(hatch none 0.5)
		(connect_pads
			(clearance 0)
		)
		(min_thickness 0.25)
		(keepout
			(tracks not_allowed)
			(vias allowed)
			(pads allowed)
			(copperpour not_allowed)
			(footprints allowed)
		)
		(placement
			(enabled no)
			(sheetname "")
		)
		(fill
			(thermal_gap 0.5)
			(thermal_bridge_width 0.5)
			(island_removal_mode 0)
		)
		(polygon
			(pts
				(arc
					(start 341.141812 -436.160672)
					(mid 341.16413 -436.214554)
					(end 341.218012 -436.236872)
				)
				(arc
					(start 342.157812 -436.236872)
					(mid 342.211694 -436.214554)
					(end 342.234012 -436.160672)
				)
				(arc
					(start 342.234012 -433.619148)
					(mid 342.211694 -433.565266)
					(end 342.157812 -433.542948)
				)
				(arc
					(start 341.218012 -433.542948)
					(mid 341.16413 -433.565266)
					(end 341.141812 -433.619148)
				)
				(arc
					(start 341.141812 -434.346604)
					(mid 341.143811 -434.363945)
					(end 341.149686 -434.380386)
				)
				(arc
					(start 341.383112 -434.856636)
					(mid 341.390895 -434.890164)
					(end 341.383112 -434.923692)
				)
				(arc
					(start 341.149686 -435.399942)
					(mid 341.143791 -435.416378)
					(end 341.141812 -435.433724)
				)
			)
		)
	)
	(zone
		(layer "In14.Cu")
		(hatch none 0.5)
		(connect_pads
			(clearance 0)
		)
		(min_thickness 0.25)
		(keepout
			(tracks not_allowed)
			(vias allowed)
			(pads allowed)
			(copperpour not_allowed)
			(footprints allowed)
		)
		(placement
			(enabled no)
			(sheetname "")
		)
		(fill
			(thermal_gap 0.5)
			(thermal_bridge_width 0.5)
			(island_removal_mode 0)
		)
		(polygon
			(pts
				(arc
					(start 125.241812 -435.160674)
					(mid 125.26413 -435.214556)
					(end 125.318012 -435.236874)
				)
				(arc
					(start 126.257812 -435.236874)
					(mid 126.311694 -435.214556)
					(end 126.334012 -435.160674)
				)
				(arc
					(start 126.334012 -432.61915)
					(mid 126.311694 -432.565268)
					(end 126.257812 -432.54295)
				)
				(arc
					(start 125.318012 -432.54295)
					(mid 125.26413 -432.565268)
					(end 125.241812 -432.61915)
				)
				(arc
					(start 125.241812 -433.346606)
					(mid 125.243811 -433.363947)
					(end 125.249686 -433.380388)
				)
				(arc
					(start 125.483112 -433.856638)
					(mid 125.490895 -433.890166)
					(end 125.483112 -433.923694)
				)
				(arc
					(start 125.249686 -434.399944)
					(mid 125.243791 -434.41638)
					(end 125.241812 -434.433726)
				)
			)
		)
	)
	(zone
		(layer "In14.Cu")
		(hatch none 0.5)
		(connect_pads
			(clearance 0)
		)
		(min_thickness 0.25)
		(keepout
			(tracks not_allowed)
			(vias allowed)
			(pads allowed)
			(copperpour not_allowed)
			(footprints allowed)
		)
		(placement
			(enabled no)
			(sheetname "")
		)
		(fill
			(thermal_gap 0.5)
			(thermal_bridge_width 0.5)
			(island_removal_mode 0)
		)
		(polygon
			(pts
				(arc
					(start 148.241766 -439.760614)
					(mid 148.264084 -439.814496)
					(end 148.317966 -439.836814)
				)
				(arc
					(start 149.257766 -439.836814)
					(mid 149.311648 -439.814496)
					(end 149.333966 -439.760614)
				)
				(arc
					(start 149.333966 -437.21909)
					(mid 149.311648 -437.165208)
					(end 149.257766 -437.14289)
				)
				(arc
					(start 148.317966 -437.14289)
					(mid 148.264084 -437.165208)
					(end 148.241766 -437.21909)
				)
				(arc
					(start 148.241766 -437.946546)
					(mid 148.243765 -437.963887)
					(end 148.24964 -437.980328)
				)
				(arc
					(start 148.483066 -438.456578)
					(mid 148.490849 -438.490106)
					(end 148.483066 -438.523634)
				)
				(arc
					(start 148.24964 -438.999884)
					(mid 148.243745 -439.01632)
					(end 148.241766 -439.033666)
				)
			)
		)
	)
	(zone
		(layer "In14.Cu")
		(hatch none 0.5)
		(connect_pads
			(clearance 0)
		)
		(min_thickness 0.25)
		(keepout
			(tracks not_allowed)
			(vias allowed)
			(pads allowed)
			(copperpour not_allowed)
			(footprints allowed)
		)
		(placement
			(enabled no)
			(sheetname "")
		)
		(fill
			(thermal_gap 0.5)
			(thermal_bridge_width 0.5)
			(island_removal_mode 0)
		)
		(polygon
			(pts
				(arc
					(start 129.241804 -435.160674)
					(mid 129.264122 -435.214556)
					(end 129.318004 -435.236874)
				)
				(arc
					(start 130.257804 -435.236874)
					(mid 130.311686 -435.214556)
					(end 130.334004 -435.160674)
				)
				(arc
					(start 130.334004 -432.61915)
					(mid 130.311686 -432.565268)
					(end 130.257804 -432.54295)
				)
				(arc
					(start 129.318004 -432.54295)
					(mid 129.264122 -432.565268)
					(end 129.241804 -432.61915)
				)
				(arc
					(start 129.241804 -433.346606)
					(mid 129.243803 -433.363947)
					(end 129.249678 -433.380388)
				)
				(arc
					(start 129.483104 -433.856638)
					(mid 129.490887 -433.890166)
					(end 129.483104 -433.923694)
				)
				(arc
					(start 129.249678 -434.399944)
					(mid 129.243783 -434.41638)
					(end 129.241804 -434.433726)
				)
			)
		)
	)
	(zone
		(layer "In14.Cu")
		(hatch none 0.5)
		(connect_pads
			(clearance 0)
		)
		(min_thickness 0.25)
		(keepout
			(tracks not_allowed)
			(vias allowed)
			(pads allowed)
			(copperpour not_allowed)
			(footprints allowed)
		)
		(placement
			(enabled no)
			(sheetname "")
		)
		(fill
			(thermal_gap 0.5)
			(thermal_bridge_width 0.5)
			(island_removal_mode 0)
		)
		(polygon
			(pts
				(arc
					(start 326.141588 -435.160674)
					(mid 326.163906 -435.214556)
					(end 326.217788 -435.236874)
				)
				(arc
					(start 327.157588 -435.236874)
					(mid 327.21147 -435.214556)
					(end 327.233788 -435.160674)
				)
				(arc
					(start 327.233788 -432.61915)
					(mid 327.21147 -432.565268)
					(end 327.157588 -432.54295)
				)
				(arc
					(start 326.217788 -432.54295)
					(mid 326.163906 -432.565268)
					(end 326.141588 -432.61915)
				)
				(arc
					(start 326.141588 -433.346606)
					(mid 326.143587 -433.363947)
					(end 326.149462 -433.380388)
				)
				(arc
					(start 326.382888 -433.856638)
					(mid 326.390671 -433.890166)
					(end 326.382888 -433.923694)
				)
				(arc
					(start 326.149462 -434.399944)
					(mid 326.143567 -434.41638)
					(end 326.141588 -434.433726)
				)
			)
		)
	)
	(zone
		(layer "In14.Cu")
		(hatch none 0.5)
		(connect_pads
			(clearance 0)
		)
		(min_thickness 0.25)
		(keepout
			(tracks not_allowed)
			(vias allowed)
			(pads allowed)
			(copperpour not_allowed)
			(footprints allowed)
		)
		(placement
			(enabled no)
			(sheetname "")
		)
		(fill
			(thermal_gap 0.5)
			(thermal_bridge_width 0.5)
			(island_removal_mode 0)
		)
		(polygon
			(pts
				(arc
					(start 381.241808 -435.160674)
					(mid 381.264126 -435.214556)
					(end 381.318008 -435.236874)
				)
				(arc
					(start 382.257808 -435.236874)
					(mid 382.31169 -435.214556)
					(end 382.334008 -435.160674)
				)
				(arc
					(start 382.334008 -432.61915)
					(mid 382.31169 -432.565268)
					(end 382.257808 -432.54295)
				)
				(arc
					(start 381.318008 -432.54295)
					(mid 381.264126 -432.565268)
					(end 381.241808 -432.61915)
				)
				(arc
					(start 381.241808 -433.346606)
					(mid 381.243807 -433.363947)
					(end 381.249682 -433.380388)
				)
				(arc
					(start 381.483108 -433.856638)
					(mid 381.490891 -433.890166)
					(end 381.483108 -433.923694)
				)
				(arc
					(start 381.249682 -434.399944)
					(mid 381.243787 -434.41638)
					(end 381.241808 -434.433726)
				)
			)
		)
	)
	(zone
		(layer "In14.Cu")
		(hatch none 0.5)
		(connect_pads
			(clearance 0)
		)
		(min_thickness 0.25)
		(keepout
			(tracks not_allowed)
			(vias allowed)
			(pads allowed)
			(copperpour not_allowed)
			(footprints allowed)
		)
		(placement
			(enabled no)
			(sheetname "")
		)
		(fill
			(thermal_gap 0.5)
			(thermal_bridge_width 0.5)
			(island_removal_mode 0)
		)
		(polygon
			(pts
				(arc
					(start 383.242058 -439.760614)
					(mid 383.264376 -439.814496)
					(end 383.318258 -439.836814)
				)
				(arc
					(start 384.258058 -439.836814)
					(mid 384.31194 -439.814496)
					(end 384.334258 -439.760614)
				)
				(arc
					(start 384.334258 -437.21909)
					(mid 384.31194 -437.165208)
					(end 384.258058 -437.14289)
				)
				(arc
					(start 383.318258 -437.14289)
					(mid 383.264376 -437.165208)
					(end 383.242058 -437.21909)
				)
				(arc
					(start 383.242058 -437.946546)
					(mid 383.244057 -437.963887)
					(end 383.249932 -437.980328)
				)
				(arc
					(start 383.483358 -438.456578)
					(mid 383.491141 -438.490106)
					(end 383.483358 -438.523634)
				)
				(arc
					(start 383.249932 -438.999884)
					(mid 383.244037 -439.01632)
					(end 383.242058 -439.033666)
				)
			)
		)
	)
	(zone
		(layer "In14.Cu")
		(hatch none 0.5)
		(connect_pads
			(clearance 0)
		)
		(min_thickness 0.25)
		(keepout
			(tracks not_allowed)
			(vias allowed)
			(pads allowed)
			(copperpour not_allowed)
			(footprints allowed)
		)
		(placement
			(enabled no)
			(sheetname "")
		)
		(fill
			(thermal_gap 0.5)
			(thermal_bridge_width 0.5)
			(island_removal_mode 0)
		)
		(polygon
			(pts
				(arc
					(start 135.241792 -436.160672)
					(mid 135.26411 -436.214554)
					(end 135.317992 -436.236872)
				)
				(arc
					(start 136.257792 -436.236872)
					(mid 136.311674 -436.214554)
					(end 136.333992 -436.160672)
				)
				(arc
					(start 136.333992 -433.619148)
					(mid 136.311674 -433.565266)
					(end 136.257792 -433.542948)
				)
				(arc
					(start 135.317992 -433.542948)
					(mid 135.26411 -433.565266)
					(end 135.241792 -433.619148)
				)
				(arc
					(start 135.241792 -434.346604)
					(mid 135.243791 -434.363945)
					(end 135.249666 -434.380386)
				)
				(arc
					(start 135.483092 -434.856636)
					(mid 135.490875 -434.890164)
					(end 135.483092 -434.923692)
				)
				(arc
					(start 135.249666 -435.399942)
					(mid 135.243771 -435.416378)
					(end 135.241792 -435.433724)
				)
			)
		)
	)
	(zone
		(layer "In14.Cu")
		(hatch none 0.5)
		(connect_pads
			(clearance 0)
		)
		(min_thickness 0.25)
		(keepout
			(tracks not_allowed)
			(vias allowed)
			(pads allowed)
			(copperpour not_allowed)
			(footprints allowed)
		)
		(placement
			(enabled no)
			(sheetname "")
		)
		(fill
			(thermal_gap 0.5)
			(thermal_bridge_width 0.5)
			(island_removal_mode 0)
		)
		(polygon
			(pts
				(arc
					(start 385.2418 -435.160674)
					(mid 385.264118 -435.214556)
					(end 385.318 -435.236874)
				)
				(arc
					(start 386.2578 -435.236874)
					(mid 386.311682 -435.214556)
					(end 386.334 -435.160674)
				)
				(arc
					(start 386.334 -432.61915)
					(mid 386.311682 -432.565268)
					(end 386.2578 -432.54295)
				)
				(arc
					(start 385.318 -432.54295)
					(mid 385.264118 -432.565268)
					(end 385.2418 -432.61915)
				)
				(arc
					(start 385.2418 -433.346606)
					(mid 385.243799 -433.363947)
					(end 385.249674 -433.380388)
				)
				(arc
					(start 385.4831 -433.856638)
					(mid 385.490883 -433.890166)
					(end 385.4831 -433.923694)
				)
				(arc
					(start 385.249674 -434.399944)
					(mid 385.243779 -434.41638)
					(end 385.2418 -434.433726)
				)
			)
		)
	)
	(zone
		(layer "In14.Cu")
		(hatch none 0.5)
		(connect_pads
			(clearance 0)
		)
		(min_thickness 0.25)
		(keepout
			(tracks not_allowed)
			(vias allowed)
			(pads allowed)
			(copperpour not_allowed)
			(footprints allowed)
		)
		(placement
			(enabled no)
			(sheetname "")
		)
		(fill
			(thermal_gap 0.5)
			(thermal_bridge_width 0.5)
			(island_removal_mode 0)
		)
		(polygon
			(pts
				(arc
					(start 412.242 -436.160672)
					(mid 412.264318 -436.214554)
					(end 412.3182 -436.236872)
				)
				(arc
					(start 413.258 -436.236872)
					(mid 413.311882 -436.214554)
					(end 413.3342 -436.160672)
				)
				(arc
					(start 413.3342 -433.619148)
					(mid 413.311882 -433.565266)
					(end 413.258 -433.542948)
				)
				(arc
					(start 412.3182 -433.542948)
					(mid 412.264318 -433.565266)
					(end 412.242 -433.619148)
				)
				(arc
					(start 412.242 -434.346604)
					(mid 412.243999 -434.363945)
					(end 412.249874 -434.380386)
				)
				(arc
					(start 412.4833 -434.856636)
					(mid 412.491083 -434.890164)
					(end 412.4833 -434.923692)
				)
				(arc
					(start 412.249874 -435.399942)
					(mid 412.243979 -435.416378)
					(end 412.242 -435.433724)
				)
			)
		)
	)
	(zone
		(layer "In14.Cu")
		(hatch none 0.5)
		(connect_pads
			(clearance 0)
		)
		(min_thickness 0.25)
		(keepout
			(tracks not_allowed)
			(vias allowed)
			(pads allowed)
			(copperpour not_allowed)
			(footprints allowed)
		)
		(placement
			(enabled no)
			(sheetname "")
		)
		(fill
			(thermal_gap 0.5)
			(thermal_bridge_width 0.5)
			(island_removal_mode 0)
		)
		(polygon
			(pts
				(arc
					(start 72.141842 -436.160672)
					(mid 72.16416 -436.214554)
					(end 72.218042 -436.236872)
				)
				(arc
					(start 73.157842 -436.236872)
					(mid 73.211724 -436.214554)
					(end 73.234042 -436.160672)
				)
				(arc
					(start 73.234042 -433.619148)
					(mid 73.211724 -433.565266)
					(end 73.157842 -433.542948)
				)
				(arc
					(start 72.218042 -433.542948)
					(mid 72.16416 -433.565266)
					(end 72.141842 -433.619148)
				)
				(arc
					(start 72.141842 -434.346604)
					(mid 72.143841 -434.363945)
					(end 72.149716 -434.380386)
				)
				(arc
					(start 72.383142 -434.856636)
					(mid 72.390925 -434.890164)
					(end 72.383142 -434.923692)
				)
				(arc
					(start 72.149716 -435.399942)
					(mid 72.143821 -435.416378)
					(end 72.141842 -435.433724)
				)
			)
		)
	)
	(zone
		(layer "In14.Cu")
		(hatch none 0.5)
		(connect_pads
			(clearance 0)
		)
		(min_thickness 0.25)
		(keepout
			(tracks not_allowed)
			(vias allowed)
			(pads allowed)
			(copperpour not_allowed)
			(footprints allowed)
		)
		(placement
			(enabled no)
			(sheetname "")
		)
		(fill
			(thermal_gap 0.5)
			(thermal_bridge_width 0.5)
			(island_removal_mode 0)
		)
		(polygon
			(pts
				(arc
					(start 395.24178 -436.160672)
					(mid 395.264098 -436.214554)
					(end 395.31798 -436.236872)
				)
				(arc
					(start 396.25778 -436.236872)
					(mid 396.311662 -436.214554)
					(end 396.33398 -436.160672)
				)
				(arc
					(start 396.33398 -433.619148)
					(mid 396.311662 -433.565266)
					(end 396.25778 -433.542948)
				)
				(arc
					(start 395.31798 -433.542948)
					(mid 395.264098 -433.565266)
					(end 395.24178 -433.619148)
				)
				(arc
					(start 395.24178 -434.346604)
					(mid 395.243779 -434.363945)
					(end 395.249654 -434.380386)
				)
				(arc
					(start 395.48308 -434.856636)
					(mid 395.490863 -434.890164)
					(end 395.48308 -434.923692)
				)
				(arc
					(start 395.249654 -435.399942)
					(mid 395.243759 -435.416378)
					(end 395.24178 -435.433724)
				)
			)
		)
	)
	(zone
		(layer "In14.Cu")
		(hatch none 0.5)
		(connect_pads
			(clearance 0)
		)
		(min_thickness 0.25)
		(keepout
			(tracks not_allowed)
			(vias allowed)
			(pads allowed)
			(copperpour not_allowed)
			(footprints allowed)
		)
		(placement
			(enabled no)
			(sheetname "")
		)
		(fill
			(thermal_gap 0.5)
			(thermal_bridge_width 0.5)
			(island_removal_mode 0)
		)
		(polygon
			(pts
				(arc
					(start 402.24202 -435.160674)
					(mid 402.264338 -435.214556)
					(end 402.31822 -435.236874)
				)
				(arc
					(start 403.25802 -435.236874)
					(mid 403.311902 -435.214556)
					(end 403.33422 -435.160674)
				)
				(arc
					(start 403.33422 -432.61915)
					(mid 403.311902 -432.565268)
					(end 403.25802 -432.54295)
				)
				(arc
					(start 402.31822 -432.54295)
					(mid 402.264338 -432.565268)
					(end 402.24202 -432.61915)
				)
				(arc
					(start 402.24202 -433.346606)
					(mid 402.244019 -433.363947)
					(end 402.249894 -433.380388)
				)
				(arc
					(start 402.48332 -433.856638)
					(mid 402.491103 -433.890166)
					(end 402.48332 -433.923694)
				)
				(arc
					(start 402.249894 -434.399944)
					(mid 402.243999 -434.41638)
					(end 402.24202 -434.433726)
				)
			)
		)
	)
	(zone
		(layer "In14.Cu")
		(hatch none 0.5)
		(connect_pads
			(clearance 0)
		)
		(min_thickness 0.25)
		(keepout
			(tracks not_allowed)
			(vias allowed)
			(pads allowed)
			(copperpour not_allowed)
			(footprints allowed)
		)
		(placement
			(enabled no)
			(sheetname "")
		)
		(fill
			(thermal_gap 0.5)
			(thermal_bridge_width 0.5)
			(island_removal_mode 0)
		)
		(polygon
			(pts
				(arc
					(start 316.141608 -436.160672)
					(mid 316.163926 -436.214554)
					(end 316.217808 -436.236872)
				)
				(arc
					(start 317.157608 -436.236872)
					(mid 317.21149 -436.214554)
					(end 317.233808 -436.160672)
				)
				(arc
					(start 317.233808 -433.619148)
					(mid 317.21149 -433.565266)
					(end 317.157608 -433.542948)
				)
				(arc
					(start 316.217808 -433.542948)
					(mid 316.163926 -433.565266)
					(end 316.141608 -433.619148)
				)
				(arc
					(start 316.141608 -434.346604)
					(mid 316.143607 -434.363945)
					(end 316.149482 -434.380386)
				)
				(arc
					(start 316.382908 -434.856636)
					(mid 316.390691 -434.890164)
					(end 316.382908 -434.923692)
				)
				(arc
					(start 316.149482 -435.399942)
					(mid 316.143587 -435.416378)
					(end 316.141608 -435.433724)
				)
			)
		)
	)
	(zone
		(layer "In14.Cu")
		(hatch none 0.5)
		(connect_pads
			(clearance 0)
		)
		(min_thickness 0.25)
		(keepout
			(tracks not_allowed)
			(vias allowed)
			(pads allowed)
			(copperpour not_allowed)
			(footprints allowed)
		)
		(placement
			(enabled no)
			(sheetname "")
		)
		(fill
			(thermal_gap 0.5)
			(thermal_bridge_width 0.5)
			(island_removal_mode 0)
		)
		(polygon
			(pts
				(arc
					(start 144.241774 -439.760614)
					(mid 144.264092 -439.814496)
					(end 144.317974 -439.836814)
				)
				(arc
					(start 145.257774 -439.836814)
					(mid 145.311656 -439.814496)
					(end 145.333974 -439.760614)
				)
				(arc
					(start 145.333974 -437.21909)
					(mid 145.311656 -437.165208)
					(end 145.257774 -437.14289)
				)
				(arc
					(start 144.317974 -437.14289)
					(mid 144.264092 -437.165208)
					(end 144.241774 -437.21909)
				)
				(arc
					(start 144.241774 -437.946546)
					(mid 144.243773 -437.963887)
					(end 144.249648 -437.980328)
				)
				(arc
					(start 144.483074 -438.456578)
					(mid 144.490857 -438.490106)
					(end 144.483074 -438.523634)
				)
				(arc
					(start 144.249648 -438.999884)
					(mid 144.243753 -439.01632)
					(end 144.241774 -439.033666)
				)
			)
		)
	)
	(zone
		(layer "In14.Cu")
		(hatch none 0.5)
		(connect_pads
			(clearance 0)
		)
		(min_thickness 0.25)
		(keepout
			(tracks not_allowed)
			(vias allowed)
			(pads allowed)
			(copperpour not_allowed)
			(footprints allowed)
		)
		(placement
			(enabled no)
			(sheetname "")
		)
		(fill
			(thermal_gap 0.5)
			(thermal_bridge_width 0.5)
			(island_removal_mode 0)
		)
		(polygon
			(pts
				(xy 220.02115 -402.703284) (xy 220.02115 -401.132294) (xy 221.692978 -401.132294) (xy 221.692978 -402.703284)
			)
		)
	)
	(zone
		(layer "In14.Cu")
		(hatch none 0.5)
		(connect_pads
			(clearance 0)
		)
		(min_thickness 0.25)
		(keepout
			(tracks not_allowed)
			(vias allowed)
			(pads allowed)
			(copperpour not_allowed)
			(footprints allowed)
		)
		(placement
			(enabled no)
			(sheetname "")
		)
		(fill
			(thermal_gap 0.5)
			(thermal_bridge_width 0.5)
			(island_removal_mode 0)
		)
		(polygon
			(pts
				(arc
					(start 398.242028 -435.160674)
					(mid 398.264346 -435.214556)
					(end 398.318228 -435.236874)
				)
				(arc
					(start 399.258028 -435.236874)
					(mid 399.31191 -435.214556)
					(end 399.334228 -435.160674)
				)
				(arc
					(start 399.334228 -432.61915)
					(mid 399.31191 -432.565268)
					(end 399.258028 -432.54295)
				)
				(arc
					(start 398.318228 -432.54295)
					(mid 398.264346 -432.565268)
					(end 398.242028 -432.61915)
				)
				(arc
					(start 398.242028 -433.346606)
					(mid 398.244027 -433.363947)
					(end 398.249902 -433.380388)
				)
				(arc
					(start 398.483328 -433.856638)
					(mid 398.491111 -433.890166)
					(end 398.483328 -433.923694)
				)
				(arc
					(start 398.249902 -434.399944)
					(mid 398.244007 -434.41638)
					(end 398.242028 -434.433726)
				)
			)
		)
	)
	(zone
		(layer "In14.Cu")
		(hatch none 0.5)
		(connect_pads
			(clearance 0)
		)
		(min_thickness 0.25)
		(keepout
			(tracks not_allowed)
			(vias allowed)
			(pads allowed)
			(copperpour not_allowed)
			(footprints allowed)
		)
		(placement
			(enabled no)
			(sheetname "")
		)
		(fill
			(thermal_gap 0.5)
			(thermal_bridge_width 0.5)
			(island_removal_mode 0)
		)
		(polygon
			(pts
				(arc
					(start 337.14182 -436.160672)
					(mid 337.164138 -436.214554)
					(end 337.21802 -436.236872)
				)
				(arc
					(start 338.15782 -436.236872)
					(mid 338.211702 -436.214554)
					(end 338.23402 -436.160672)
				)
				(arc
					(start 338.23402 -433.619148)
					(mid 338.211702 -433.565266)
					(end 338.15782 -433.542948)
				)
				(arc
					(start 337.21802 -433.542948)
					(mid 337.164138 -433.565266)
					(end 337.14182 -433.619148)
				)
				(arc
					(start 337.14182 -434.346604)
					(mid 337.143819 -434.363945)
					(end 337.149694 -434.380386)
				)
				(arc
					(start 337.38312 -434.856636)
					(mid 337.390903 -434.890164)
					(end 337.38312 -434.923692)
				)
				(arc
					(start 337.149694 -435.399942)
					(mid 337.143799 -435.416378)
					(end 337.14182 -435.433724)
				)
			)
		)
	)
	(zone
		(layer "In14.Cu")
		(hatch none 0.5)
		(connect_pads
			(clearance 0)
		)
		(min_thickness 0.25)
		(keepout
			(tracks not_allowed)
			(vias allowed)
			(pads allowed)
			(copperpour not_allowed)
			(footprints allowed)
		)
		(placement
			(enabled no)
			(sheetname "")
		)
		(fill
			(thermal_gap 0.5)
			(thermal_bridge_width 0.5)
			(island_removal_mode 0)
		)
		(polygon
			(pts
				(arc
					(start 64.141858 -436.160672)
					(mid 64.164176 -436.214554)
					(end 64.218058 -436.236872)
				)
				(arc
					(start 65.157858 -436.236872)
					(mid 65.21174 -436.214554)
					(end 65.234058 -436.160672)
				)
				(arc
					(start 65.234058 -433.619148)
					(mid 65.21174 -433.565266)
					(end 65.157858 -433.542948)
				)
				(arc
					(start 64.218058 -433.542948)
					(mid 64.164176 -433.565266)
					(end 64.141858 -433.619148)
				)
				(arc
					(start 64.141858 -434.346604)
					(mid 64.143857 -434.363945)
					(end 64.149732 -434.380386)
				)
				(arc
					(start 64.383158 -434.856636)
					(mid 64.390941 -434.890164)
					(end 64.383158 -434.923692)
				)
				(arc
					(start 64.149732 -435.399942)
					(mid 64.143837 -435.416378)
					(end 64.141858 -435.433724)
				)
			)
		)
	)
	(zone
		(layer "In14.Cu")
		(hatch none 0.5)
		(connect_pads
			(clearance 0)
		)
		(min_thickness 0.25)
		(keepout
			(tracks not_allowed)
			(vias allowed)
			(pads allowed)
			(copperpour not_allowed)
			(footprints allowed)
		)
		(placement
			(enabled no)
			(sheetname "")
		)
		(fill
			(thermal_gap 0.5)
			(thermal_bridge_width 0.5)
			(island_removal_mode 0)
		)
		(polygon
			(pts
				(arc
					(start 87.141812 -438.760616)
					(mid 87.16413 -438.814498)
					(end 87.218012 -438.836816)
				)
				(arc
					(start 88.157812 -438.836816)
					(mid 88.211694 -438.814498)
					(end 88.234012 -438.760616)
				)
				(arc
					(start 88.234012 -436.219092)
					(mid 88.211694 -436.16521)
					(end 88.157812 -436.142892)
				)
				(arc
					(start 87.218012 -436.142892)
					(mid 87.16413 -436.16521)
					(end 87.141812 -436.219092)
				)
				(arc
					(start 87.141812 -436.946548)
					(mid 87.143811 -436.963889)
					(end 87.149686 -436.98033)
				)
				(arc
					(start 87.383112 -437.45658)
					(mid 87.390895 -437.490108)
					(end 87.383112 -437.523636)
				)
				(arc
					(start 87.149686 -437.999886)
					(mid 87.143791 -438.016322)
					(end 87.141812 -438.033668)
				)
			)
		)
	)
	(zone
		(layer "In14.Cu")
		(hatch none 0.5)
		(connect_pads
			(clearance 0)
		)
		(min_thickness 0.25)
		(keepout
			(tracks not_allowed)
			(vias allowed)
			(pads allowed)
			(copperpour not_allowed)
			(footprints allowed)
		)
		(placement
			(enabled no)
			(sheetname "")
		)
		(fill
			(thermal_gap 0.5)
			(thermal_bridge_width 0.5)
			(island_removal_mode 0)
		)
		(polygon
			(pts
				(arc
					(start 152.242012 -436.160672)
					(mid 152.26433 -436.214554)
					(end 152.318212 -436.236872)
				)
				(arc
					(start 153.258012 -436.236872)
					(mid 153.311894 -436.214554)
					(end 153.334212 -436.160672)
				)
				(arc
					(start 153.334212 -433.619148)
					(mid 153.311894 -433.565266)
					(end 153.258012 -433.542948)
				)
				(arc
					(start 152.318212 -433.542948)
					(mid 152.26433 -433.565266)
					(end 152.242012 -433.619148)
				)
				(arc
					(start 152.242012 -434.346604)
					(mid 152.244011 -434.363945)
					(end 152.249886 -434.380386)
				)
				(arc
					(start 152.483312 -434.856636)
					(mid 152.491095 -434.890164)
					(end 152.483312 -434.923692)
				)
				(arc
					(start 152.249886 -435.399942)
					(mid 152.243991 -435.416378)
					(end 152.242012 -435.433724)
				)
			)
		)
	)
	(zone
		(layer "In14.Cu")
		(hatch none 0.5)
		(connect_pads
			(clearance 0)
		)
		(min_thickness 0.25)
		(keepout
			(tracks not_allowed)
			(vias allowed)
			(pads allowed)
			(copperpour not_allowed)
			(footprints allowed)
		)
		(placement
			(enabled no)
			(sheetname "")
		)
		(fill
			(thermal_gap 0.5)
			(thermal_bridge_width 0.5)
			(island_removal_mode 0)
		)
		(polygon
			(pts
				(arc
					(start 83.14182 -435.160674)
					(mid 83.164138 -435.214556)
					(end 83.21802 -435.236874)
				)
				(arc
					(start 84.15782 -435.236874)
					(mid 84.211702 -435.214556)
					(end 84.23402 -435.160674)
				)
				(arc
					(start 84.23402 -432.61915)
					(mid 84.211702 -432.565268)
					(end 84.15782 -432.54295)
				)
				(arc
					(start 83.21802 -432.54295)
					(mid 83.164138 -432.565268)
					(end 83.14182 -432.61915)
				)
				(arc
					(start 83.14182 -433.346606)
					(mid 83.143819 -433.363947)
					(end 83.149694 -433.380388)
				)
				(arc
					(start 83.38312 -433.856638)
					(mid 83.390903 -433.890166)
					(end 83.38312 -433.923694)
				)
				(arc
					(start 83.149694 -434.399944)
					(mid 83.143799 -434.41638)
					(end 83.14182 -434.433726)
				)
			)
		)
	)
	(zone
		(layer "In14.Cu")
		(hatch none 0.5)
		(connect_pads
			(clearance 0)
		)
		(min_thickness 0.25)
		(keepout
			(tracks not_allowed)
			(vias allowed)
			(pads allowed)
			(copperpour not_allowed)
			(footprints allowed)
		)
		(placement
			(enabled no)
			(sheetname "")
		)
		(fill
			(thermal_gap 0.5)
			(thermal_bridge_width 0.5)
			(island_removal_mode 0)
		)
		(polygon
			(pts
				(arc
					(start 381.242062 -438.760616)
					(mid 381.26438 -438.814498)
					(end 381.318262 -438.836816)
				)
				(arc
					(start 382.258062 -438.836816)
					(mid 382.311944 -438.814498)
					(end 382.334262 -438.760616)
				)
				(arc
					(start 382.334262 -436.219092)
					(mid 382.311944 -436.16521)
					(end 382.258062 -436.142892)
				)
				(arc
					(start 381.318262 -436.142892)
					(mid 381.26438 -436.16521)
					(end 381.242062 -436.219092)
				)
				(arc
					(start 381.242062 -436.946548)
					(mid 381.244061 -436.963889)
					(end 381.249936 -436.98033)
				)
				(arc
					(start 381.483362 -437.45658)
					(mid 381.491145 -437.490108)
					(end 381.483362 -437.523636)
				)
				(arc
					(start 381.249936 -437.999886)
					(mid 381.244041 -438.016322)
					(end 381.242062 -438.033668)
				)
			)
		)
	)
	(zone
		(layer "In14.Cu")
		(hatch none 0.5)
		(connect_pads
			(clearance 0)
		)
		(min_thickness 0.25)
		(keepout
			(tracks not_allowed)
			(vias allowed)
			(pads allowed)
			(copperpour not_allowed)
			(footprints allowed)
		)
		(placement
			(enabled no)
			(sheetname "")
		)
		(fill
			(thermal_gap 0.5)
			(thermal_bridge_width 0.5)
			(island_removal_mode 0)
		)
		(polygon
			(pts
				(arc
					(start 393.242038 -438.760616)
					(mid 393.264356 -438.814498)
					(end 393.318238 -438.836816)
				)
				(arc
					(start 394.258038 -438.836816)
					(mid 394.31192 -438.814498)
					(end 394.334238 -438.760616)
				)
				(arc
					(start 394.334238 -436.219092)
					(mid 394.31192 -436.16521)
					(end 394.258038 -436.142892)
				)
				(arc
					(start 393.318238 -436.142892)
					(mid 393.264356 -436.16521)
					(end 393.242038 -436.219092)
				)
				(arc
					(start 393.242038 -436.946548)
					(mid 393.244037 -436.963889)
					(end 393.249912 -436.98033)
				)
				(arc
					(start 393.483338 -437.45658)
					(mid 393.491121 -437.490108)
					(end 393.483338 -437.523636)
				)
				(arc
					(start 393.249912 -437.999886)
					(mid 393.244017 -438.016322)
					(end 393.242038 -438.033668)
				)
			)
		)
	)
	(zone
		(layer "In14.Cu")
		(hatch none 0.5)
		(connect_pads
			(clearance 0)
		)
		(min_thickness 0.25)
		(keepout
			(tracks not_allowed)
			(vias allowed)
			(pads allowed)
			(copperpour not_allowed)
			(footprints allowed)
		)
		(placement
			(enabled no)
			(sheetname "")
		)
		(fill
			(thermal_gap 0.5)
			(thermal_bridge_width 0.5)
			(island_removal_mode 0)
		)
		(polygon
			(pts
				(xy 230.702866 -402.709634) (xy 230.702866 -401.088098) (xy 232.343452 -401.088098) (xy 232.343452 -402.709634)
			)
		)
	)
	(zone
		(layer "In14.Cu")
		(hatch none 0.5)
		(connect_pads
			(clearance 0)
		)
		(min_thickness 0.25)
		(keepout
			(tracks not_allowed)
			(vias allowed)
			(pads allowed)
			(copperpour not_allowed)
			(footprints allowed)
		)
		(placement
			(enabled no)
			(sheetname "")
		)
		(fill
			(thermal_gap 0.5)
			(thermal_bridge_width 0.5)
			(island_removal_mode 0)
		)
		(polygon
			(pts
				(arc
					(start 156.24175 -439.760614)
					(mid 156.264068 -439.814496)
					(end 156.31795 -439.836814)
				)
				(arc
					(start 157.25775 -439.836814)
					(mid 157.311632 -439.814496)
					(end 157.33395 -439.760614)
				)
				(arc
					(start 157.33395 -437.21909)
					(mid 157.311632 -437.165208)
					(end 157.25775 -437.14289)
				)
				(arc
					(start 156.31795 -437.14289)
					(mid 156.264068 -437.165208)
					(end 156.24175 -437.21909)
				)
				(arc
					(start 156.24175 -437.946546)
					(mid 156.243749 -437.963887)
					(end 156.249624 -437.980328)
				)
				(arc
					(start 156.48305 -438.456578)
					(mid 156.490833 -438.490106)
					(end 156.48305 -438.523634)
				)
				(arc
					(start 156.249624 -438.999884)
					(mid 156.243729 -439.01632)
					(end 156.24175 -439.033666)
				)
			)
		)
	)
	(zone
		(layer "In14.Cu")
		(hatch none 0.5)
		(connect_pads
			(clearance 0)
		)
		(min_thickness 0.25)
		(keepout
			(tracks not_allowed)
			(vias allowed)
			(pads allowed)
			(copperpour not_allowed)
			(footprints allowed)
		)
		(placement
			(enabled no)
			(sheetname "")
		)
		(fill
			(thermal_gap 0.5)
			(thermal_bridge_width 0.5)
			(island_removal_mode 0)
		)
		(polygon
			(pts
				(arc
					(start 339.141816 -435.160674)
					(mid 339.164134 -435.214556)
					(end 339.218016 -435.236874)
				)
				(arc
					(start 340.157816 -435.236874)
					(mid 340.211698 -435.214556)
					(end 340.234016 -435.160674)
				)
				(arc
					(start 340.234016 -432.61915)
					(mid 340.211698 -432.565268)
					(end 340.157816 -432.54295)
				)
				(arc
					(start 339.218016 -432.54295)
					(mid 339.164134 -432.565268)
					(end 339.141816 -432.61915)
				)
				(arc
					(start 339.141816 -433.346606)
					(mid 339.143815 -433.363947)
					(end 339.14969 -433.380388)
				)
				(arc
					(start 339.383116 -433.856638)
					(mid 339.390899 -433.890166)
					(end 339.383116 -433.923694)
				)
				(arc
					(start 339.14969 -434.399944)
					(mid 339.143795 -434.41638)
					(end 339.141816 -434.433726)
				)
			)
		)
	)
	(zone
		(layer "In14.Cu")
		(hatch none 0.5)
		(connect_pads
			(clearance 0)
		)
		(min_thickness 0.25)
		(keepout
			(tracks not_allowed)
			(vias allowed)
			(pads allowed)
			(copperpour not_allowed)
			(footprints allowed)
		)
		(placement
			(enabled no)
			(sheetname "")
		)
		(fill
			(thermal_gap 0.5)
			(thermal_bridge_width 0.5)
			(island_removal_mode 0)
		)
		(polygon
			(pts
				(arc
					(start 404.242016 -436.160672)
					(mid 404.264334 -436.214554)
					(end 404.318216 -436.236872)
				)
				(arc
					(start 405.258016 -436.236872)
					(mid 405.311898 -436.214554)
					(end 405.334216 -436.160672)
				)
				(arc
					(start 405.334216 -433.619148)
					(mid 405.311898 -433.565266)
					(end 405.258016 -433.542948)
				)
				(arc
					(start 404.318216 -433.542948)
					(mid 404.264334 -433.565266)
					(end 404.242016 -433.619148)
				)
				(arc
					(start 404.242016 -434.346604)
					(mid 404.244015 -434.363945)
					(end 404.24989 -434.380386)
				)
				(arc
					(start 404.483316 -434.856636)
					(mid 404.491099 -434.890164)
					(end 404.483316 -434.923692)
				)
				(arc
					(start 404.24989 -435.399942)
					(mid 404.243995 -435.416378)
					(end 404.242016 -435.433724)
				)
			)
		)
	)
	(zone
		(layer "In14.Cu")
		(hatch none 0.5)
		(connect_pads
			(clearance 0)
		)
		(min_thickness 0.25)
		(keepout
			(tracks not_allowed)
			(vias allowed)
			(pads allowed)
			(copperpour not_allowed)
			(footprints allowed)
		)
		(placement
			(enabled no)
			(sheetname "")
		)
		(fill
			(thermal_gap 0.5)
			(thermal_bridge_width 0.5)
			(island_removal_mode 0)
		)
		(polygon
			(pts
				(arc
					(start 142.242032 -435.160674)
					(mid 142.26435 -435.214556)
					(end 142.318232 -435.236874)
				)
				(arc
					(start 143.258032 -435.236874)
					(mid 143.311914 -435.214556)
					(end 143.334232 -435.160674)
				)
				(arc
					(start 143.334232 -432.61915)
					(mid 143.311914 -432.565268)
					(end 143.258032 -432.54295)
				)
				(arc
					(start 142.318232 -432.54295)
					(mid 142.26435 -432.565268)
					(end 142.242032 -432.61915)
				)
				(arc
					(start 142.242032 -433.346606)
					(mid 142.244031 -433.363947)
					(end 142.249906 -433.380388)
				)
				(arc
					(start 142.483332 -433.856638)
					(mid 142.491115 -433.890166)
					(end 142.483332 -433.923694)
				)
				(arc
					(start 142.249906 -434.399944)
					(mid 142.244011 -434.41638)
					(end 142.242032 -434.433726)
				)
			)
		)
	)
	(zone
		(layer "In14.Cu")
		(hatch none 0.5)
		(connect_pads
			(clearance 0)
		)
		(min_thickness 0.25)
		(keepout
			(tracks not_allowed)
			(vias allowed)
			(pads allowed)
			(copperpour not_allowed)
			(footprints allowed)
		)
		(placement
			(enabled no)
			(sheetname "")
		)
		(fill
			(thermal_gap 0.5)
			(thermal_bridge_width 0.5)
			(island_removal_mode 0)
		)
		(polygon
			(pts
				(arc
					(start 137.241788 -435.160674)
					(mid 137.264106 -435.214556)
					(end 137.317988 -435.236874)
				)
				(arc
					(start 138.257788 -435.236874)
					(mid 138.31167 -435.214556)
					(end 138.333988 -435.160674)
				)
				(arc
					(start 138.333988 -432.61915)
					(mid 138.31167 -432.565268)
					(end 138.257788 -432.54295)
				)
				(arc
					(start 137.317988 -432.54295)
					(mid 137.264106 -432.565268)
					(end 137.241788 -432.61915)
				)
				(arc
					(start 137.241788 -433.346606)
					(mid 137.243787 -433.363947)
					(end 137.249662 -433.380388)
				)
				(arc
					(start 137.483088 -433.856638)
					(mid 137.490871 -433.890166)
					(end 137.483088 -433.923694)
				)
				(arc
					(start 137.249662 -434.399944)
					(mid 137.243767 -434.41638)
					(end 137.241788 -434.433726)
				)
			)
		)
	)
	(zone
		(layer "In14.Cu")
		(hatch none 0.5)
		(connect_pads
			(clearance 0)
		)
		(min_thickness 0.25)
		(keepout
			(tracks not_allowed)
			(vias allowed)
			(pads allowed)
			(copperpour not_allowed)
			(footprints allowed)
		)
		(placement
			(enabled no)
			(sheetname "")
		)
		(fill
			(thermal_gap 0.5)
			(thermal_bridge_width 0.5)
			(island_removal_mode 0)
		)
		(polygon
			(pts
				(arc
					(start 81.141824 -439.760614)
					(mid 81.164142 -439.814496)
					(end 81.218024 -439.836814)
				)
				(arc
					(start 82.157824 -439.836814)
					(mid 82.211706 -439.814496)
					(end 82.234024 -439.760614)
				)
				(arc
					(start 82.234024 -437.21909)
					(mid 82.211706 -437.165208)
					(end 82.157824 -437.14289)
				)
				(arc
					(start 81.218024 -437.14289)
					(mid 81.164142 -437.165208)
					(end 81.141824 -437.21909)
				)
				(arc
					(start 81.141824 -437.946546)
					(mid 81.143823 -437.963887)
					(end 81.149698 -437.980328)
				)
				(arc
					(start 81.383124 -438.456578)
					(mid 81.390907 -438.490106)
					(end 81.383124 -438.523634)
				)
				(arc
					(start 81.149698 -438.999884)
					(mid 81.143803 -439.01632)
					(end 81.141824 -439.033666)
				)
			)
		)
	)
	(zone
		(layer "In14.Cu")
		(hatch none 0.5)
		(connect_pads
			(clearance 0)
		)
		(min_thickness 0.25)
		(keepout
			(tracks not_allowed)
			(vias allowed)
			(pads allowed)
			(copperpour not_allowed)
			(footprints allowed)
		)
		(placement
			(enabled no)
			(sheetname "")
		)
		(fill
			(thermal_gap 0.5)
			(thermal_bridge_width 0.5)
			(island_removal_mode 0)
		)
		(polygon
			(pts
				(arc
					(start 316.141862 -439.760614)
					(mid 316.16418 -439.814496)
					(end 316.218062 -439.836814)
				)
				(arc
					(start 317.157862 -439.836814)
					(mid 317.211744 -439.814496)
					(end 317.234062 -439.760614)
				)
				(arc
					(start 317.234062 -437.21909)
					(mid 317.211744 -437.165208)
					(end 317.157862 -437.14289)
				)
				(arc
					(start 316.218062 -437.14289)
					(mid 316.16418 -437.165208)
					(end 316.141862 -437.21909)
				)
				(arc
					(start 316.141862 -437.946546)
					(mid 316.143861 -437.963887)
					(end 316.149736 -437.980328)
				)
				(arc
					(start 316.383162 -438.456578)
					(mid 316.390945 -438.490106)
					(end 316.383162 -438.523634)
				)
				(arc
					(start 316.149736 -438.999884)
					(mid 316.143841 -439.01632)
					(end 316.141862 -439.033666)
				)
			)
		)
	)
	(zone
		(layer "In14.Cu")
		(hatch none 0.5)
		(connect_pads
			(clearance 0)
		)
		(min_thickness 0.25)
		(keepout
			(tracks not_allowed)
			(vias allowed)
			(pads allowed)
			(copperpour not_allowed)
			(footprints allowed)
		)
		(placement
			(enabled no)
			(sheetname "")
		)
		(fill
			(thermal_gap 0.5)
			(thermal_bridge_width 0.5)
			(island_removal_mode 0)
		)
		(polygon
			(pts
				(arc
					(start 331.141832 -435.160674)
					(mid 331.16415 -435.214556)
					(end 331.218032 -435.236874)
				)
				(arc
					(start 332.157832 -435.236874)
					(mid 332.211714 -435.214556)
					(end 332.234032 -435.160674)
				)
				(arc
					(start 332.234032 -432.61915)
					(mid 332.211714 -432.565268)
					(end 332.157832 -432.54295)
				)
				(arc
					(start 331.218032 -432.54295)
					(mid 331.16415 -432.565268)
					(end 331.141832 -432.61915)
				)
				(arc
					(start 331.141832 -433.346606)
					(mid 331.143831 -433.363947)
					(end 331.149706 -433.380388)
				)
				(arc
					(start 331.383132 -433.856638)
					(mid 331.390915 -433.890166)
					(end 331.383132 -433.923694)
				)
				(arc
					(start 331.149706 -434.399944)
					(mid 331.143811 -434.41638)
					(end 331.141832 -434.433726)
				)
			)
		)
	)
	(zone
		(layer "In14.Cu")
		(hatch none 0.5)
		(connect_pads
			(clearance 0)
		)
		(min_thickness 0.25)
		(keepout
			(tracks not_allowed)
			(vias allowed)
			(pads allowed)
			(copperpour not_allowed)
			(footprints allowed)
		)
		(placement
			(enabled no)
			(sheetname "")
		)
		(fill
			(thermal_gap 0.5)
			(thermal_bridge_width 0.5)
			(island_removal_mode 0)
		)
		(polygon
			(pts
				(arc
					(start 333.141828 -436.160672)
					(mid 333.164146 -436.214554)
					(end 333.218028 -436.236872)
				)
				(arc
					(start 334.157828 -436.236872)
					(mid 334.21171 -436.214554)
					(end 334.234028 -436.160672)
				)
				(arc
					(start 334.234028 -433.619148)
					(mid 334.21171 -433.565266)
					(end 334.157828 -433.542948)
				)
				(arc
					(start 333.218028 -433.542948)
					(mid 333.164146 -433.565266)
					(end 333.141828 -433.619148)
				)
				(arc
					(start 333.141828 -434.346604)
					(mid 333.143827 -434.363945)
					(end 333.149702 -434.380386)
				)
				(arc
					(start 333.383128 -434.856636)
					(mid 333.390911 -434.890164)
					(end 333.383128 -434.923692)
				)
				(arc
					(start 333.149702 -435.399942)
					(mid 333.143807 -435.416378)
					(end 333.141828 -435.433724)
				)
			)
		)
	)
	(zone
		(layer "In14.Cu")
		(hatch none 0.5)
		(connect_pads
			(clearance 0)
		)
		(min_thickness 0.25)
		(keepout
			(tracks not_allowed)
			(vias allowed)
			(pads allowed)
			(copperpour not_allowed)
			(footprints allowed)
		)
		(placement
			(enabled no)
			(sheetname "")
		)
		(fill
			(thermal_gap 0.5)
			(thermal_bridge_width 0.5)
			(island_removal_mode 0)
		)
		(polygon
			(pts
				(xy 209.364326 -402.696934) (xy 209.364326 -401.100544) (xy 211.017358 -401.100544) (xy 211.017358 -402.696934)
			)
		)
	)
	(zone
		(layer "In14.Cu")
		(hatch none 0.5)
		(connect_pads
			(clearance 0)
		)
		(min_thickness 0.25)
		(keepout
			(tracks not_allowed)
			(vias allowed)
			(pads allowed)
			(copperpour not_allowed)
			(footprints allowed)
		)
		(placement
			(enabled no)
			(sheetname "")
		)
		(fill
			(thermal_gap 0.5)
			(thermal_bridge_width 0.5)
			(island_removal_mode 0)
		)
		(polygon
			(pts
				(arc
					(start 146.242024 -435.160674)
					(mid 146.264342 -435.214556)
					(end 146.318224 -435.236874)
				)
				(arc
					(start 147.258024 -435.236874)
					(mid 147.311906 -435.214556)
					(end 147.334224 -435.160674)
				)
				(arc
					(start 147.334224 -432.61915)
					(mid 147.311906 -432.565268)
					(end 147.258024 -432.54295)
				)
				(arc
					(start 146.318224 -432.54295)
					(mid 146.264342 -432.565268)
					(end 146.242024 -432.61915)
				)
				(arc
					(start 146.242024 -433.346606)
					(mid 146.244023 -433.363947)
					(end 146.249898 -433.380388)
				)
				(arc
					(start 146.483324 -433.856638)
					(mid 146.491107 -433.890166)
					(end 146.483324 -433.923694)
				)
				(arc
					(start 146.249898 -434.399944)
					(mid 146.244003 -434.41638)
					(end 146.242024 -434.433726)
				)
			)
		)
	)
	(zone
		(layer "In14.Cu")
		(hatch none 0.5)
		(connect_pads
			(clearance 0)
		)
		(min_thickness 0.25)
		(keepout
			(tracks not_allowed)
			(vias allowed)
			(pads allowed)
			(copperpour not_allowed)
			(footprints allowed)
		)
		(placement
			(enabled no)
			(sheetname "")
		)
		(fill
			(thermal_gap 0.5)
			(thermal_bridge_width 0.5)
			(island_removal_mode 0)
		)
		(polygon
			(pts
				(arc
					(start 389.242046 -438.760616)
					(mid 389.264364 -438.814498)
					(end 389.318246 -438.836816)
				)
				(arc
					(start 390.258046 -438.836816)
					(mid 390.311928 -438.814498)
					(end 390.334246 -438.760616)
				)
				(arc
					(start 390.334246 -436.219092)
					(mid 390.311928 -436.16521)
					(end 390.258046 -436.142892)
				)
				(arc
					(start 389.318246 -436.142892)
					(mid 389.264364 -436.16521)
					(end 389.242046 -436.219092)
				)
				(arc
					(start 389.242046 -436.946548)
					(mid 389.244045 -436.963889)
					(end 389.24992 -436.98033)
				)
				(arc
					(start 389.483346 -437.45658)
					(mid 389.491129 -437.490108)
					(end 389.483346 -437.523636)
				)
				(arc
					(start 389.24992 -437.999886)
					(mid 389.244025 -438.016322)
					(end 389.242046 -438.033668)
				)
			)
		)
	)
	(zone
		(layer "In14.Cu")
		(hatch none 0.5)
		(connect_pads
			(clearance 0)
		)
		(min_thickness 0.25)
		(keepout
			(tracks not_allowed)
			(vias allowed)
			(pads allowed)
			(copperpour not_allowed)
			(footprints allowed)
		)
		(placement
			(enabled no)
			(sheetname "")
		)
		(fill
			(thermal_gap 0.5)
			(thermal_bridge_width 0.5)
			(island_removal_mode 0)
		)
		(polygon
			(pts
				(arc
					(start 150.242016 -435.160674)
					(mid 150.264334 -435.214556)
					(end 150.318216 -435.236874)
				)
				(arc
					(start 151.258016 -435.236874)
					(mid 151.311898 -435.214556)
					(end 151.334216 -435.160674)
				)
				(arc
					(start 151.334216 -432.61915)
					(mid 151.311898 -432.565268)
					(end 151.258016 -432.54295)
				)
				(arc
					(start 150.318216 -432.54295)
					(mid 150.264334 -432.565268)
					(end 150.242016 -432.61915)
				)
				(arc
					(start 150.242016 -433.346606)
					(mid 150.244015 -433.363947)
					(end 150.24989 -433.380388)
				)
				(arc
					(start 150.483316 -433.856638)
					(mid 150.491099 -433.890166)
					(end 150.483316 -433.923694)
				)
				(arc
					(start 150.24989 -434.399944)
					(mid 150.243995 -434.41638)
					(end 150.242016 -434.433726)
				)
			)
		)
	)
	(zone
		(layer "In14.Cu")
		(hatch none 0.5)
		(connect_pads
			(clearance 0)
		)
		(min_thickness 0.25)
		(keepout
			(tracks not_allowed)
			(vias allowed)
			(pads allowed)
			(copperpour not_allowed)
			(footprints allowed)
		)
		(placement
			(enabled no)
			(sheetname "")
		)
		(fill
			(thermal_gap 0.5)
			(thermal_bridge_width 0.5)
			(island_removal_mode 0)
		)
		(polygon
			(pts
				(arc
					(start 326.141842 -438.760616)
					(mid 326.16416 -438.814498)
					(end 326.218042 -438.836816)
				)
				(arc
					(start 327.157842 -438.836816)
					(mid 327.211724 -438.814498)
					(end 327.234042 -438.760616)
				)
				(arc
					(start 327.234042 -436.219092)
					(mid 327.211724 -436.16521)
					(end 327.157842 -436.142892)
				)
				(arc
					(start 326.218042 -436.142892)
					(mid 326.16416 -436.16521)
					(end 326.141842 -436.219092)
				)
				(arc
					(start 326.141842 -436.946548)
					(mid 326.143841 -436.963889)
					(end 326.149716 -436.98033)
				)
				(arc
					(start 326.383142 -437.45658)
					(mid 326.390925 -437.490108)
					(end 326.383142 -437.523636)
				)
				(arc
					(start 326.149716 -437.999886)
					(mid 326.143821 -438.016322)
					(end 326.141842 -438.033668)
				)
			)
		)
	)
	(zone
		(layer "In14.Cu")
		(hatch none 0.5)
		(connect_pads
			(clearance 0)
		)
		(min_thickness 0.25)
		(keepout
			(tracks not_allowed)
			(vias allowed)
			(pads allowed)
			(copperpour not_allowed)
			(footprints allowed)
		)
		(placement
			(enabled no)
			(sheetname "")
		)
		(fill
			(thermal_gap 0.5)
			(thermal_bridge_width 0.5)
			(island_removal_mode 0)
		)
		(polygon
			(pts
				(arc
					(start 75.141836 -435.160674)
					(mid 75.164154 -435.214556)
					(end 75.218036 -435.236874)
				)
				(arc
					(start 76.157836 -435.236874)
					(mid 76.211718 -435.214556)
					(end 76.234036 -435.160674)
				)
				(arc
					(start 76.234036 -432.61915)
					(mid 76.211718 -432.565268)
					(end 76.157836 -432.54295)
				)
				(arc
					(start 75.218036 -432.54295)
					(mid 75.164154 -432.565268)
					(end 75.141836 -432.61915)
				)
				(arc
					(start 75.141836 -433.346606)
					(mid 75.143835 -433.363947)
					(end 75.14971 -433.380388)
				)
				(arc
					(start 75.383136 -433.856638)
					(mid 75.390919 -433.890166)
					(end 75.383136 -433.923694)
				)
				(arc
					(start 75.14971 -434.399944)
					(mid 75.143815 -434.41638)
					(end 75.141836 -434.433726)
				)
			)
		)
	)
	(zone
		(layer "In14.Cu")
		(hatch none 0.5)
		(connect_pads
			(clearance 0)
		)
		(min_thickness 0.25)
		(keepout
			(tracks not_allowed)
			(vias allowed)
			(pads allowed)
			(copperpour not_allowed)
			(footprints allowed)
		)
		(placement
			(enabled no)
			(sheetname "")
		)
		(fill
			(thermal_gap 0.5)
			(thermal_bridge_width 0.5)
			(island_removal_mode 0)
		)
		(polygon
			(pts
				(arc
					(start 77.141832 -439.760614)
					(mid 77.16415 -439.814496)
					(end 77.218032 -439.836814)
				)
				(arc
					(start 78.157832 -439.836814)
					(mid 78.211714 -439.814496)
					(end 78.234032 -439.760614)
				)
				(arc
					(start 78.234032 -437.21909)
					(mid 78.211714 -437.165208)
					(end 78.157832 -437.14289)
				)
				(arc
					(start 77.218032 -437.14289)
					(mid 77.16415 -437.165208)
					(end 77.141832 -437.21909)
				)
				(arc
					(start 77.141832 -437.946546)
					(mid 77.143831 -437.963887)
					(end 77.149706 -437.980328)
				)
				(arc
					(start 77.383132 -438.456578)
					(mid 77.390915 -438.490106)
					(end 77.383132 -438.523634)
				)
				(arc
					(start 77.149706 -438.999884)
					(mid 77.143811 -439.01632)
					(end 77.141832 -439.033666)
				)
			)
		)
	)
	(zone
		(layer "In14.Cu")
		(hatch none 0.5)
		(connect_pads
			(clearance 0)
		)
		(min_thickness 0.25)
		(keepout
			(tracks not_allowed)
			(vias allowed)
			(pads allowed)
			(copperpour not_allowed)
			(footprints allowed)
		)
		(placement
			(enabled no)
			(sheetname "")
		)
		(fill
			(thermal_gap 0.5)
			(thermal_bridge_width 0.5)
			(island_removal_mode 0)
		)
		(polygon
			(pts
				(arc
					(start 85.141816 -439.760614)
					(mid 85.164134 -439.814496)
					(end 85.218016 -439.836814)
				)
				(arc
					(start 86.157816 -439.836814)
					(mid 86.211698 -439.814496)
					(end 86.234016 -439.760614)
				)
				(arc
					(start 86.234016 -437.21909)
					(mid 86.211698 -437.165208)
					(end 86.157816 -437.14289)
				)
				(arc
					(start 85.218016 -437.14289)
					(mid 85.164134 -437.165208)
					(end 85.141816 -437.21909)
				)
				(arc
					(start 85.141816 -437.946546)
					(mid 85.143815 -437.963887)
					(end 85.14969 -437.980328)
				)
				(arc
					(start 85.383116 -438.456578)
					(mid 85.390899 -438.490106)
					(end 85.383116 -438.523634)
				)
				(arc
					(start 85.14969 -438.999884)
					(mid 85.143795 -439.01632)
					(end 85.141816 -439.033666)
				)
			)
		)
	)
	(zone
		(layer "In14.Cu")
		(hatch none 0.5)
		(connect_pads
			(clearance 0)
		)
		(min_thickness 0.25)
		(keepout
			(tracks not_allowed)
			(vias allowed)
			(pads allowed)
			(copperpour not_allowed)
			(footprints allowed)
		)
		(placement
			(enabled no)
			(sheetname "")
		)
		(fill
			(thermal_gap 0.5)
			(thermal_bridge_width 0.5)
			(island_removal_mode 0)
		)
		(polygon
			(pts
				(arc
					(start 400.242024 -436.160672)
					(mid 400.264342 -436.214554)
					(end 400.318224 -436.236872)
				)
				(arc
					(start 401.258024 -436.236872)
					(mid 401.311906 -436.214554)
					(end 401.334224 -436.160672)
				)
				(arc
					(start 401.334224 -433.619148)
					(mid 401.311906 -433.565266)
					(end 401.258024 -433.542948)
				)
				(arc
					(start 400.318224 -433.542948)
					(mid 400.264342 -433.565266)
					(end 400.242024 -433.619148)
				)
				(arc
					(start 400.242024 -434.346604)
					(mid 400.244023 -434.363945)
					(end 400.249898 -434.380386)
				)
				(arc
					(start 400.483324 -434.856636)
					(mid 400.491107 -434.890164)
					(end 400.483324 -434.923692)
				)
				(arc
					(start 400.249898 -435.399942)
					(mid 400.244003 -435.416378)
					(end 400.242024 -435.433724)
				)
			)
		)
	)
	(zone
		(layer "In14.Cu")
		(hatch none 0.5)
		(connect_pads
			(clearance 0)
		)
		(min_thickness 0.25)
		(keepout
			(tracks not_allowed)
			(vias allowed)
			(pads allowed)
			(copperpour not_allowed)
			(footprints allowed)
		)
		(placement
			(enabled no)
			(sheetname "")
		)
		(fill
			(thermal_gap 0.5)
			(thermal_bridge_width 0.5)
			(island_removal_mode 0)
		)
		(polygon
			(pts
				(arc
					(start 314.141866 -438.760616)
					(mid 314.164184 -438.814498)
					(end 314.218066 -438.836816)
				)
				(arc
					(start 315.157866 -438.836816)
					(mid 315.211748 -438.814498)
					(end 315.234066 -438.760616)
				)
				(arc
					(start 315.234066 -436.219092)
					(mid 315.211748 -436.16521)
					(end 315.157866 -436.142892)
				)
				(arc
					(start 314.218066 -436.142892)
					(mid 314.164184 -436.16521)
					(end 314.141866 -436.219092)
				)
				(arc
					(start 314.141866 -436.946548)
					(mid 314.143865 -436.963889)
					(end 314.14974 -436.98033)
				)
				(arc
					(start 314.383166 -437.45658)
					(mid 314.390949 -437.490108)
					(end 314.383166 -437.523636)
				)
				(arc
					(start 314.14974 -437.999886)
					(mid 314.143845 -438.016322)
					(end 314.141866 -438.033668)
				)
			)
		)
	)
	(zone
		(layer "In14.Cu")
		(hatch none 0.5)
		(connect_pads
			(clearance 0)
		)
		(min_thickness 0.25)
		(keepout
			(tracks not_allowed)
			(vias allowed)
			(pads allowed)
			(copperpour not_allowed)
			(footprints allowed)
		)
		(placement
			(enabled no)
			(sheetname "")
		)
		(fill
			(thermal_gap 0.5)
			(thermal_bridge_width 0.5)
			(island_removal_mode 0)
		)
		(polygon
			(pts
				(arc
					(start 391.242042 -439.760614)
					(mid 391.26436 -439.814496)
					(end 391.318242 -439.836814)
				)
				(arc
					(start 392.258042 -439.836814)
					(mid 392.311924 -439.814496)
					(end 392.334242 -439.760614)
				)
				(arc
					(start 392.334242 -437.21909)
					(mid 392.311924 -437.165208)
					(end 392.258042 -437.14289)
				)
				(arc
					(start 391.318242 -437.14289)
					(mid 391.26436 -437.165208)
					(end 391.242042 -437.21909)
				)
				(arc
					(start 391.242042 -437.946546)
					(mid 391.244041 -437.963887)
					(end 391.249916 -437.980328)
				)
				(arc
					(start 391.483342 -438.456578)
					(mid 391.491125 -438.490106)
					(end 391.483342 -438.523634)
				)
				(arc
					(start 391.249916 -438.999884)
					(mid 391.244021 -439.01632)
					(end 391.242042 -439.033666)
				)
			)
		)
	)
	(zone
		(layer "In14.Cu")
		(hatch none 0.5)
		(connect_pads
			(clearance 0)
		)
		(min_thickness 0.25)
		(keepout
			(tracks not_allowed)
			(vias allowed)
			(pads allowed)
			(copperpour not_allowed)
			(footprints allowed)
		)
		(placement
			(enabled no)
			(sheetname "")
		)
		(fill
			(thermal_gap 0.5)
			(thermal_bridge_width 0.5)
			(island_removal_mode 0)
		)
		(polygon
			(pts
				(arc
					(start 131.2418 -436.160672)
					(mid 131.264118 -436.214554)
					(end 131.318 -436.236872)
				)
				(arc
					(start 132.2578 -436.236872)
					(mid 132.311682 -436.214554)
					(end 132.334 -436.160672)
				)
				(arc
					(start 132.334 -433.619148)
					(mid 132.311682 -433.565266)
					(end 132.2578 -433.542948)
				)
				(arc
					(start 131.318 -433.542948)
					(mid 131.264118 -433.565266)
					(end 131.2418 -433.619148)
				)
				(arc
					(start 131.2418 -434.346604)
					(mid 131.243799 -434.363945)
					(end 131.249674 -434.380386)
				)
				(arc
					(start 131.4831 -434.856636)
					(mid 131.490883 -434.890164)
					(end 131.4831 -434.923692)
				)
				(arc
					(start 131.249674 -435.399942)
					(mid 131.243779 -435.416378)
					(end 131.2418 -435.433724)
				)
			)
		)
	)
	(zone
		(layer "In14.Cu")
		(hatch none 0.5)
		(connect_pads
			(clearance 0)
		)
		(min_thickness 0.25)
		(keepout
			(tracks not_allowed)
			(vias allowed)
			(pads allowed)
			(copperpour not_allowed)
			(footprints allowed)
		)
		(placement
			(enabled no)
			(sheetname "")
		)
		(fill
			(thermal_gap 0.5)
			(thermal_bridge_width 0.5)
			(island_removal_mode 0)
		)
		(polygon
			(pts
				(arc
					(start 139.241784 -436.160672)
					(mid 139.264102 -436.214554)
					(end 139.317984 -436.236872)
				)
				(arc
					(start 140.257784 -436.236872)
					(mid 140.311666 -436.214554)
					(end 140.333984 -436.160672)
				)
				(arc
					(start 140.333984 -433.619148)
					(mid 140.311666 -433.565266)
					(end 140.257784 -433.542948)
				)
				(arc
					(start 139.317984 -433.542948)
					(mid 139.264102 -433.565266)
					(end 139.241784 -433.619148)
				)
				(arc
					(start 139.241784 -434.346604)
					(mid 139.243783 -434.363945)
					(end 139.249658 -434.380386)
				)
				(arc
					(start 139.483084 -434.856636)
					(mid 139.490867 -434.890164)
					(end 139.483084 -434.923692)
				)
				(arc
					(start 139.249658 -435.399942)
					(mid 139.243763 -435.416378)
					(end 139.241784 -435.433724)
				)
			)
		)
	)
	(zone
		(layer "In14.Cu")
		(hatch none 0.5)
		(connect_pads
			(clearance 0)
		)
		(min_thickness 0.25)
		(keepout
			(tracks not_allowed)
			(vias allowed)
			(pads allowed)
			(copperpour not_allowed)
			(footprints allowed)
		)
		(placement
			(enabled no)
			(sheetname "")
		)
		(fill
			(thermal_gap 0.5)
			(thermal_bridge_width 0.5)
			(island_removal_mode 0)
		)
		(polygon
			(pts
				(arc
					(start 156.242004 -436.160672)
					(mid 156.264322 -436.214554)
					(end 156.318204 -436.236872)
				)
				(arc
					(start 157.258004 -436.236872)
					(mid 157.311886 -436.214554)
					(end 157.334204 -436.160672)
				)
				(arc
					(start 157.334204 -433.619148)
					(mid 157.311886 -433.565266)
					(end 157.258004 -433.542948)
				)
				(arc
					(start 156.318204 -433.542948)
					(mid 156.264322 -433.565266)
					(end 156.242004 -433.619148)
				)
				(arc
					(start 156.242004 -434.346604)
					(mid 156.244003 -434.363945)
					(end 156.249878 -434.380386)
				)
				(arc
					(start 156.483304 -434.856636)
					(mid 156.491087 -434.890164)
					(end 156.483304 -434.923692)
				)
				(arc
					(start 156.249878 -435.399942)
					(mid 156.243983 -435.416378)
					(end 156.242004 -435.433724)
				)
			)
		)
	)
	(zone
		(layer "In14.Cu")
		(hatch none 0.5)
		(connect_pads
			(clearance 0)
		)
		(min_thickness 0.25)
		(keepout
			(tracks not_allowed)
			(vias allowed)
			(pads allowed)
			(copperpour not_allowed)
			(footprints allowed)
		)
		(placement
			(enabled no)
			(sheetname "")
		)
		(fill
			(thermal_gap 0.5)
			(thermal_bridge_width 0.5)
			(island_removal_mode 0)
		)
		(polygon
			(pts
				(arc
					(start 85.141816 -436.160672)
					(mid 85.164134 -436.214554)
					(end 85.218016 -436.236872)
				)
				(arc
					(start 86.157816 -436.236872)
					(mid 86.211698 -436.214554)
					(end 86.234016 -436.160672)
				)
				(arc
					(start 86.234016 -433.619148)
					(mid 86.211698 -433.565266)
					(end 86.157816 -433.542948)
				)
				(arc
					(start 85.218016 -433.542948)
					(mid 85.164134 -433.565266)
					(end 85.141816 -433.619148)
				)
				(arc
					(start 85.141816 -434.346604)
					(mid 85.143815 -434.363945)
					(end 85.14969 -434.380386)
				)
				(arc
					(start 85.383116 -434.856636)
					(mid 85.390899 -434.890164)
					(end 85.383116 -434.923692)
				)
				(arc
					(start 85.14969 -435.399942)
					(mid 85.143795 -435.416378)
					(end 85.141816 -435.433724)
				)
			)
		)
	)
	(zone
		(layer "In14.Cu")
		(hatch none 0.5)
		(connect_pads
			(clearance 0)
		)
		(min_thickness 0.25)
		(keepout
			(tracks not_allowed)
			(vias allowed)
			(pads allowed)
			(copperpour not_allowed)
			(footprints allowed)
		)
		(placement
			(enabled no)
			(sheetname "")
		)
		(fill
			(thermal_gap 0.5)
			(thermal_bridge_width 0.5)
			(island_removal_mode 0)
		)
		(polygon
			(pts
				(arc
					(start 318.141858 -438.760616)
					(mid 318.164176 -438.814498)
					(end 318.218058 -438.836816)
				)
				(arc
					(start 319.157858 -438.836816)
					(mid 319.21174 -438.814498)
					(end 319.234058 -438.760616)
				)
				(arc
					(start 319.234058 -436.219092)
					(mid 319.21174 -436.16521)
					(end 319.157858 -436.142892)
				)
				(arc
					(start 318.218058 -436.142892)
					(mid 318.164176 -436.16521)
					(end 318.141858 -436.219092)
				)
				(arc
					(start 318.141858 -436.946548)
					(mid 318.143857 -436.963889)
					(end 318.149732 -436.98033)
				)
				(arc
					(start 318.383158 -437.45658)
					(mid 318.390941 -437.490108)
					(end 318.383158 -437.523636)
				)
				(arc
					(start 318.149732 -437.999886)
					(mid 318.143837 -438.016322)
					(end 318.141858 -438.033668)
				)
			)
		)
	)
	(zone
		(layer "In14.Cu")
		(hatch none 0.5)
		(connect_pads
			(clearance 0)
		)
		(min_thickness 0.25)
		(keepout
			(tracks not_allowed)
			(vias allowed)
			(pads allowed)
			(copperpour not_allowed)
			(footprints allowed)
		)
		(placement
			(enabled no)
			(sheetname "")
		)
		(fill
			(thermal_gap 0.5)
			(thermal_bridge_width 0.5)
			(island_removal_mode 0)
		)
		(polygon
			(pts
				(arc
					(start 77.141832 -436.160672)
					(mid 77.16415 -436.214554)
					(end 77.218032 -436.236872)
				)
				(arc
					(start 78.157832 -436.236872)
					(mid 78.211714 -436.214554)
					(end 78.234032 -436.160672)
				)
				(arc
					(start 78.234032 -433.619148)
					(mid 78.211714 -433.565266)
					(end 78.157832 -433.542948)
				)
				(arc
					(start 77.218032 -433.542948)
					(mid 77.16415 -433.565266)
					(end 77.141832 -433.619148)
				)
				(arc
					(start 77.141832 -434.346604)
					(mid 77.143831 -434.363945)
					(end 77.149706 -434.380386)
				)
				(arc
					(start 77.383132 -434.856636)
					(mid 77.390915 -434.890164)
					(end 77.383132 -434.923692)
				)
				(arc
					(start 77.149706 -435.399942)
					(mid 77.143811 -435.416378)
					(end 77.141832 -435.433724)
				)
			)
		)
	)
	(zone
		(layer "In14.Cu")
		(hatch none 0.5)
		(connect_pads
			(clearance 0)
		)
		(min_thickness 0.25)
		(keepout
			(tracks not_allowed)
			(vias allowed)
			(pads allowed)
			(copperpour not_allowed)
			(footprints allowed)
		)
		(placement
			(enabled no)
			(sheetname "")
		)
		(fill
			(thermal_gap 0.5)
			(thermal_bridge_width 0.5)
			(island_removal_mode 0)
		)
		(polygon
			(pts
				(xy 185.463942 -402.714714) (xy 185.463942 -401.131024) (xy 187.085478 -401.131024) (xy 187.085478 -402.714714)
			)
		)
	)
	(zone
		(layer "In14.Cu")
		(hatch none 0.5)
		(connect_pads
			(clearance 0)
		)
		(min_thickness 0.25)
		(keepout
			(tracks not_allowed)
			(vias allowed)
			(pads allowed)
			(copperpour not_allowed)
			(footprints allowed)
		)
		(placement
			(enabled no)
			(sheetname "")
		)
		(fill
			(thermal_gap 0.5)
			(thermal_bridge_width 0.5)
			(island_removal_mode 0)
		)
		(polygon
			(pts
				(arc
					(start 154.241754 -438.760616)
					(mid 154.264072 -438.814498)
					(end 154.317954 -438.836816)
				)
				(arc
					(start 155.257754 -438.836816)
					(mid 155.311636 -438.814498)
					(end 155.333954 -438.760616)
				)
				(arc
					(start 155.333954 -436.219092)
					(mid 155.311636 -436.16521)
					(end 155.257754 -436.142892)
				)
				(arc
					(start 154.317954 -436.142892)
					(mid 154.264072 -436.16521)
					(end 154.241754 -436.219092)
				)
				(arc
					(start 154.241754 -436.946548)
					(mid 154.243753 -436.963889)
					(end 154.249628 -436.98033)
				)
				(arc
					(start 154.483054 -437.45658)
					(mid 154.490837 -437.490108)
					(end 154.483054 -437.523636)
				)
				(arc
					(start 154.249628 -437.999886)
					(mid 154.243733 -438.016322)
					(end 154.241754 -438.033668)
				)
			)
		)
	)
	(zone
		(layer "In14.Cu")
		(hatch none 0.5)
		(connect_pads
			(clearance 0)
		)
		(min_thickness 0.25)
		(keepout
			(tracks not_allowed)
			(vias allowed)
			(pads allowed)
			(copperpour not_allowed)
			(footprints allowed)
		)
		(placement
			(enabled no)
			(sheetname "")
		)
		(fill
			(thermal_gap 0.5)
			(thermal_bridge_width 0.5)
			(island_removal_mode 0)
		)
		(polygon
			(pts
				(arc
					(start 133.241796 -435.160674)
					(mid 133.264114 -435.214556)
					(end 133.317996 -435.236874)
				)
				(arc
					(start 134.257796 -435.236874)
					(mid 134.311678 -435.214556)
					(end 134.333996 -435.160674)
				)
				(arc
					(start 134.333996 -432.61915)
					(mid 134.311678 -432.565268)
					(end 134.257796 -432.54295)
				)
				(arc
					(start 133.317996 -432.54295)
					(mid 133.264114 -432.565268)
					(end 133.241796 -432.61915)
				)
				(arc
					(start 133.241796 -433.346606)
					(mid 133.243795 -433.363947)
					(end 133.24967 -433.380388)
				)
				(arc
					(start 133.483096 -433.856638)
					(mid 133.490879 -433.890166)
					(end 133.483096 -433.923694)
				)
				(arc
					(start 133.24967 -434.399944)
					(mid 133.243775 -434.41638)
					(end 133.241796 -434.433726)
				)
			)
		)
	)
	(zone
		(layer "In14.Cu")
		(hatch none 0.5)
		(connect_pads
			(clearance 0)
		)
		(min_thickness 0.25)
		(keepout
			(tracks not_allowed)
			(vias allowed)
			(pads allowed)
			(copperpour not_allowed)
			(footprints allowed)
		)
		(placement
			(enabled no)
			(sheetname "")
		)
		(fill
			(thermal_gap 0.5)
			(thermal_bridge_width 0.5)
			(island_removal_mode 0)
		)
		(polygon
			(pts
				(arc
					(start 410.242004 -435.160674)
					(mid 410.264322 -435.214556)
					(end 410.318204 -435.236874)
				)
				(arc
					(start 411.258004 -435.236874)
					(mid 411.311886 -435.214556)
					(end 411.334204 -435.160674)
				)
				(arc
					(start 411.334204 -432.61915)
					(mid 411.311886 -432.565268)
					(end 411.258004 -432.54295)
				)
				(arc
					(start 410.318204 -432.54295)
					(mid 410.264322 -432.565268)
					(end 410.242004 -432.61915)
				)
				(arc
					(start 410.242004 -433.346606)
					(mid 410.244003 -433.363947)
					(end 410.249878 -433.380388)
				)
				(arc
					(start 410.483304 -433.856638)
					(mid 410.491087 -433.890166)
					(end 410.483304 -433.923694)
				)
				(arc
					(start 410.249878 -434.399944)
					(mid 410.243983 -434.41638)
					(end 410.242004 -434.433726)
				)
			)
		)
	)
	(zone
		(layer "In14.Cu")
		(hatch none 0.5)
		(connect_pads
			(clearance 0)
		)
		(min_thickness 0.25)
		(keepout
			(tracks not_allowed)
			(vias allowed)
			(pads allowed)
			(copperpour not_allowed)
			(footprints allowed)
		)
		(placement
			(enabled no)
			(sheetname "")
		)
		(fill
			(thermal_gap 0.5)
			(thermal_bridge_width 0.5)
			(island_removal_mode 0)
		)
		(polygon
			(pts
				(arc
					(start 408.242008 -436.160672)
					(mid 408.264326 -436.214554)
					(end 408.318208 -436.236872)
				)
				(arc
					(start 409.258008 -436.236872)
					(mid 409.31189 -436.214554)
					(end 409.334208 -436.160672)
				)
				(arc
					(start 409.334208 -433.619148)
					(mid 409.31189 -433.565266)
					(end 409.258008 -433.542948)
				)
				(arc
					(start 408.318208 -433.542948)
					(mid 408.264326 -433.565266)
					(end 408.242008 -433.619148)
				)
				(arc
					(start 408.242008 -434.346604)
					(mid 408.244007 -434.363945)
					(end 408.249882 -434.380386)
				)
				(arc
					(start 408.483308 -434.856636)
					(mid 408.491091 -434.890164)
					(end 408.483308 -434.923692)
				)
				(arc
					(start 408.249882 -435.399942)
					(mid 408.243987 -435.416378)
					(end 408.242008 -435.433724)
				)
			)
		)
	)
	(zone
		(layer "In14.Cu")
		(hatch none 0.5)
		(connect_pads
			(clearance 0)
		)
		(min_thickness 0.25)
		(keepout
			(tracks not_allowed)
			(vias allowed)
			(pads allowed)
			(copperpour not_allowed)
			(footprints allowed)
		)
		(placement
			(enabled no)
			(sheetname "")
		)
		(fill
			(thermal_gap 0.5)
			(thermal_bridge_width 0.5)
			(island_removal_mode 0)
		)
		(polygon
			(pts
				(arc
					(start 335.141824 -435.160674)
					(mid 335.164142 -435.214556)
					(end 335.218024 -435.236874)
				)
				(arc
					(start 336.157824 -435.236874)
					(mid 336.211706 -435.214556)
					(end 336.234024 -435.160674)
				)
				(arc
					(start 336.234024 -432.61915)
					(mid 336.211706 -432.565268)
					(end 336.157824 -432.54295)
				)
				(arc
					(start 335.218024 -432.54295)
					(mid 335.164142 -432.565268)
					(end 335.141824 -432.61915)
				)
				(arc
					(start 335.141824 -433.346606)
					(mid 335.143823 -433.363947)
					(end 335.149698 -433.380388)
				)
				(arc
					(start 335.383124 -433.856638)
					(mid 335.390907 -433.890166)
					(end 335.383124 -433.923694)
				)
				(arc
					(start 335.149698 -434.399944)
					(mid 335.143803 -434.41638)
					(end 335.141824 -434.433726)
				)
			)
		)
	)
	(zone
		(layer "In14.Cu")
		(hatch none 0.5)
		(connect_pads
			(clearance 0)
		)
		(min_thickness 0.25)
		(keepout
			(tracks not_allowed)
			(vias allowed)
			(pads allowed)
			(copperpour not_allowed)
			(footprints allowed)
		)
		(placement
			(enabled no)
			(sheetname "")
		)
		(fill
			(thermal_gap 0.5)
			(thermal_bridge_width 0.5)
			(island_removal_mode 0)
		)
		(polygon
			(pts
				(arc
					(start 395.242034 -439.760614)
					(mid 395.264352 -439.814496)
					(end 395.318234 -439.836814)
				)
				(arc
					(start 396.258034 -439.836814)
					(mid 396.311916 -439.814496)
					(end 396.334234 -439.760614)
				)
				(arc
					(start 396.334234 -437.21909)
					(mid 396.311916 -437.165208)
					(end 396.258034 -437.14289)
				)
				(arc
					(start 395.318234 -437.14289)
					(mid 395.264352 -437.165208)
					(end 395.242034 -437.21909)
				)
				(arc
					(start 395.242034 -437.946546)
					(mid 395.244033 -437.963887)
					(end 395.249908 -437.980328)
				)
				(arc
					(start 395.483334 -438.456578)
					(mid 395.491117 -438.490106)
					(end 395.483334 -438.523634)
				)
				(arc
					(start 395.249908 -438.999884)
					(mid 395.244013 -439.01632)
					(end 395.242034 -439.033666)
				)
			)
		)
	)
	(zone
		(layer "In14.Cu")
		(hatch none 0.5)
		(connect_pads
			(clearance 0)
		)
		(min_thickness 0.25)
		(keepout
			(tracks not_allowed)
			(vias allowed)
			(pads allowed)
			(copperpour not_allowed)
			(footprints allowed)
		)
		(placement
			(enabled no)
			(sheetname "")
		)
		(fill
			(thermal_gap 0.5)
			(thermal_bridge_width 0.5)
			(island_removal_mode 0)
		)
		(polygon
			(pts
				(arc
					(start 385.242054 -438.760616)
					(mid 385.264372 -438.814498)
					(end 385.318254 -438.836816)
				)
				(arc
					(start 386.258054 -438.836816)
					(mid 386.311936 -438.814498)
					(end 386.334254 -438.760616)
				)
				(arc
					(start 386.334254 -436.219092)
					(mid 386.311936 -436.16521)
					(end 386.258054 -436.142892)
				)
				(arc
					(start 385.318254 -436.142892)
					(mid 385.264372 -436.16521)
					(end 385.242054 -436.219092)
				)
				(arc
					(start 385.242054 -436.946548)
					(mid 385.244053 -436.963889)
					(end 385.249928 -436.98033)
				)
				(arc
					(start 385.483354 -437.45658)
					(mid 385.491137 -437.490108)
					(end 385.483354 -437.523636)
				)
				(arc
					(start 385.249928 -437.999886)
					(mid 385.244033 -438.016322)
					(end 385.242054 -438.033668)
				)
			)
		)
	)
	(zone
		(layer "In14.Cu")
		(hatch none 0.5)
		(connect_pads
			(clearance 0)
		)
		(min_thickness 0.25)
		(keepout
			(tracks not_allowed)
			(vias allowed)
			(pads allowed)
			(copperpour not_allowed)
			(footprints allowed)
		)
		(placement
			(enabled no)
			(sheetname "")
		)
		(fill
			(thermal_gap 0.5)
			(thermal_bridge_width 0.5)
			(island_removal_mode 0)
		)
		(polygon
			(pts
				(arc
					(start 62.141862 -435.160674)
					(mid 62.16418 -435.214556)
					(end 62.218062 -435.236874)
				)
				(arc
					(start 63.157862 -435.236874)
					(mid 63.211744 -435.214556)
					(end 63.234062 -435.160674)
				)
				(arc
					(start 63.234062 -432.61915)
					(mid 63.211744 -432.565268)
					(end 63.157862 -432.54295)
				)
				(arc
					(start 62.218062 -432.54295)
					(mid 62.16418 -432.565268)
					(end 62.141862 -432.61915)
				)
				(arc
					(start 62.141862 -433.346606)
					(mid 62.143861 -433.363947)
					(end 62.149736 -433.380388)
				)
				(arc
					(start 62.383162 -433.856638)
					(mid 62.390945 -433.890166)
					(end 62.383162 -433.923694)
				)
				(arc
					(start 62.149736 -434.399944)
					(mid 62.143841 -434.41638)
					(end 62.141862 -434.433726)
				)
			)
		)
	)
	(zone
		(layer "In14.Cu")
		(hatch none 0.5)
		(connect_pads
			(clearance 0)
		)
		(min_thickness 0.25)
		(keepout
			(tracks not_allowed)
			(vias allowed)
			(pads allowed)
			(copperpour not_allowed)
			(footprints allowed)
		)
		(placement
			(enabled no)
			(sheetname "")
		)
		(fill
			(thermal_gap 0.5)
			(thermal_bridge_width 0.5)
			(island_removal_mode 0)
		)
		(polygon
			(pts
				(arc
					(start 387.24205 -439.760614)
					(mid 387.264368 -439.814496)
					(end 387.31825 -439.836814)
				)
				(arc
					(start 388.25805 -439.836814)
					(mid 388.311932 -439.814496)
					(end 388.33425 -439.760614)
				)
				(arc
					(start 388.33425 -437.21909)
					(mid 388.311932 -437.165208)
					(end 388.25805 -437.14289)
				)
				(arc
					(start 387.31825 -437.14289)
					(mid 387.264368 -437.165208)
					(end 387.24205 -437.21909)
				)
				(arc
					(start 387.24205 -437.946546)
					(mid 387.244049 -437.963887)
					(end 387.249924 -437.980328)
				)
				(arc
					(start 387.48335 -438.456578)
					(mid 387.491133 -438.490106)
					(end 387.48335 -438.523634)
				)
				(arc
					(start 387.249924 -438.999884)
					(mid 387.244029 -439.01632)
					(end 387.24205 -439.033666)
				)
			)
		)
	)
	(zone
		(layer "In14.Cu")
		(hatch none 0.5)
		(connect_pads
			(clearance 0)
		)
		(min_thickness 0.25)
		(keepout
			(tracks not_allowed)
			(vias allowed)
			(pads allowed)
			(copperpour not_allowed)
			(footprints allowed)
		)
		(placement
			(enabled no)
			(sheetname "")
		)
		(fill
			(thermal_gap 0.5)
			(thermal_bridge_width 0.5)
			(island_removal_mode 0)
		)
		(polygon
			(pts
				(arc
					(start 393.241784 -435.160674)
					(mid 393.264102 -435.214556)
					(end 393.317984 -435.236874)
				)
				(arc
					(start 394.257784 -435.236874)
					(mid 394.311666 -435.214556)
					(end 394.333984 -435.160674)
				)
				(arc
					(start 394.333984 -432.61915)
					(mid 394.311666 -432.565268)
					(end 394.257784 -432.54295)
				)
				(arc
					(start 393.317984 -432.54295)
					(mid 393.264102 -432.565268)
					(end 393.241784 -432.61915)
				)
				(arc
					(start 393.241784 -433.346606)
					(mid 393.243783 -433.363947)
					(end 393.249658 -433.380388)
				)
				(arc
					(start 393.483084 -433.856638)
					(mid 393.490867 -433.890166)
					(end 393.483084 -433.923694)
				)
				(arc
					(start 393.249658 -434.399944)
					(mid 393.243763 -434.41638)
					(end 393.241784 -434.433726)
				)
			)
		)
	)
	(zone
		(layer "In14.Cu")
		(hatch none 0.5)
		(connect_pads
			(clearance 0)
		)
		(min_thickness 0.25)
		(keepout
			(tracks not_allowed)
			(vias allowed)
			(pads allowed)
			(copperpour not_allowed)
			(footprints allowed)
		)
		(placement
			(enabled no)
			(sheetname "")
		)
		(fill
			(thermal_gap 0.5)
			(thermal_bridge_width 0.5)
			(island_removal_mode 0)
		)
		(polygon
			(pts
				(arc
					(start 79.141828 -435.160674)
					(mid 79.164146 -435.214556)
					(end 79.218028 -435.236874)
				)
				(arc
					(start 80.157828 -435.236874)
					(mid 80.21171 -435.214556)
					(end 80.234028 -435.160674)
				)
				(arc
					(start 80.234028 -432.61915)
					(mid 80.21171 -432.565268)
					(end 80.157828 -432.54295)
				)
				(arc
					(start 79.218028 -432.54295)
					(mid 79.164146 -432.565268)
					(end 79.141828 -432.61915)
				)
				(arc
					(start 79.141828 -433.346606)
					(mid 79.143827 -433.363947)
					(end 79.149702 -433.380388)
				)
				(arc
					(start 79.383128 -433.856638)
					(mid 79.390911 -433.890166)
					(end 79.383128 -433.923694)
				)
				(arc
					(start 79.149702 -434.399944)
					(mid 79.143807 -434.41638)
					(end 79.141828 -434.433726)
				)
			)
		)
	)
	(zone
		(layers "In14.Cu" "In16.Cu")
		(hatch none 0.5)
		(connect_pads
			(clearance 0)
		)
		(min_thickness 0.25)
		(keepout
			(tracks not_allowed)
			(vias allowed)
			(pads allowed)
			(copperpour not_allowed)
			(footprints allowed)
		)
		(placement
			(enabled no)
			(sheetname "")
		)
		(fill yes
			(thermal_gap 0.5)
			(thermal_bridge_width 0.5)
			(island_removal_mode 0)
		)
		(polygon
			(pts
				(arc
					(start 58.14187 -438.760616)
					(mid 58.164188 -438.814498)
					(end 58.21807 -438.836816)
				)
				(arc
					(start 59.15787 -438.836816)
					(mid 59.211752 -438.814498)
					(end 59.23407 -438.760616)
				)
				(arc
					(start 59.23407 -436.219092)
					(mid 59.211752 -436.16521)
					(end 59.15787 -436.142892)
				)
				(arc
					(start 58.21807 -436.142892)
					(mid 58.164188 -436.16521)
					(end 58.14187 -436.219092)
				)
				(arc
					(start 58.14187 -436.946548)
					(mid 58.143869 -436.963889)
					(end 58.149744 -436.98033)
				)
				(arc
					(start 58.38317 -437.45658)
					(mid 58.390953 -437.490108)
					(end 58.38317 -437.523636)
				)
				(arc
					(start 58.149744 -437.999886)
					(mid 58.143849 -438.016322)
					(end 58.14187 -438.033668)
				)
			)
		)
	)
	(zone
		(layers "In14.Cu" "In16.Cu")
		(hatch none 0.5)
		(connect_pads
			(clearance 0)
		)
		(min_thickness 0.25)
		(keepout
			(tracks not_allowed)
			(vias allowed)
			(pads allowed)
			(copperpour not_allowed)
			(footprints allowed)
		)
		(placement
			(enabled no)
			(sheetname "")
		)
		(fill yes
			(thermal_gap 0.5)
			(thermal_bridge_width 0.5)
			(island_removal_mode 0)
		)
		(polygon
			(pts
				(arc
					(start 315.93663 -394.552424)
					(mid 316.046601 -394.653478)
					(end 316.191392 -394.690092)
				)
				(arc
					(start 316.191392 -394.690092)
					(mid 316.406918 -394.600818)
					(end 316.496192 -394.385292)
				)
				(arc
					(start 316.496192 -394.385292)
					(mid 316.485855 -394.306553)
					(end 316.455552 -394.233146)
				)
				(arc
					(start 316.063122 -393.554204)
					(mid 315.950725 -393.432587)
					(end 315.791342 -393.38758)
				)
				(arc
					(start 315.791342 -393.38758)
					(mid 315.575816 -393.476854)
					(end 315.486542 -393.69238)
				)
				(arc
					(start 315.486542 -393.69238)
					(mid 315.49612 -393.768442)
					(end 315.524388 -393.8397)
				)
				(xy 315.921644 -394.527024) (xy 315.933836 -394.54836) (xy 315.936376 -394.552678)
			)
		)
	)
	(zone
		(layers "In14.Cu" "In16.Cu")
		(hatch none 0.5)
		(connect_pads
			(clearance 0)
		)
		(min_thickness 0.25)
		(keepout
			(tracks not_allowed)
			(vias allowed)
			(pads allowed)
			(copperpour not_allowed)
			(footprints allowed)
		)
		(placement
			(enabled no)
			(sheetname "")
		)
		(fill yes
			(thermal_gap 0.5)
			(thermal_bridge_width 0.5)
			(island_removal_mode 0)
		)
		(polygon
			(pts
				(arc
					(start 129.241804 -438.760616)
					(mid 129.264122 -438.814498)
					(end 129.318004 -438.836816)
				)
				(arc
					(start 130.257804 -438.836816)
					(mid 130.311686 -438.814498)
					(end 130.334004 -438.760616)
				)
				(arc
					(start 130.334004 -436.219092)
					(mid 130.311686 -436.16521)
					(end 130.257804 -436.142892)
				)
				(arc
					(start 129.318004 -436.142892)
					(mid 129.264122 -436.16521)
					(end 129.241804 -436.219092)
				)
				(arc
					(start 129.241804 -436.946548)
					(mid 129.243803 -436.963889)
					(end 129.249678 -436.98033)
				)
				(arc
					(start 129.483104 -437.45658)
					(mid 129.490887 -437.490108)
					(end 129.483104 -437.523636)
				)
				(arc
					(start 129.249678 -437.999886)
					(mid 129.243783 -438.016322)
					(end 129.241804 -438.033668)
				)
			)
		)
	)
	(zone
		(layers "In14.Cu" "In16.Cu")
		(hatch none 0.5)
		(connect_pads
			(clearance 0)
		)
		(min_thickness 0.25)
		(keepout
			(tracks not_allowed)
			(vias allowed)
			(pads allowed)
			(copperpour not_allowed)
			(footprints allowed)
		)
		(placement
			(enabled no)
			(sheetname "")
		)
		(fill yes
			(thermal_gap 0.5)
			(thermal_bridge_width 0.5)
			(island_removal_mode 0)
		)
		(polygon
			(pts
				(arc
					(start 64.141858 -439.760614)
					(mid 64.164176 -439.814496)
					(end 64.218058 -439.836814)
				)
				(arc
					(start 65.157858 -439.836814)
					(mid 65.21174 -439.814496)
					(end 65.234058 -439.760614)
				)
				(arc
					(start 65.234058 -437.21909)
					(mid 65.21174 -437.165208)
					(end 65.157858 -437.14289)
				)
				(arc
					(start 64.218058 -437.14289)
					(mid 64.164176 -437.165208)
					(end 64.141858 -437.21909)
				)
				(arc
					(start 64.141858 -437.946546)
					(mid 64.143857 -437.963887)
					(end 64.149732 -437.980328)
				)
				(arc
					(start 64.383158 -438.456578)
					(mid 64.390941 -438.490106)
					(end 64.383158 -438.523634)
				)
				(arc
					(start 64.149732 -438.999884)
					(mid 64.143837 -439.01632)
					(end 64.141858 -439.033666)
				)
			)
		)
	)
	(zone
		(layers "In14.Cu" "In16.Cu")
		(hatch none 0.5)
		(connect_pads
			(clearance 0)
		)
		(min_thickness 0.25)
		(keepout
			(tracks not_allowed)
			(vias allowed)
			(pads allowed)
			(copperpour not_allowed)
			(footprints allowed)
		)
		(placement
			(enabled no)
			(sheetname "")
		)
		(fill yes
			(thermal_gap 0.5)
			(thermal_bridge_width 0.5)
			(island_removal_mode 0)
		)
		(polygon
			(pts
				(arc
					(start 406.242012 -438.760616)
					(mid 406.26433 -438.814498)
					(end 406.318212 -438.836816)
				)
				(arc
					(start 407.258012 -438.836816)
					(mid 407.311894 -438.814498)
					(end 407.334212 -438.760616)
				)
				(arc
					(start 407.334212 -436.219092)
					(mid 407.311894 -436.16521)
					(end 407.258012 -436.142892)
				)
				(arc
					(start 406.318212 -436.142892)
					(mid 406.26433 -436.16521)
					(end 406.242012 -436.219092)
				)
				(arc
					(start 406.242012 -436.946548)
					(mid 406.244011 -436.963889)
					(end 406.249886 -436.98033)
				)
				(arc
					(start 406.483312 -437.45658)
					(mid 406.491095 -437.490108)
					(end 406.483312 -437.523636)
				)
				(arc
					(start 406.249886 -437.999886)
					(mid 406.243991 -438.016322)
					(end 406.242012 -438.033668)
				)
			)
		)
	)
	(zone
		(layers "In14.Cu" "In16.Cu")
		(hatch none 0.5)
		(connect_pads
			(clearance 0)
		)
		(min_thickness 0.25)
		(keepout
			(tracks not_allowed)
			(vias allowed)
			(pads allowed)
			(copperpour not_allowed)
			(footprints allowed)
		)
		(placement
			(enabled no)
			(sheetname "")
		)
		(fill yes
			(thermal_gap 0.5)
			(thermal_bridge_width 0.5)
			(island_removal_mode 0)
		)
		(polygon
			(pts
				(arc
					(start 127.241808 -439.760614)
					(mid 127.264126 -439.814496)
					(end 127.318008 -439.836814)
				)
				(arc
					(start 128.257808 -439.836814)
					(mid 128.31169 -439.814496)
					(end 128.334008 -439.760614)
				)
				(arc
					(start 128.334008 -437.21909)
					(mid 128.31169 -437.165208)
					(end 128.257808 -437.14289)
				)
				(arc
					(start 127.318008 -437.14289)
					(mid 127.264126 -437.165208)
					(end 127.241808 -437.21909)
				)
				(arc
					(start 127.241808 -437.946546)
					(mid 127.243807 -437.963887)
					(end 127.249682 -437.980328)
				)
				(arc
					(start 127.483108 -438.456578)
					(mid 127.490891 -438.490106)
					(end 127.483108 -438.523634)
				)
				(arc
					(start 127.249682 -438.999884)
					(mid 127.243787 -439.01632)
					(end 127.241808 -439.033666)
				)
			)
		)
	)
	(zone
		(layers "In14.Cu" "In16.Cu")
		(hatch none 0.5)
		(connect_pads
			(clearance 0)
		)
		(min_thickness 0.25)
		(keepout
			(tracks not_allowed)
			(vias allowed)
			(pads allowed)
			(copperpour not_allowed)
			(footprints allowed)
		)
		(placement
			(enabled no)
			(sheetname "")
		)
		(fill yes
			(thermal_gap 0.5)
			(thermal_bridge_width 0.5)
			(island_removal_mode 0)
		)
		(polygon
			(pts
				(arc
					(start 345.141804 -439.760614)
					(mid 345.164122 -439.814496)
					(end 345.218004 -439.836814)
				)
				(arc
					(start 346.157804 -439.836814)
					(mid 346.211686 -439.814496)
					(end 346.234004 -439.760614)
				)
				(arc
					(start 346.234004 -437.21909)
					(mid 346.211686 -437.165208)
					(end 346.157804 -437.14289)
				)
				(arc
					(start 345.218004 -437.14289)
					(mid 345.164122 -437.165208)
					(end 345.141804 -437.21909)
				)
				(arc
					(start 345.141804 -437.946546)
					(mid 345.143803 -437.963887)
					(end 345.149678 -437.980328)
				)
				(arc
					(start 345.383104 -438.456578)
					(mid 345.390887 -438.490106)
					(end 345.383104 -438.523634)
				)
				(arc
					(start 345.149678 -438.999884)
					(mid 345.143783 -439.01632)
					(end 345.141804 -439.033666)
				)
			)
		)
	)
	(zone
		(layers "In14.Cu" "In16.Cu")
		(hatch none 0.5)
		(connect_pads
			(clearance 0)
		)
		(min_thickness 0.25)
		(keepout
			(tracks not_allowed)
			(vias allowed)
			(pads allowed)
			(copperpour not_allowed)
			(footprints allowed)
		)
		(placement
			(enabled no)
			(sheetname "")
		)
		(fill yes
			(thermal_gap 0.5)
			(thermal_bridge_width 0.5)
			(island_removal_mode 0)
		)
		(polygon
			(pts
				(arc
					(start 408.242008 -439.760614)
					(mid 408.264326 -439.814496)
					(end 408.318208 -439.836814)
				)
				(arc
					(start 409.258008 -439.836814)
					(mid 409.31189 -439.814496)
					(end 409.334208 -439.760614)
				)
				(arc
					(start 409.334208 -437.21909)
					(mid 409.31189 -437.165208)
					(end 409.258008 -437.14289)
				)
				(arc
					(start 408.318208 -437.14289)
					(mid 408.264326 -437.165208)
					(end 408.242008 -437.21909)
				)
				(arc
					(start 408.242008 -437.946546)
					(mid 408.244007 -437.963887)
					(end 408.249882 -437.980328)
				)
				(arc
					(start 408.483308 -438.456578)
					(mid 408.491091 -438.490106)
					(end 408.483308 -438.523634)
				)
				(arc
					(start 408.249882 -438.999884)
					(mid 408.243987 -439.01632)
					(end 408.242008 -439.033666)
				)
			)
		)
	)
	(zone
		(layers "In14.Cu" "In16.Cu")
		(hatch none 0.5)
		(connect_pads
			(clearance 0)
		)
		(min_thickness 0.25)
		(keepout
			(tracks not_allowed)
			(vias allowed)
			(pads allowed)
			(copperpour not_allowed)
			(footprints allowed)
		)
		(placement
			(enabled no)
			(sheetname "")
		)
		(fill yes
			(thermal_gap 0.5)
			(thermal_bridge_width 0.5)
			(island_removal_mode 0)
		)
		(polygon
			(pts
				(arc
					(start 133.241796 -438.760616)
					(mid 133.264114 -438.814498)
					(end 133.317996 -438.836816)
				)
				(arc
					(start 134.257796 -438.836816)
					(mid 134.311678 -438.814498)
					(end 134.333996 -438.760616)
				)
				(arc
					(start 134.333996 -436.219092)
					(mid 134.311678 -436.16521)
					(end 134.257796 -436.142892)
				)
				(arc
					(start 133.317996 -436.142892)
					(mid 133.264114 -436.16521)
					(end 133.241796 -436.219092)
				)
				(arc
					(start 133.241796 -436.946548)
					(mid 133.243795 -436.963889)
					(end 133.24967 -436.98033)
				)
				(arc
					(start 133.483096 -437.45658)
					(mid 133.490879 -437.490108)
					(end 133.483096 -437.523636)
				)
				(arc
					(start 133.24967 -437.999886)
					(mid 133.243775 -438.016322)
					(end 133.241796 -438.033668)
				)
			)
		)
	)
	(zone
		(layers "In14.Cu" "In16.Cu")
		(hatch none 0.5)
		(connect_pads
			(clearance 0)
		)
		(min_thickness 0.25)
		(keepout
			(tracks not_allowed)
			(vias allowed)
			(pads allowed)
			(copperpour not_allowed)
			(footprints allowed)
		)
		(placement
			(enabled no)
			(sheetname "")
		)
		(fill yes
			(thermal_gap 0.5)
			(thermal_bridge_width 0.5)
			(island_removal_mode 0)
		)
		(polygon
			(pts
				(arc
					(start 410.242004 -438.760616)
					(mid 410.264322 -438.814498)
					(end 410.318204 -438.836816)
				)
				(arc
					(start 411.258004 -438.836816)
					(mid 411.311886 -438.814498)
					(end 411.334204 -438.760616)
				)
				(arc
					(start 411.334204 -436.219092)
					(mid 411.311886 -436.16521)
					(end 411.258004 -436.142892)
				)
				(arc
					(start 410.318204 -436.142892)
					(mid 410.264322 -436.16521)
					(end 410.242004 -436.219092)
				)
				(arc
					(start 410.242004 -436.946548)
					(mid 410.244003 -436.963889)
					(end 410.249878 -436.98033)
				)
				(arc
					(start 410.483304 -437.45658)
					(mid 410.491087 -437.490108)
					(end 410.483304 -437.523636)
				)
				(arc
					(start 410.249878 -437.999886)
					(mid 410.243983 -438.016322)
					(end 410.242004 -438.033668)
				)
			)
		)
	)
	(zone
		(layers "In14.Cu" "In16.Cu")
		(hatch none 0.5)
		(connect_pads
			(clearance 0)
		)
		(min_thickness 0.25)
		(keepout
			(tracks not_allowed)
			(vias allowed)
			(pads allowed)
			(copperpour not_allowed)
			(footprints allowed)
		)
		(placement
			(enabled no)
			(sheetname "")
		)
		(fill yes
			(thermal_gap 0.5)
			(thermal_bridge_width 0.5)
			(island_removal_mode 0)
		)
		(polygon
			(pts
				(arc
					(start 333.141828 -439.760614)
					(mid 333.164146 -439.814496)
					(end 333.218028 -439.836814)
				)
				(arc
					(start 334.157828 -439.836814)
					(mid 334.21171 -439.814496)
					(end 334.234028 -439.760614)
				)
				(arc
					(start 334.234028 -437.21909)
					(mid 334.21171 -437.165208)
					(end 334.157828 -437.14289)
				)
				(arc
					(start 333.218028 -437.14289)
					(mid 333.164146 -437.165208)
					(end 333.141828 -437.21909)
				)
				(arc
					(start 333.141828 -437.946546)
					(mid 333.143827 -437.963887)
					(end 333.149702 -437.980328)
				)
				(arc
					(start 333.383128 -438.456578)
					(mid 333.390911 -438.490106)
					(end 333.383128 -438.523634)
				)
				(arc
					(start 333.149702 -438.999884)
					(mid 333.143807 -439.01632)
					(end 333.141828 -439.033666)
				)
			)
		)
	)
	(zone
		(layers "In14.Cu" "In16.Cu")
		(hatch none 0.5)
		(connect_pads
			(clearance 0)
		)
		(min_thickness 0.25)
		(keepout
			(tracks not_allowed)
			(vias allowed)
			(pads allowed)
			(copperpour not_allowed)
			(footprints allowed)
		)
		(placement
			(enabled no)
			(sheetname "")
		)
		(fill yes
			(thermal_gap 0.5)
			(thermal_bridge_width 0.5)
			(island_removal_mode 0)
		)
		(polygon
			(pts
				(arc
					(start 139.241784 -439.760614)
					(mid 139.264102 -439.814496)
					(end 139.317984 -439.836814)
				)
				(arc
					(start 140.257784 -439.836814)
					(mid 140.311666 -439.814496)
					(end 140.333984 -439.760614)
				)
				(arc
					(start 140.333984 -437.21909)
					(mid 140.311666 -437.165208)
					(end 140.257784 -437.14289)
				)
				(arc
					(start 139.317984 -437.14289)
					(mid 139.264102 -437.165208)
					(end 139.241784 -437.21909)
				)
				(arc
					(start 139.241784 -437.946546)
					(mid 139.243783 -437.963887)
					(end 139.249658 -437.980328)
				)
				(arc
					(start 139.483084 -438.456578)
					(mid 139.490867 -438.490106)
					(end 139.483084 -438.523634)
				)
				(arc
					(start 139.249658 -438.999884)
					(mid 139.243763 -439.01632)
					(end 139.241784 -439.033666)
				)
			)
		)
	)
	(zone
		(layers "In14.Cu" "In16.Cu")
		(hatch none 0.5)
		(connect_pads
			(clearance 0)
		)
		(min_thickness 0.25)
		(keepout
			(tracks not_allowed)
			(vias allowed)
			(pads allowed)
			(copperpour not_allowed)
			(footprints allowed)
		)
		(placement
			(enabled no)
			(sheetname "")
		)
		(fill yes
			(thermal_gap 0.5)
			(thermal_bridge_width 0.5)
			(island_removal_mode 0)
		)
		(polygon
			(pts
				(arc
					(start 335.141824 -438.760616)
					(mid 335.164142 -438.814498)
					(end 335.218024 -438.836816)
				)
				(arc
					(start 336.157824 -438.836816)
					(mid 336.211706 -438.814498)
					(end 336.234024 -438.760616)
				)
				(arc
					(start 336.234024 -436.219092)
					(mid 336.211706 -436.16521)
					(end 336.157824 -436.142892)
				)
				(arc
					(start 335.218024 -436.142892)
					(mid 335.164142 -436.16521)
					(end 335.141824 -436.219092)
				)
				(arc
					(start 335.141824 -436.946548)
					(mid 335.143823 -436.963889)
					(end 335.149698 -436.98033)
				)
				(arc
					(start 335.383124 -437.45658)
					(mid 335.390907 -437.490108)
					(end 335.383124 -437.523636)
				)
				(arc
					(start 335.149698 -437.999886)
					(mid 335.143803 -438.016322)
					(end 335.141824 -438.033668)
				)
			)
		)
	)
	(zone
		(layers "In14.Cu" "In16.Cu")
		(hatch none 0.5)
		(connect_pads
			(clearance 0)
		)
		(min_thickness 0.25)
		(keepout
			(tracks not_allowed)
			(vias allowed)
			(pads allowed)
			(copperpour not_allowed)
			(footprints allowed)
		)
		(placement
			(enabled no)
			(sheetname "")
		)
		(fill yes
			(thermal_gap 0.5)
			(thermal_bridge_width 0.5)
			(island_removal_mode 0)
		)
		(polygon
			(pts
				(arc
					(start 66.141854 -438.760616)
					(mid 66.164172 -438.814498)
					(end 66.218054 -438.836816)
				)
				(arc
					(start 67.157854 -438.836816)
					(mid 67.211736 -438.814498)
					(end 67.234054 -438.760616)
				)
				(arc
					(start 67.234054 -436.219092)
					(mid 67.211736 -436.16521)
					(end 67.157854 -436.142892)
				)
				(arc
					(start 66.218054 -436.142892)
					(mid 66.164172 -436.16521)
					(end 66.141854 -436.219092)
				)
				(arc
					(start 66.141854 -436.946548)
					(mid 66.143853 -436.963889)
					(end 66.149728 -436.98033)
				)
				(arc
					(start 66.383154 -437.45658)
					(mid 66.390937 -437.490108)
					(end 66.383154 -437.523636)
				)
				(arc
					(start 66.149728 -437.999886)
					(mid 66.143833 -438.016322)
					(end 66.141854 -438.033668)
				)
			)
		)
	)
	(zone
		(layers "In14.Cu" "In16.Cu")
		(hatch none 0.5)
		(connect_pads
			(clearance 0)
		)
		(min_thickness 0.25)
		(keepout
			(tracks not_allowed)
			(vias allowed)
			(pads allowed)
			(copperpour not_allowed)
			(footprints allowed)
		)
		(placement
			(enabled no)
			(sheetname "")
		)
		(fill yes
			(thermal_gap 0.5)
			(thermal_bridge_width 0.5)
			(island_removal_mode 0)
		)
		(polygon
			(pts
				(arc
					(start 68.14185 -439.760614)
					(mid 68.164168 -439.814496)
					(end 68.21805 -439.836814)
				)
				(arc
					(start 69.15785 -439.836814)
					(mid 69.211732 -439.814496)
					(end 69.23405 -439.760614)
				)
				(arc
					(start 69.23405 -437.21909)
					(mid 69.211732 -437.165208)
					(end 69.15785 -437.14289)
				)
				(arc
					(start 68.21805 -437.14289)
					(mid 68.164168 -437.165208)
					(end 68.14185 -437.21909)
				)
				(arc
					(start 68.14185 -437.946546)
					(mid 68.143849 -437.963887)
					(end 68.149724 -437.980328)
				)
				(arc
					(start 68.38315 -438.456578)
					(mid 68.390933 -438.490106)
					(end 68.38315 -438.523634)
				)
				(arc
					(start 68.149724 -438.999884)
					(mid 68.143829 -439.01632)
					(end 68.14185 -439.033666)
				)
			)
		)
	)
	(zone
		(layers "In14.Cu" "In16.Cu")
		(hatch none 0.5)
		(connect_pads
			(clearance 0)
		)
		(min_thickness 0.25)
		(keepout
			(tracks not_allowed)
			(vias allowed)
			(pads allowed)
			(copperpour not_allowed)
			(footprints allowed)
		)
		(placement
			(enabled no)
			(sheetname "")
		)
		(fill yes
			(thermal_gap 0.5)
			(thermal_bridge_width 0.5)
			(island_removal_mode 0)
		)
		(polygon
			(pts
				(arc
					(start 412.242 -439.760614)
					(mid 412.264318 -439.814496)
					(end 412.3182 -439.836814)
				)
				(arc
					(start 413.258 -439.836814)
					(mid 413.311882 -439.814496)
					(end 413.3342 -439.760614)
				)
				(arc
					(start 413.3342 -437.21909)
					(mid 413.311882 -437.165208)
					(end 413.258 -437.14289)
				)
				(arc
					(start 412.3182 -437.14289)
					(mid 412.264318 -437.165208)
					(end 412.242 -437.21909)
				)
				(arc
					(start 412.242 -437.946546)
					(mid 412.243999 -437.963887)
					(end 412.249874 -437.980328)
				)
				(arc
					(start 412.4833 -438.456578)
					(mid 412.491083 -438.490106)
					(end 412.4833 -438.523634)
				)
				(arc
					(start 412.249874 -438.999884)
					(mid 412.243979 -439.01632)
					(end 412.242 -439.033666)
				)
			)
		)
	)
	(zone
		(layers "In14.Cu" "In16.Cu")
		(hatch none 0.5)
		(connect_pads
			(clearance 0)
		)
		(min_thickness 0.25)
		(keepout
			(tracks not_allowed)
			(vias allowed)
			(pads allowed)
			(copperpour not_allowed)
			(footprints allowed)
		)
		(placement
			(enabled no)
			(sheetname "")
		)
		(fill yes
			(thermal_gap 0.5)
			(thermal_bridge_width 0.5)
			(island_removal_mode 0)
		)
		(polygon
			(pts
				(arc
					(start 343.141808 -438.760616)
					(mid 343.164126 -438.814498)
					(end 343.218008 -438.836816)
				)
				(arc
					(start 344.157808 -438.836816)
					(mid 344.21169 -438.814498)
					(end 344.234008 -438.760616)
				)
				(arc
					(start 344.234008 -436.219092)
					(mid 344.21169 -436.16521)
					(end 344.157808 -436.142892)
				)
				(arc
					(start 343.218008 -436.142892)
					(mid 343.164126 -436.16521)
					(end 343.141808 -436.219092)
				)
				(arc
					(start 343.141808 -436.946548)
					(mid 343.143807 -436.963889)
					(end 343.149682 -436.98033)
				)
				(arc
					(start 343.383108 -437.45658)
					(mid 343.390891 -437.490108)
					(end 343.383108 -437.523636)
				)
				(arc
					(start 343.149682 -437.999886)
					(mid 343.143787 -438.016322)
					(end 343.141808 -438.033668)
				)
			)
		)
	)
	(zone
		(layers "In14.Cu" "In16.Cu")
		(hatch none 0.5)
		(connect_pads
			(clearance 0)
		)
		(min_thickness 0.25)
		(keepout
			(tracks not_allowed)
			(vias allowed)
			(pads allowed)
			(copperpour not_allowed)
			(footprints allowed)
		)
		(placement
			(enabled no)
			(sheetname "")
		)
		(fill yes
			(thermal_gap 0.5)
			(thermal_bridge_width 0.5)
			(island_removal_mode 0)
		)
		(polygon
			(pts
				(arc
					(start 404.242016 -439.760614)
					(mid 404.264334 -439.814496)
					(end 404.318216 -439.836814)
				)
				(arc
					(start 405.258016 -439.836814)
					(mid 405.311898 -439.814496)
					(end 405.334216 -439.760614)
				)
				(arc
					(start 405.334216 -437.21909)
					(mid 405.311898 -437.165208)
					(end 405.258016 -437.14289)
				)
				(arc
					(start 404.318216 -437.14289)
					(mid 404.264334 -437.165208)
					(end 404.242016 -437.21909)
				)
				(arc
					(start 404.242016 -437.946546)
					(mid 404.244015 -437.963887)
					(end 404.24989 -437.980328)
				)
				(arc
					(start 404.483316 -438.456578)
					(mid 404.491099 -438.490106)
					(end 404.483316 -438.523634)
				)
				(arc
					(start 404.24989 -438.999884)
					(mid 404.243995 -439.01632)
					(end 404.242016 -439.033666)
				)
			)
		)
	)
	(zone
		(layers "In14.Cu" "In16.Cu")
		(hatch none 0.5)
		(connect_pads
			(clearance 0)
		)
		(min_thickness 0.25)
		(keepout
			(tracks not_allowed)
			(vias allowed)
			(pads allowed)
			(copperpour not_allowed)
			(footprints allowed)
		)
		(placement
			(enabled no)
			(sheetname "")
		)
		(fill yes
			(thermal_gap 0.5)
			(thermal_bridge_width 0.5)
			(island_removal_mode 0)
		)
		(polygon
			(pts
				(arc
					(start 402.24202 -438.760616)
					(mid 402.264338 -438.814498)
					(end 402.31822 -438.836816)
				)
				(arc
					(start 403.25802 -438.836816)
					(mid 403.311902 -438.814498)
					(end 403.33422 -438.760616)
				)
				(arc
					(start 403.33422 -436.219092)
					(mid 403.311902 -436.16521)
					(end 403.25802 -436.142892)
				)
				(arc
					(start 402.31822 -436.142892)
					(mid 402.264338 -436.16521)
					(end 402.24202 -436.219092)
				)
				(arc
					(start 402.24202 -436.946548)
					(mid 402.244019 -436.963889)
					(end 402.249894 -436.98033)
				)
				(arc
					(start 402.48332 -437.45658)
					(mid 402.491103 -437.490108)
					(end 402.48332 -437.523636)
				)
				(arc
					(start 402.249894 -437.999886)
					(mid 402.243999 -438.016322)
					(end 402.24202 -438.033668)
				)
			)
		)
	)
	(zone
		(layers "In14.Cu" "In16.Cu")
		(hatch none 0.5)
		(connect_pads
			(clearance 0)
		)
		(min_thickness 0.25)
		(keepout
			(tracks not_allowed)
			(vias allowed)
			(pads allowed)
			(copperpour not_allowed)
			(footprints allowed)
		)
		(placement
			(enabled no)
			(sheetname "")
		)
		(fill yes
			(thermal_gap 0.5)
			(thermal_bridge_width 0.5)
			(island_removal_mode 0)
		)
		(polygon
			(pts
				(arc
					(start 339.141816 -438.760616)
					(mid 339.164134 -438.814498)
					(end 339.218016 -438.836816)
				)
				(arc
					(start 340.157816 -438.836816)
					(mid 340.211698 -438.814498)
					(end 340.234016 -438.760616)
				)
				(arc
					(start 340.234016 -436.219092)
					(mid 340.211698 -436.16521)
					(end 340.157816 -436.142892)
				)
				(arc
					(start 339.218016 -436.142892)
					(mid 339.164134 -436.16521)
					(end 339.141816 -436.219092)
				)
				(arc
					(start 339.141816 -436.946548)
					(mid 339.143815 -436.963889)
					(end 339.14969 -436.98033)
				)
				(arc
					(start 339.383116 -437.45658)
					(mid 339.390899 -437.490108)
					(end 339.383116 -437.523636)
				)
				(arc
					(start 339.14969 -437.999886)
					(mid 339.143795 -438.016322)
					(end 339.141816 -438.033668)
				)
			)
		)
	)
	(zone
		(layers "In14.Cu" "In16.Cu")
		(hatch none 0.5)
		(connect_pads
			(clearance 0)
		)
		(min_thickness 0.25)
		(keepout
			(tracks not_allowed)
			(vias allowed)
			(pads allowed)
			(copperpour not_allowed)
			(footprints allowed)
		)
		(placement
			(enabled no)
			(sheetname "")
		)
		(fill yes
			(thermal_gap 0.5)
			(thermal_bridge_width 0.5)
			(island_removal_mode 0)
		)
		(polygon
			(pts
				(arc
					(start 62.141862 -438.760616)
					(mid 62.16418 -438.814498)
					(end 62.218062 -438.836816)
				)
				(arc
					(start 63.157862 -438.836816)
					(mid 63.211744 -438.814498)
					(end 63.234062 -438.760616)
				)
				(arc
					(start 63.234062 -436.219092)
					(mid 63.211744 -436.16521)
					(end 63.157862 -436.142892)
				)
				(arc
					(start 62.218062 -436.142892)
					(mid 62.16418 -436.16521)
					(end 62.141862 -436.219092)
				)
				(arc
					(start 62.141862 -436.946548)
					(mid 62.143861 -436.963889)
					(end 62.149736 -436.98033)
				)
				(arc
					(start 62.383162 -437.45658)
					(mid 62.390945 -437.490108)
					(end 62.383162 -437.523636)
				)
				(arc
					(start 62.149736 -437.999886)
					(mid 62.143841 -438.016322)
					(end 62.141862 -438.033668)
				)
			)
		)
	)
	(zone
		(layers "In14.Cu" "In16.Cu")
		(hatch none 0.5)
		(connect_pads
			(clearance 0)
		)
		(min_thickness 0.25)
		(keepout
			(tracks not_allowed)
			(vias allowed)
			(pads allowed)
			(copperpour not_allowed)
			(footprints allowed)
		)
		(placement
			(enabled no)
			(sheetname "")
		)
		(fill yes
			(thermal_gap 0.5)
			(thermal_bridge_width 0.5)
			(island_removal_mode 0)
		)
		(polygon
			(pts
				(arc
					(start 398.242028 -438.760616)
					(mid 398.264346 -438.814498)
					(end 398.318228 -438.836816)
				)
				(arc
					(start 399.258028 -438.836816)
					(mid 399.31191 -438.814498)
					(end 399.334228 -438.760616)
				)
				(arc
					(start 399.334228 -436.219092)
					(mid 399.31191 -436.16521)
					(end 399.258028 -436.142892)
				)
				(arc
					(start 398.318228 -436.142892)
					(mid 398.264346 -436.16521)
					(end 398.242028 -436.219092)
				)
				(arc
					(start 398.242028 -436.946548)
					(mid 398.244027 -436.963889)
					(end 398.249902 -436.98033)
				)
				(arc
					(start 398.483328 -437.45658)
					(mid 398.491111 -437.490108)
					(end 398.483328 -437.523636)
				)
				(arc
					(start 398.249902 -437.999886)
					(mid 398.244007 -438.016322)
					(end 398.242028 -438.033668)
				)
			)
		)
	)
	(zone
		(layers "In14.Cu" "In16.Cu")
		(hatch none 0.5)
		(connect_pads
			(clearance 0)
		)
		(min_thickness 0.25)
		(keepout
			(tracks not_allowed)
			(vias allowed)
			(pads allowed)
			(copperpour not_allowed)
			(footprints allowed)
		)
		(placement
			(enabled no)
			(sheetname "")
		)
		(fill yes
			(thermal_gap 0.5)
			(thermal_bridge_width 0.5)
			(island_removal_mode 0)
		)
		(polygon
			(pts
				(arc
					(start 321.936618 -394.552424)
					(mid 322.046589 -394.653478)
					(end 322.19138 -394.690092)
				)
				(arc
					(start 322.19138 -394.690092)
					(mid 322.406906 -394.600818)
					(end 322.49618 -394.385292)
				)
				(arc
					(start 322.49618 -394.385292)
					(mid 322.485843 -394.306553)
					(end 322.45554 -394.233146)
				)
				(arc
					(start 322.06311 -393.554204)
					(mid 321.950713 -393.432587)
					(end 321.79133 -393.38758)
				)
				(arc
					(start 321.79133 -393.38758)
					(mid 321.575804 -393.476854)
					(end 321.48653 -393.69238)
				)
				(arc
					(start 321.48653 -393.69238)
					(mid 321.496108 -393.768442)
					(end 321.524376 -393.8397)
				)
				(xy 321.921632 -394.527024) (xy 321.933824 -394.54836) (xy 321.936364 -394.552678)
			)
		)
	)
	(zone
		(layers "In14.Cu" "In16.Cu")
		(hatch none 0.5)
		(connect_pads
			(clearance 0)
		)
		(min_thickness 0.25)
		(keepout
			(tracks not_allowed)
			(vias allowed)
			(pads allowed)
			(copperpour not_allowed)
			(footprints allowed)
		)
		(placement
			(enabled no)
			(sheetname "")
		)
		(fill yes
			(thermal_gap 0.5)
			(thermal_bridge_width 0.5)
			(island_removal_mode 0)
		)
		(polygon
			(pts
				(arc
					(start 337.14182 -439.760614)
					(mid 337.164138 -439.814496)
					(end 337.21802 -439.836814)
				)
				(arc
					(start 338.15782 -439.836814)
					(mid 338.211702 -439.814496)
					(end 338.23402 -439.760614)
				)
				(arc
					(start 338.23402 -437.21909)
					(mid 338.211702 -437.165208)
					(end 338.15782 -437.14289)
				)
				(arc
					(start 337.21802 -437.14289)
					(mid 337.164138 -437.165208)
					(end 337.14182 -437.21909)
				)
				(arc
					(start 337.14182 -437.946546)
					(mid 337.143819 -437.963887)
					(end 337.149694 -437.980328)
				)
				(arc
					(start 337.38312 -438.456578)
					(mid 337.390903 -438.490106)
					(end 337.38312 -438.523634)
				)
				(arc
					(start 337.149694 -438.999884)
					(mid 337.143799 -439.01632)
					(end 337.14182 -439.033666)
				)
			)
		)
	)
	(zone
		(layers "In14.Cu" "In16.Cu")
		(hatch none 0.5)
		(connect_pads
			(clearance 0)
		)
		(min_thickness 0.25)
		(keepout
			(tracks not_allowed)
			(vias allowed)
			(pads allowed)
			(copperpour not_allowed)
			(footprints allowed)
		)
		(placement
			(enabled no)
			(sheetname "")
		)
		(fill yes
			(thermal_gap 0.5)
			(thermal_bridge_width 0.5)
			(island_removal_mode 0)
		)
		(polygon
			(pts
				(arc
					(start 135.241792 -439.760614)
					(mid 135.26411 -439.814496)
					(end 135.317992 -439.836814)
				)
				(arc
					(start 136.257792 -439.836814)
					(mid 136.311674 -439.814496)
					(end 136.333992 -439.760614)
				)
				(arc
					(start 136.333992 -437.21909)
					(mid 136.311674 -437.165208)
					(end 136.257792 -437.14289)
				)
				(arc
					(start 135.317992 -437.14289)
					(mid 135.26411 -437.165208)
					(end 135.241792 -437.21909)
				)
				(arc
					(start 135.241792 -437.946546)
					(mid 135.243791 -437.963887)
					(end 135.249666 -437.980328)
				)
				(arc
					(start 135.483092 -438.456578)
					(mid 135.490875 -438.490106)
					(end 135.483092 -438.523634)
				)
				(arc
					(start 135.249666 -438.999884)
					(mid 135.243771 -439.01632)
					(end 135.241792 -439.033666)
				)
			)
		)
	)
	(zone
		(layers "In14.Cu" "In16.Cu")
		(hatch none 0.5)
		(connect_pads
			(clearance 0)
		)
		(min_thickness 0.25)
		(keepout
			(tracks not_allowed)
			(vias allowed)
			(pads allowed)
			(copperpour not_allowed)
			(footprints allowed)
		)
		(placement
			(enabled no)
			(sheetname "")
		)
		(fill yes
			(thermal_gap 0.5)
			(thermal_bridge_width 0.5)
			(island_removal_mode 0)
		)
		(polygon
			(pts
				(arc
					(start 400.242024 -439.760614)
					(mid 400.264342 -439.814496)
					(end 400.318224 -439.836814)
				)
				(arc
					(start 401.258024 -439.836814)
					(mid 401.311906 -439.814496)
					(end 401.334224 -439.760614)
				)
				(arc
					(start 401.334224 -437.21909)
					(mid 401.311906 -437.165208)
					(end 401.258024 -437.14289)
				)
				(arc
					(start 400.318224 -437.14289)
					(mid 400.264342 -437.165208)
					(end 400.242024 -437.21909)
				)
				(arc
					(start 400.242024 -437.946546)
					(mid 400.244023 -437.963887)
					(end 400.249898 -437.980328)
				)
				(arc
					(start 400.483324 -438.456578)
					(mid 400.491107 -438.490106)
					(end 400.483324 -438.523634)
				)
				(arc
					(start 400.249898 -438.999884)
					(mid 400.244003 -439.01632)
					(end 400.242024 -439.033666)
				)
			)
		)
	)
	(zone
		(layers "In14.Cu" "In16.Cu")
		(hatch none 0.5)
		(connect_pads
			(clearance 0)
		)
		(min_thickness 0.25)
		(keepout
			(tracks not_allowed)
			(vias allowed)
			(pads allowed)
			(copperpour not_allowed)
			(footprints allowed)
		)
		(placement
			(enabled no)
			(sheetname "")
		)
		(fill yes
			(thermal_gap 0.5)
			(thermal_bridge_width 0.5)
			(island_removal_mode 0)
		)
		(polygon
			(pts
				(arc
					(start 72.141842 -439.760614)
					(mid 72.16416 -439.814496)
					(end 72.218042 -439.836814)
				)
				(arc
					(start 73.157842 -439.836814)
					(mid 73.211724 -439.814496)
					(end 73.234042 -439.760614)
				)
				(arc
					(start 73.234042 -437.21909)
					(mid 73.211724 -437.165208)
					(end 73.157842 -437.14289)
				)
				(arc
					(start 72.218042 -437.14289)
					(mid 72.16416 -437.165208)
					(end 72.141842 -437.21909)
				)
				(arc
					(start 72.141842 -437.946546)
					(mid 72.143841 -437.963887)
					(end 72.149716 -437.980328)
				)
				(arc
					(start 72.383142 -438.456578)
					(mid 72.390925 -438.490106)
					(end 72.383142 -438.523634)
				)
				(arc
					(start 72.149716 -438.999884)
					(mid 72.143821 -439.01632)
					(end 72.141842 -439.033666)
				)
			)
		)
	)
	(zone
		(layers "In14.Cu" "In16.Cu")
		(hatch none 0.5)
		(connect_pads
			(clearance 0)
		)
		(min_thickness 0.25)
		(keepout
			(tracks not_allowed)
			(vias allowed)
			(pads allowed)
			(copperpour not_allowed)
			(footprints allowed)
		)
		(placement
			(enabled no)
			(sheetname "")
		)
		(fill yes
			(thermal_gap 0.5)
			(thermal_bridge_width 0.5)
			(island_removal_mode 0)
		)
		(polygon
			(pts
				(arc
					(start 137.241788 -438.760616)
					(mid 137.264106 -438.814498)
					(end 137.317988 -438.836816)
				)
				(arc
					(start 138.257788 -438.836816)
					(mid 138.31167 -438.814498)
					(end 138.333988 -438.760616)
				)
				(arc
					(start 138.333988 -436.219092)
					(mid 138.31167 -436.16521)
					(end 138.257788 -436.142892)
				)
				(arc
					(start 137.317988 -436.142892)
					(mid 137.264106 -436.16521)
					(end 137.241788 -436.219092)
				)
				(arc
					(start 137.241788 -436.946548)
					(mid 137.243787 -436.963889)
					(end 137.249662 -436.98033)
				)
				(arc
					(start 137.483088 -437.45658)
					(mid 137.490871 -437.490108)
					(end 137.483088 -437.523636)
				)
				(arc
					(start 137.249662 -437.999886)
					(mid 137.243767 -438.016322)
					(end 137.241788 -438.033668)
				)
			)
		)
	)
	(zone
		(layers "In14.Cu" "In16.Cu")
		(hatch none 0.5)
		(connect_pads
			(clearance 0)
		)
		(min_thickness 0.25)
		(keepout
			(tracks not_allowed)
			(vias allowed)
			(pads allowed)
			(copperpour not_allowed)
			(footprints allowed)
		)
		(placement
			(enabled no)
			(sheetname "")
		)
		(fill yes
			(thermal_gap 0.5)
			(thermal_bridge_width 0.5)
			(island_removal_mode 0)
		)
		(polygon
			(pts
				(arc
					(start 60.141866 -439.760614)
					(mid 60.164184 -439.814496)
					(end 60.218066 -439.836814)
				)
				(arc
					(start 61.157866 -439.836814)
					(mid 61.211748 -439.814496)
					(end 61.234066 -439.760614)
				)
				(arc
					(start 61.234066 -437.21909)
					(mid 61.211748 -437.165208)
					(end 61.157866 -437.14289)
				)
				(arc
					(start 60.218066 -437.14289)
					(mid 60.164184 -437.165208)
					(end 60.141866 -437.21909)
				)
				(arc
					(start 60.141866 -437.946546)
					(mid 60.143865 -437.963887)
					(end 60.14974 -437.980328)
				)
				(arc
					(start 60.383166 -438.456578)
					(mid 60.390949 -438.490106)
					(end 60.383166 -438.523634)
				)
				(arc
					(start 60.14974 -438.999884)
					(mid 60.143845 -439.01632)
					(end 60.141866 -439.033666)
				)
			)
		)
	)
	(zone
		(layers "In14.Cu" "In16.Cu")
		(hatch none 0.5)
		(connect_pads
			(clearance 0)
		)
		(min_thickness 0.25)
		(keepout
			(tracks not_allowed)
			(vias allowed)
			(pads allowed)
			(copperpour not_allowed)
			(footprints allowed)
		)
		(placement
			(enabled no)
			(sheetname "")
		)
		(fill yes
			(thermal_gap 0.5)
			(thermal_bridge_width 0.5)
			(island_removal_mode 0)
		)
		(polygon
			(pts
				(arc
					(start 125.241812 -438.760616)
					(mid 125.26413 -438.814498)
					(end 125.318012 -438.836816)
				)
				(arc
					(start 126.257812 -438.836816)
					(mid 126.311694 -438.814498)
					(end 126.334012 -438.760616)
				)
				(arc
					(start 126.334012 -436.219092)
					(mid 126.311694 -436.16521)
					(end 126.257812 -436.142892)
				)
				(arc
					(start 125.318012 -436.142892)
					(mid 125.26413 -436.16521)
					(end 125.241812 -436.219092)
				)
				(arc
					(start 125.241812 -436.946548)
					(mid 125.243811 -436.963889)
					(end 125.249686 -436.98033)
				)
				(arc
					(start 125.483112 -437.45658)
					(mid 125.490895 -437.490108)
					(end 125.483112 -437.523636)
				)
				(arc
					(start 125.249686 -437.999886)
					(mid 125.243791 -438.016322)
					(end 125.241812 -438.033668)
				)
			)
		)
	)
	(zone
		(layers "In14.Cu" "In16.Cu")
		(hatch none 0.5)
		(connect_pads
			(clearance 0)
		)
		(min_thickness 0.25)
		(keepout
			(tracks not_allowed)
			(vias allowed)
			(pads allowed)
			(copperpour not_allowed)
			(footprints allowed)
		)
		(placement
			(enabled no)
			(sheetname "")
		)
		(fill yes
			(thermal_gap 0.5)
			(thermal_bridge_width 0.5)
			(island_removal_mode 0)
		)
		(polygon
			(pts
				(arc
					(start 131.2418 -439.760614)
					(mid 131.264118 -439.814496)
					(end 131.318 -439.836814)
				)
				(arc
					(start 132.2578 -439.836814)
					(mid 132.311682 -439.814496)
					(end 132.334 -439.760614)
				)
				(arc
					(start 132.334 -437.21909)
					(mid 132.311682 -437.165208)
					(end 132.2578 -437.14289)
				)
				(arc
					(start 131.318 -437.14289)
					(mid 131.264118 -437.165208)
					(end 131.2418 -437.21909)
				)
				(arc
					(start 131.2418 -437.946546)
					(mid 131.243799 -437.963887)
					(end 131.249674 -437.980328)
				)
				(arc
					(start 131.4831 -438.456578)
					(mid 131.490883 -438.490106)
					(end 131.4831 -438.523634)
				)
				(arc
					(start 131.249674 -438.999884)
					(mid 131.243779 -439.01632)
					(end 131.2418 -439.033666)
				)
			)
		)
	)
	(zone
		(layers "In14.Cu" "In16.Cu")
		(hatch none 0.5)
		(connect_pads
			(clearance 0)
		)
		(min_thickness 0.25)
		(keepout
			(tracks not_allowed)
			(vias allowed)
			(pads allowed)
			(copperpour not_allowed)
			(footprints allowed)
		)
		(placement
			(enabled no)
			(sheetname "")
		)
		(fill yes
			(thermal_gap 0.5)
			(thermal_bridge_width 0.5)
			(island_removal_mode 0)
		)
		(polygon
			(pts
				(arc
					(start 341.141812 -439.760614)
					(mid 341.16413 -439.814496)
					(end 341.218012 -439.836814)
				)
				(arc
					(start 342.157812 -439.836814)
					(mid 342.211694 -439.814496)
					(end 342.234012 -439.760614)
				)
				(arc
					(start 342.234012 -437.21909)
					(mid 342.211694 -437.165208)
					(end 342.157812 -437.14289)
				)
				(arc
					(start 341.218012 -437.14289)
					(mid 341.16413 -437.165208)
					(end 341.141812 -437.21909)
				)
				(arc
					(start 341.141812 -437.946546)
					(mid 341.143811 -437.963887)
					(end 341.149686 -437.980328)
				)
				(arc
					(start 341.383112 -438.456578)
					(mid 341.390895 -438.490106)
					(end 341.383112 -438.523634)
				)
				(arc
					(start 341.149686 -438.999884)
					(mid 341.143791 -439.01632)
					(end 341.141812 -439.033666)
				)
			)
		)
	)
	(zone
		(layers "In14.Cu" "In16.Cu")
		(hatch none 0.5)
		(connect_pads
			(clearance 0)
		)
		(min_thickness 0.25)
		(keepout
			(tracks not_allowed)
			(vias allowed)
			(pads allowed)
			(copperpour not_allowed)
			(footprints allowed)
		)
		(placement
			(enabled no)
			(sheetname "")
		)
		(fill yes
			(thermal_gap 0.5)
			(thermal_bridge_width 0.5)
			(island_removal_mode 0)
		)
		(polygon
			(pts
				(arc
					(start 331.141832 -438.760616)
					(mid 331.16415 -438.814498)
					(end 331.218032 -438.836816)
				)
				(arc
					(start 332.157832 -438.836816)
					(mid 332.211714 -438.814498)
					(end 332.234032 -438.760616)
				)
				(arc
					(start 332.234032 -436.219092)
					(mid 332.211714 -436.16521)
					(end 332.157832 -436.142892)
				)
				(arc
					(start 331.218032 -436.142892)
					(mid 331.16415 -436.16521)
					(end 331.141832 -436.219092)
				)
				(arc
					(start 331.141832 -436.946548)
					(mid 331.143831 -436.963889)
					(end 331.149706 -436.98033)
				)
				(arc
					(start 331.383132 -437.45658)
					(mid 331.390915 -437.490108)
					(end 331.383132 -437.523636)
				)
				(arc
					(start 331.149706 -437.999886)
					(mid 331.143811 -438.016322)
					(end 331.141832 -438.033668)
				)
			)
		)
	)
	(zone
		(layers "In14.Cu" "In16.Cu")
		(hatch none 0.5)
		(connect_pads
			(clearance 0)
		)
		(min_thickness 0.25)
		(keepout
			(tracks not_allowed)
			(vias allowed)
			(pads allowed)
			(copperpour not_allowed)
			(footprints allowed)
		)
		(placement
			(enabled no)
			(sheetname "")
		)
		(fill yes
			(thermal_gap 0.5)
			(thermal_bridge_width 0.5)
			(island_removal_mode 0)
		)
		(polygon
			(pts
				(arc
					(start 70.141846 -438.760616)
					(mid 70.164164 -438.814498)
					(end 70.218046 -438.836816)
				)
				(arc
					(start 71.157846 -438.836816)
					(mid 71.211728 -438.814498)
					(end 71.234046 -438.760616)
				)
				(arc
					(start 71.234046 -436.219092)
					(mid 71.211728 -436.16521)
					(end 71.157846 -436.142892)
				)
				(arc
					(start 70.218046 -436.142892)
					(mid 70.164164 -436.16521)
					(end 70.141846 -436.219092)
				)
				(arc
					(start 70.141846 -436.946548)
					(mid 70.143845 -436.963889)
					(end 70.14972 -436.98033)
				)
				(arc
					(start 70.383146 -437.45658)
					(mid 70.390929 -437.490108)
					(end 70.383146 -437.523636)
				)
				(arc
					(start 70.14972 -437.999886)
					(mid 70.143825 -438.016322)
					(end 70.141846 -438.033668)
				)
			)
		)
	)
	(zone
		(layer "In15.Cu")
		(hatch none 0.5)
		(connect_pads
			(clearance 0)
		)
		(min_thickness 0.25)
		(keepout
			(tracks allowed)
			(vias allowed)
			(pads allowed)
			(copperpour allowed)
			(footprints allowed)
		)
		(placement
			(enabled no)
			(sheetname "")
		)
		(fill
			(thermal_gap 0.5)
			(thermal_bridge_width 0.5)
			(island_removal_mode 0)
		)
		(polygon
			(pts
				(xy 185.28157 -400.947636) (xy 185.28157 -398.66316) (xy 188.931804 -398.66316) (xy 188.931804 -400.947636)
			)
		)
	)
	(zone
		(layer "In15.Cu")
		(hatch none 0.5)
		(connect_pads
			(clearance 0)
		)
		(min_thickness 0.25)
		(keepout
			(tracks allowed)
			(vias allowed)
			(pads allowed)
			(copperpour allowed)
			(footprints allowed)
		)
		(placement
			(enabled no)
			(sheetname "")
		)
		(fill
			(thermal_gap 0.5)
			(thermal_bridge_width 0.5)
			(island_removal_mode 0)
		)
		(polygon
			(pts
				(xy 276.612604 -394.135864) (xy 276.612604 -393.658598) (xy 277.831042 -393.658598) (xy 277.831042 -394.135864)
			)
		)
	)
	(zone
		(layer "In15.Cu")
		(hatch none 0.5)
		(connect_pads
			(clearance 0)
		)
		(min_thickness 0.25)
		(keepout
			(tracks allowed)
			(vias allowed)
			(pads allowed)
			(copperpour allowed)
			(footprints allowed)
		)
		(placement
			(enabled no)
			(sheetname "")
		)
		(fill
			(thermal_gap 0.5)
			(thermal_bridge_width 0.5)
			(island_removal_mode 0)
		)
		(polygon
			(pts
				(xy 259.559552 -394.150088) (xy 259.559552 -393.672822) (xy 260.77799 -393.672822) (xy 260.77799 -394.150088)
			)
		)
	)
	(zone
		(layer "In15.Cu")
		(hatch none 0.5)
		(connect_pads
			(clearance 0)
		)
		(min_thickness 0.25)
		(keepout
			(tracks allowed)
			(vias allowed)
			(pads allowed)
			(copperpour allowed)
			(footprints allowed)
		)
		(placement
			(enabled no)
			(sheetname "")
		)
		(fill
			(thermal_gap 0.5)
			(thermal_bridge_width 0.5)
			(island_removal_mode 0)
		)
		(polygon
			(pts
				(xy 267.585952 -394.150088) (xy 267.585952 -393.672822) (xy 268.80439 -393.672822) (xy 268.80439 -394.150088)
			)
		)
	)
	(zone
		(layer "In15.Cu")
		(hatch none 0.5)
		(connect_pads
			(clearance 0)
		)
		(min_thickness 0.25)
		(keepout
			(tracks allowed)
			(vias allowed)
			(pads allowed)
			(copperpour allowed)
			(footprints allowed)
		)
		(placement
			(enabled no)
			(sheetname "")
		)
		(fill
			(thermal_gap 0.5)
			(thermal_bridge_width 0.5)
			(island_removal_mode 0)
		)
		(polygon
			(pts
				(xy 15.67561 -105.871772) (xy 15.67561 -104.586532) (xy 16.264128 -104.586532) (xy 16.264128 -105.871772)
			)
		)
	)
	(zone
		(layer "In15.Cu")
		(hatch none 0.5)
		(connect_pads
			(clearance 0)
		)
		(min_thickness 0.25)
		(keepout
			(tracks allowed)
			(vias allowed)
			(pads allowed)
			(copperpour allowed)
			(footprints allowed)
		)
		(placement
			(enabled no)
			(sheetname "")
		)
		(fill
			(thermal_gap 0.5)
			(thermal_bridge_width 0.5)
			(island_removal_mode 0)
		)
		(polygon
			(pts
				(xy 243.503704 -394.146024) (xy 243.503704 -393.668758) (xy 244.722142 -393.668758) (xy 244.722142 -394.146024)
			)
		)
	)
	(zone
		(layer "In15.Cu")
		(hatch none 0.5)
		(connect_pads
			(clearance 0)
		)
		(min_thickness 0.25)
		(keepout
			(tracks not_allowed)
			(vias allowed)
			(pads allowed)
			(copperpour not_allowed)
			(footprints allowed)
		)
		(placement
			(enabled no)
			(sheetname "")
		)
		(fill
			(thermal_gap 0.5)
			(thermal_bridge_width 0.5)
			(island_removal_mode 0)
		)
		(polygon
			(pts
				(arc
					(start 437.627014 -384.869944)
					(mid 429.37303 -384.869944)
					(end 437.627014 -384.869944)
				)
			)
		)
	)
	(zone
		(layer "In15.Cu")
		(hatch none 0.5)
		(connect_pads
			(clearance 0)
		)
		(min_thickness 0.25)
		(keepout
			(tracks allowed)
			(vias allowed)
			(pads allowed)
			(copperpour allowed)
			(footprints allowed)
		)
		(placement
			(enabled no)
			(sheetname "")
		)
		(fill
			(thermal_gap 0.5)
			(thermal_bridge_width 0.5)
			(island_removal_mode 0)
		)
		(polygon
			(pts
				(xy 251.533152 -394.150088) (xy 251.533152 -393.672822) (xy 252.75159 -393.672822) (xy 252.75159 -394.150088)
			)
		)
	)
	(zone
		(layer "In15.Cu")
		(hatch none 0.5)
		(connect_pads
			(clearance 0)
		)
		(min_thickness 0.25)
		(keepout
			(tracks allowed)
			(vias allowed)
			(pads allowed)
			(copperpour allowed)
			(footprints allowed)
		)
		(placement
			(enabled no)
			(sheetname "")
		)
		(fill
			(thermal_gap 0.5)
			(thermal_bridge_width 0.5)
			(island_removal_mode 0)
		)
		(polygon
			(pts
				(xy 190.42634 -131.73964) (xy 190.42634 -130.12674) (xy 192.07226 -130.12674) (xy 192.07226 -131.73964)
			)
		)
	)
	(zone
		(layers "In15.Cu" "In16.Cu")
		(hatch none 0.5)
		(connect_pads
			(clearance 0)
		)
		(min_thickness 0.25)
		(keepout
			(tracks not_allowed)
			(vias allowed)
			(pads allowed)
			(copperpour not_allowed)
			(footprints allowed)
		)
		(placement
			(enabled no)
			(sheetname "")
		)
		(fill yes
			(thermal_gap 0.5)
			(thermal_bridge_width 0.5)
			(island_removal_mode 0)
		)
		(polygon
			(pts
				(arc
					(start 402.840952 -417.242244)
					(mid 402.86327 -417.296126)
					(end 402.917152 -417.318444)
				)
				(arc
					(start 403.112732 -417.318444)
					(mid 403.134608 -417.315312)
					(end 403.154642 -417.305998)
				)
				(arc
					(start 403.448266 -417.113466)
					(mid 403.489922 -417.101064)
					(end 403.531578 -417.113466)
				)
				(arc
					(start 403.826472 -417.305998)
					(mid 403.846396 -417.315234)
					(end 403.868128 -417.318444)
				)
				(arc
					(start 404.062692 -417.318444)
					(mid 404.116574 -417.296126)
					(end 404.138892 -417.242244)
				)
				(arc
					(start 404.138892 -416.556444)
					(mid 404.116574 -416.502562)
					(end 404.062692 -416.480244)
				)
				(arc
					(start 403.868128 -416.480244)
					(mid 403.846384 -416.483412)
					(end 403.826472 -416.49269)
				)
				(arc
					(start 403.530308 -416.685476)
					(mid 403.488624 -416.697698)
					(end 403.446996 -416.685222)
				)
				(arc
					(start 403.153372 -416.49269)
					(mid 403.133448 -416.483454)
					(end 403.111716 -416.480244)
				)
				(arc
					(start 402.917152 -416.480244)
					(mid 402.86327 -416.502562)
					(end 402.840952 -416.556444)
				)
			)
		)
	)
	(zone
		(layers "In15.Cu" "In16.Cu")
		(hatch none 0.5)
		(connect_pads
			(clearance 0)
		)
		(min_thickness 0.25)
		(keepout
			(tracks not_allowed)
			(vias allowed)
			(pads allowed)
			(copperpour not_allowed)
			(footprints allowed)
		)
		(placement
			(enabled no)
			(sheetname "")
		)
		(fill yes
			(thermal_gap 0.5)
			(thermal_bridge_width 0.5)
			(island_removal_mode 0)
		)
		(polygon
			(pts
				(arc
					(start 341.867236 -417.242244)
					(mid 341.889554 -417.296126)
					(end 341.943436 -417.318444)
				)
				(arc
					(start 342.139016 -417.318444)
					(mid 342.160892 -417.315312)
					(end 342.180926 -417.305998)
				)
				(arc
					(start 342.47455 -417.113466)
					(mid 342.516206 -417.101064)
					(end 342.557862 -417.113466)
				)
				(arc
					(start 342.852756 -417.305998)
					(mid 342.87268 -417.315234)
					(end 342.894412 -417.318444)
				)
				(arc
					(start 343.088976 -417.318444)
					(mid 343.142858 -417.296126)
					(end 343.165176 -417.242244)
				)
				(arc
					(start 343.165176 -416.556444)
					(mid 343.142858 -416.502562)
					(end 343.088976 -416.480244)
				)
				(arc
					(start 342.894412 -416.480244)
					(mid 342.872668 -416.483412)
					(end 342.852756 -416.49269)
				)
				(arc
					(start 342.556592 -416.685476)
					(mid 342.514908 -416.697698)
					(end 342.47328 -416.685222)
				)
				(arc
					(start 342.179656 -416.49269)
					(mid 342.159732 -416.483454)
					(end 342.138 -416.480244)
				)
				(arc
					(start 341.943436 -416.480244)
					(mid 341.889554 -416.502562)
					(end 341.867236 -416.556444)
				)
			)
		)
	)
	(zone
		(layers "In15.Cu" "In16.Cu")
		(hatch none 0.5)
		(connect_pads
			(clearance 0)
		)
		(min_thickness 0.25)
		(keepout
			(tracks not_allowed)
			(vias allowed)
			(pads allowed)
			(copperpour not_allowed)
			(footprints allowed)
		)
		(placement
			(enabled no)
			(sheetname "")
		)
		(fill yes
			(thermal_gap 0.5)
			(thermal_bridge_width 0.5)
			(island_removal_mode 0)
		)
		(polygon
			(pts
				(arc
					(start 159.093916 -408.860244)
					(mid 159.116234 -408.914126)
					(end 159.170116 -408.936444)
				)
				(arc
					(start 159.365696 -408.936444)
					(mid 159.387572 -408.933312)
					(end 159.407606 -408.923998)
				)
				(arc
					(start 159.70123 -408.731466)
					(mid 159.742886 -408.719064)
					(end 159.784542 -408.731466)
				)
				(arc
					(start 160.079436 -408.923998)
					(mid 160.09936 -408.933234)
					(end 160.121092 -408.936444)
				)
				(arc
					(start 160.315656 -408.936444)
					(mid 160.369538 -408.914126)
					(end 160.391856 -408.860244)
				)
				(arc
					(start 160.391856 -408.174444)
					(mid 160.369538 -408.120562)
					(end 160.315656 -408.098244)
				)
				(arc
					(start 160.121092 -408.098244)
					(mid 160.099348 -408.101412)
					(end 160.079436 -408.11069)
				)
				(arc
					(start 159.783272 -408.303476)
					(mid 159.741588 -408.315698)
					(end 159.69996 -408.303222)
				)
				(arc
					(start 159.406336 -408.11069)
					(mid 159.386412 -408.101454)
					(end 159.36468 -408.098244)
				)
				(arc
					(start 159.170116 -408.098244)
					(mid 159.116234 -408.120562)
					(end 159.093916 -408.174444)
				)
			)
		)
	)
	(zone
		(layers "In15.Cu" "In16.Cu")
		(hatch none 0.5)
		(connect_pads
			(clearance 0)
		)
		(min_thickness 0.25)
		(keepout
			(tracks not_allowed)
			(vias allowed)
			(pads allowed)
			(copperpour not_allowed)
			(footprints allowed)
		)
		(placement
			(enabled no)
			(sheetname "")
		)
		(fill yes
			(thermal_gap 0.5)
			(thermal_bridge_width 0.5)
			(island_removal_mode 0)
		)
		(polygon
			(pts
				(arc
					(start 156.030676 -408.860244)
					(mid 156.052994 -408.914126)
					(end 156.106876 -408.936444)
				)
				(arc
					(start 156.302456 -408.936444)
					(mid 156.324332 -408.933312)
					(end 156.344366 -408.923998)
				)
				(arc
					(start 156.63799 -408.731466)
					(mid 156.679646 -408.719064)
					(end 156.721302 -408.731466)
				)
				(arc
					(start 157.016196 -408.923998)
					(mid 157.03612 -408.933234)
					(end 157.057852 -408.936444)
				)
				(arc
					(start 157.252416 -408.936444)
					(mid 157.306298 -408.914126)
					(end 157.328616 -408.860244)
				)
				(arc
					(start 157.328616 -408.174444)
					(mid 157.306298 -408.120562)
					(end 157.252416 -408.098244)
				)
				(arc
					(start 157.057852 -408.098244)
					(mid 157.036108 -408.101412)
					(end 157.016196 -408.11069)
				)
				(arc
					(start 156.720032 -408.303476)
					(mid 156.678348 -408.315698)
					(end 156.63672 -408.303222)
				)
				(arc
					(start 156.343096 -408.11069)
					(mid 156.323172 -408.101454)
					(end 156.30144 -408.098244)
				)
				(arc
					(start 156.106876 -408.098244)
					(mid 156.052994 -408.120562)
					(end 156.030676 -408.174444)
				)
			)
		)
	)
	(zone
		(layers "In15.Cu" "In16.Cu")
		(hatch none 0.5)
		(connect_pads
			(clearance 0)
		)
		(min_thickness 0.25)
		(keepout
			(tracks not_allowed)
			(vias allowed)
			(pads allowed)
			(copperpour not_allowed)
			(footprints allowed)
		)
		(placement
			(enabled no)
			(sheetname "")
		)
		(fill yes
			(thermal_gap 0.5)
			(thermal_bridge_width 0.5)
			(island_removal_mode 0)
		)
		(polygon
			(pts
				(arc
					(start 405.904192 -417.242244)
					(mid 405.92651 -417.296126)
					(end 405.980392 -417.318444)
				)
				(arc
					(start 406.175972 -417.318444)
					(mid 406.197848 -417.315312)
					(end 406.217882 -417.305998)
				)
				(arc
					(start 406.511506 -417.113466)
					(mid 406.553162 -417.101064)
					(end 406.594818 -417.113466)
				)
				(arc
					(start 406.889712 -417.305998)
					(mid 406.909636 -417.315234)
					(end 406.931368 -417.318444)
				)
				(arc
					(start 407.125932 -417.318444)
					(mid 407.179814 -417.296126)
					(end 407.202132 -417.242244)
				)
				(arc
					(start 407.202132 -416.556444)
					(mid 407.179814 -416.502562)
					(end 407.125932 -416.480244)
				)
				(arc
					(start 406.931368 -416.480244)
					(mid 406.909624 -416.483412)
					(end 406.889712 -416.49269)
				)
				(arc
					(start 406.593548 -416.685476)
					(mid 406.551864 -416.697698)
					(end 406.510236 -416.685222)
				)
				(arc
					(start 406.216612 -416.49269)
					(mid 406.196688 -416.483454)
					(end 406.174956 -416.480244)
				)
				(arc
					(start 405.980392 -416.480244)
					(mid 405.92651 -416.502562)
					(end 405.904192 -416.556444)
				)
			)
		)
	)
	(zone
		(layers "In15.Cu" "In16.Cu")
		(hatch none 0.5)
		(connect_pads
			(clearance 0)
		)
		(min_thickness 0.25)
		(keepout
			(tracks not_allowed)
			(vias allowed)
			(pads allowed)
			(copperpour not_allowed)
			(footprints allowed)
		)
		(placement
			(enabled no)
			(sheetname "")
		)
		(fill yes
			(thermal_gap 0.5)
			(thermal_bridge_width 0.5)
			(island_removal_mode 0)
		)
		(polygon
			(pts
				(arc
					(start 152.967436 -408.860244)
					(mid 152.989754 -408.914126)
					(end 153.043636 -408.936444)
				)
				(arc
					(start 153.239216 -408.936444)
					(mid 153.261092 -408.933312)
					(end 153.281126 -408.923998)
				)
				(arc
					(start 153.57475 -408.731466)
					(mid 153.616406 -408.719064)
					(end 153.658062 -408.731466)
				)
				(arc
					(start 153.952956 -408.923998)
					(mid 153.97288 -408.933234)
					(end 153.994612 -408.936444)
				)
				(arc
					(start 154.189176 -408.936444)
					(mid 154.243058 -408.914126)
					(end 154.265376 -408.860244)
				)
				(arc
					(start 154.265376 -408.174444)
					(mid 154.243058 -408.120562)
					(end 154.189176 -408.098244)
				)
				(arc
					(start 153.994612 -408.098244)
					(mid 153.972868 -408.101412)
					(end 153.952956 -408.11069)
				)
				(arc
					(start 153.656792 -408.303476)
					(mid 153.615108 -408.315698)
					(end 153.57348 -408.303222)
				)
				(arc
					(start 153.279856 -408.11069)
					(mid 153.259932 -408.101454)
					(end 153.2382 -408.098244)
				)
				(arc
					(start 153.043636 -408.098244)
					(mid 152.989754 -408.120562)
					(end 152.967436 -408.174444)
				)
			)
		)
	)
	(zone
		(layers "In15.Cu" "In16.Cu")
		(hatch none 0.5)
		(connect_pads
			(clearance 0)
		)
		(min_thickness 0.25)
		(keepout
			(tracks not_allowed)
			(vias allowed)
			(pads allowed)
			(copperpour not_allowed)
			(footprints allowed)
		)
		(placement
			(enabled no)
			(sheetname "")
		)
		(fill yes
			(thermal_gap 0.5)
			(thermal_bridge_width 0.5)
			(island_removal_mode 0)
		)
		(polygon
			(pts
				(arc
					(start 335.740756 -417.242244)
					(mid 335.763074 -417.296126)
					(end 335.816956 -417.318444)
				)
				(arc
					(start 336.012536 -417.318444)
					(mid 336.034412 -417.315312)
					(end 336.054446 -417.305998)
				)
				(arc
					(start 336.34807 -417.113466)
					(mid 336.389726 -417.101064)
					(end 336.431382 -417.113466)
				)
				(arc
					(start 336.726276 -417.305998)
					(mid 336.7462 -417.315234)
					(end 336.767932 -417.318444)
				)
				(arc
					(start 336.962496 -417.318444)
					(mid 337.016378 -417.296126)
					(end 337.038696 -417.242244)
				)
				(arc
					(start 337.038696 -416.556444)
					(mid 337.016378 -416.502562)
					(end 336.962496 -416.480244)
				)
				(arc
					(start 336.767932 -416.480244)
					(mid 336.746188 -416.483412)
					(end 336.726276 -416.49269)
				)
				(arc
					(start 336.430112 -416.685476)
					(mid 336.388428 -416.697698)
					(end 336.3468 -416.685222)
				)
				(arc
					(start 336.053176 -416.49269)
					(mid 336.033252 -416.483454)
					(end 336.01152 -416.480244)
				)
				(arc
					(start 335.816956 -416.480244)
					(mid 335.763074 -416.502562)
					(end 335.740756 -416.556444)
				)
			)
		)
	)
	(zone
		(layers "In15.Cu" "In16.Cu")
		(hatch none 0.5)
		(connect_pads
			(clearance 0)
		)
		(min_thickness 0.25)
		(keepout
			(tracks not_allowed)
			(vias allowed)
			(pads allowed)
			(copperpour not_allowed)
			(footprints allowed)
		)
		(placement
			(enabled no)
			(sheetname "")
		)
		(fill yes
			(thermal_gap 0.5)
			(thermal_bridge_width 0.5)
			(island_removal_mode 0)
		)
		(polygon
			(pts
				(arc
					(start 143.777716 -408.860244)
					(mid 143.800034 -408.914126)
					(end 143.853916 -408.936444)
				)
				(arc
					(start 144.049496 -408.936444)
					(mid 144.071372 -408.933312)
					(end 144.091406 -408.923998)
				)
				(arc
					(start 144.38503 -408.731466)
					(mid 144.426686 -408.719064)
					(end 144.468342 -408.731466)
				)
				(arc
					(start 144.763236 -408.923998)
					(mid 144.78316 -408.933234)
					(end 144.804892 -408.936444)
				)
				(arc
					(start 144.999456 -408.936444)
					(mid 145.053338 -408.914126)
					(end 145.075656 -408.860244)
				)
				(arc
					(start 145.075656 -408.174444)
					(mid 145.053338 -408.120562)
					(end 144.999456 -408.098244)
				)
				(arc
					(start 144.804892 -408.098244)
					(mid 144.783148 -408.101412)
					(end 144.763236 -408.11069)
				)
				(arc
					(start 144.467072 -408.303476)
					(mid 144.425388 -408.315698)
					(end 144.38376 -408.303222)
				)
				(arc
					(start 144.090136 -408.11069)
					(mid 144.070212 -408.101454)
					(end 144.04848 -408.098244)
				)
				(arc
					(start 143.853916 -408.098244)
					(mid 143.800034 -408.120562)
					(end 143.777716 -408.174444)
				)
			)
		)
	)
	(zone
		(layers "In15.Cu" "In16.Cu")
		(hatch none 0.5)
		(connect_pads
			(clearance 0)
		)
		(min_thickness 0.25)
		(keepout
			(tracks not_allowed)
			(vias allowed)
			(pads allowed)
			(copperpour not_allowed)
			(footprints allowed)
		)
		(placement
			(enabled no)
			(sheetname "")
		)
		(fill yes
			(thermal_gap 0.5)
			(thermal_bridge_width 0.5)
			(island_removal_mode 0)
		)
		(polygon
			(pts
				(arc
					(start 375.271792 -417.242244)
					(mid 375.29411 -417.296126)
					(end 375.347992 -417.318444)
				)
				(arc
					(start 375.543572 -417.318444)
					(mid 375.565448 -417.315312)
					(end 375.585482 -417.305998)
				)
				(arc
					(start 375.879106 -417.113466)
					(mid 375.920762 -417.101064)
					(end 375.962418 -417.113466)
				)
				(arc
					(start 376.257312 -417.305998)
					(mid 376.277236 -417.315234)
					(end 376.298968 -417.318444)
				)
				(arc
					(start 376.493532 -417.318444)
					(mid 376.547414 -417.296126)
					(end 376.569732 -417.242244)
				)
				(arc
					(start 376.569732 -416.556444)
					(mid 376.547414 -416.502562)
					(end 376.493532 -416.480244)
				)
				(arc
					(start 376.298968 -416.480244)
					(mid 376.277224 -416.483412)
					(end 376.257312 -416.49269)
				)
				(arc
					(start 375.961148 -416.685476)
					(mid 375.919464 -416.697698)
					(end 375.877836 -416.685222)
				)
				(arc
					(start 375.584212 -416.49269)
					(mid 375.564288 -416.483454)
					(end 375.542556 -416.480244)
				)
				(arc
					(start 375.347992 -416.480244)
					(mid 375.29411 -416.502562)
					(end 375.271792 -416.556444)
				)
			)
		)
	)
	(zone
		(layers "In15.Cu" "In16.Cu")
		(hatch none 0.5)
		(connect_pads
			(clearance 0)
		)
		(min_thickness 0.25)
		(keepout
			(tracks not_allowed)
			(vias allowed)
			(pads allowed)
			(copperpour not_allowed)
			(footprints allowed)
		)
		(placement
			(enabled no)
			(sheetname "")
		)
		(fill yes
			(thermal_gap 0.5)
			(thermal_bridge_width 0.5)
			(island_removal_mode 0)
		)
		(polygon
			(pts
				(arc
					(start 305.108356 -417.242244)
					(mid 305.130674 -417.296126)
					(end 305.184556 -417.318444)
				)
				(arc
					(start 305.380136 -417.318444)
					(mid 305.402012 -417.315312)
					(end 305.422046 -417.305998)
				)
				(arc
					(start 305.71567 -417.113466)
					(mid 305.757326 -417.101064)
					(end 305.798982 -417.113466)
				)
				(arc
					(start 306.093876 -417.305998)
					(mid 306.1138 -417.315234)
					(end 306.135532 -417.318444)
				)
				(arc
					(start 306.330096 -417.318444)
					(mid 306.383978 -417.296126)
					(end 306.406296 -417.242244)
				)
				(arc
					(start 306.406296 -416.556444)
					(mid 306.383978 -416.502562)
					(end 306.330096 -416.480244)
				)
				(arc
					(start 306.135532 -416.480244)
					(mid 306.113788 -416.483412)
					(end 306.093876 -416.49269)
				)
				(arc
					(start 305.797712 -416.685476)
					(mid 305.756028 -416.697698)
					(end 305.7144 -416.685222)
				)
				(arc
					(start 305.420776 -416.49269)
					(mid 305.400852 -416.483454)
					(end 305.37912 -416.480244)
				)
				(arc
					(start 305.184556 -416.480244)
					(mid 305.130674 -416.502562)
					(end 305.108356 -416.556444)
				)
			)
		)
	)
	(zone
		(layers "In15.Cu" "In16.Cu")
		(hatch none 0.5)
		(connect_pads
			(clearance 0)
		)
		(min_thickness 0.25)
		(keepout
			(tracks not_allowed)
			(vias allowed)
			(pads allowed)
			(copperpour not_allowed)
			(footprints allowed)
		)
		(placement
			(enabled no)
			(sheetname "")
		)
		(fill yes
			(thermal_gap 0.5)
			(thermal_bridge_width 0.5)
			(island_removal_mode 0)
		)
		(polygon
			(pts
				(arc
					(start 412.030672 -417.242244)
					(mid 412.05299 -417.296126)
					(end 412.106872 -417.318444)
				)
				(arc
					(start 412.302452 -417.318444)
					(mid 412.324328 -417.315312)
					(end 412.344362 -417.305998)
				)
				(arc
					(start 412.637986 -417.113466)
					(mid 412.679642 -417.101064)
					(end 412.721298 -417.113466)
				)
				(arc
					(start 413.016192 -417.305998)
					(mid 413.036116 -417.315234)
					(end 413.057848 -417.318444)
				)
				(arc
					(start 413.252412 -417.318444)
					(mid 413.306294 -417.296126)
					(end 413.328612 -417.242244)
				)
				(arc
					(start 413.328612 -416.556444)
					(mid 413.306294 -416.502562)
					(end 413.252412 -416.480244)
				)
				(arc
					(start 413.057848 -416.480244)
					(mid 413.036104 -416.483412)
					(end 413.016192 -416.49269)
				)
				(arc
					(start 412.720028 -416.685476)
					(mid 412.678344 -416.697698)
					(end 412.636716 -416.685222)
				)
				(arc
					(start 412.343092 -416.49269)
					(mid 412.323168 -416.483454)
					(end 412.301436 -416.480244)
				)
				(arc
					(start 412.106872 -416.480244)
					(mid 412.05299 -416.502562)
					(end 412.030672 -416.556444)
				)
			)
		)
	)
	(zone
		(layers "In15.Cu" "In16.Cu")
		(hatch none 0.5)
		(connect_pads
			(clearance 0)
		)
		(min_thickness 0.25)
		(keepout
			(tracks not_allowed)
			(vias allowed)
			(pads allowed)
			(copperpour not_allowed)
			(footprints allowed)
		)
		(placement
			(enabled no)
			(sheetname "")
		)
		(fill yes
			(thermal_gap 0.5)
			(thermal_bridge_width 0.5)
			(island_removal_mode 0)
		)
		(polygon
			(pts
				(arc
					(start 308.171596 -417.242244)
					(mid 308.193914 -417.296126)
					(end 308.247796 -417.318444)
				)
				(arc
					(start 308.443376 -417.318444)
					(mid 308.465252 -417.315312)
					(end 308.485286 -417.305998)
				)
				(arc
					(start 308.77891 -417.113466)
					(mid 308.820566 -417.101064)
					(end 308.862222 -417.113466)
				)
				(arc
					(start 309.157116 -417.305998)
					(mid 309.17704 -417.315234)
					(end 309.198772 -417.318444)
				)
				(arc
					(start 309.393336 -417.318444)
					(mid 309.447218 -417.296126)
					(end 309.469536 -417.242244)
				)
				(arc
					(start 309.469536 -416.556444)
					(mid 309.447218 -416.502562)
					(end 309.393336 -416.480244)
				)
				(arc
					(start 309.198772 -416.480244)
					(mid 309.177028 -416.483412)
					(end 309.157116 -416.49269)
				)
				(arc
					(start 308.860952 -416.685476)
					(mid 308.819268 -416.697698)
					(end 308.77764 -416.685222)
				)
				(arc
					(start 308.484016 -416.49269)
					(mid 308.464092 -416.483454)
					(end 308.44236 -416.480244)
				)
				(arc
					(start 308.247796 -416.480244)
					(mid 308.193914 -416.502562)
					(end 308.171596 -416.556444)
				)
			)
		)
	)
	(zone
		(layers "In15.Cu" "In16.Cu")
		(hatch none 0.5)
		(connect_pads
			(clearance 0)
		)
		(min_thickness 0.25)
		(keepout
			(tracks not_allowed)
			(vias allowed)
			(pads allowed)
			(copperpour not_allowed)
			(footprints allowed)
		)
		(placement
			(enabled no)
			(sheetname "")
		)
		(fill yes
			(thermal_gap 0.5)
			(thermal_bridge_width 0.5)
			(island_removal_mode 0)
		)
		(polygon
			(pts
				(arc
					(start 329.614276 -417.242244)
					(mid 329.636594 -417.296126)
					(end 329.690476 -417.318444)
				)
				(arc
					(start 329.886056 -417.318444)
					(mid 329.907932 -417.315312)
					(end 329.927966 -417.305998)
				)
				(arc
					(start 330.22159 -417.113466)
					(mid 330.263246 -417.101064)
					(end 330.304902 -417.113466)
				)
				(arc
					(start 330.599796 -417.305998)
					(mid 330.61972 -417.315234)
					(end 330.641452 -417.318444)
				)
				(arc
					(start 330.836016 -417.318444)
					(mid 330.889898 -417.296126)
					(end 330.912216 -417.242244)
				)
				(arc
					(start 330.912216 -416.556444)
					(mid 330.889898 -416.502562)
					(end 330.836016 -416.480244)
				)
				(arc
					(start 330.641452 -416.480244)
					(mid 330.619708 -416.483412)
					(end 330.599796 -416.49269)
				)
				(arc
					(start 330.303632 -416.685476)
					(mid 330.261948 -416.697698)
					(end 330.22032 -416.685222)
				)
				(arc
					(start 329.926696 -416.49269)
					(mid 329.906772 -416.483454)
					(end 329.88504 -416.480244)
				)
				(arc
					(start 329.690476 -416.480244)
					(mid 329.636594 -416.502562)
					(end 329.614276 -416.556444)
				)
			)
		)
	)
	(zone
		(layers "In15.Cu" "In16.Cu")
		(hatch none 0.5)
		(connect_pads
			(clearance 0)
		)
		(min_thickness 0.25)
		(keepout
			(tracks not_allowed)
			(vias allowed)
			(pads allowed)
			(copperpour not_allowed)
			(footprints allowed)
		)
		(placement
			(enabled no)
			(sheetname "")
		)
		(fill yes
			(thermal_gap 0.5)
			(thermal_bridge_width 0.5)
			(island_removal_mode 0)
		)
		(polygon
			(pts
				(arc
					(start 415.093912 -417.242244)
					(mid 415.11623 -417.296126)
					(end 415.170112 -417.318444)
				)
				(arc
					(start 415.365692 -417.318444)
					(mid 415.387568 -417.315312)
					(end 415.407602 -417.305998)
				)
				(arc
					(start 415.701226 -417.113466)
					(mid 415.742882 -417.101064)
					(end 415.784538 -417.113466)
				)
				(arc
					(start 416.079432 -417.305998)
					(mid 416.099356 -417.315234)
					(end 416.121088 -417.318444)
				)
				(arc
					(start 416.315652 -417.318444)
					(mid 416.369534 -417.296126)
					(end 416.391852 -417.242244)
				)
				(arc
					(start 416.391852 -416.556444)
					(mid 416.369534 -416.502562)
					(end 416.315652 -416.480244)
				)
				(arc
					(start 416.121088 -416.480244)
					(mid 416.099344 -416.483412)
					(end 416.079432 -416.49269)
				)
				(arc
					(start 415.783268 -416.685476)
					(mid 415.741584 -416.697698)
					(end 415.699956 -416.685222)
				)
				(arc
					(start 415.406332 -416.49269)
					(mid 415.386408 -416.483454)
					(end 415.364676 -416.480244)
				)
				(arc
					(start 415.170112 -416.480244)
					(mid 415.11623 -416.502562)
					(end 415.093912 -416.556444)
				)
			)
		)
	)
	(zone
		(layers "In15.Cu" "In16.Cu")
		(hatch none 0.5)
		(connect_pads
			(clearance 0)
		)
		(min_thickness 0.25)
		(keepout
			(tracks not_allowed)
			(vias allowed)
			(pads allowed)
			(copperpour not_allowed)
			(footprints allowed)
		)
		(placement
			(enabled no)
			(sheetname "")
		)
		(fill yes
			(thermal_gap 0.5)
			(thermal_bridge_width 0.5)
			(island_removal_mode 0)
		)
		(polygon
			(pts
				(arc
					(start 399.777712 -417.242244)
					(mid 399.80003 -417.296126)
					(end 399.853912 -417.318444)
				)
				(arc
					(start 400.049492 -417.318444)
					(mid 400.071368 -417.315312)
					(end 400.091402 -417.305998)
				)
				(arc
					(start 400.385026 -417.113466)
					(mid 400.426682 -417.101064)
					(end 400.468338 -417.113466)
				)
				(arc
					(start 400.763232 -417.305998)
					(mid 400.783156 -417.315234)
					(end 400.804888 -417.318444)
				)
				(arc
					(start 400.999452 -417.318444)
					(mid 401.053334 -417.296126)
					(end 401.075652 -417.242244)
				)
				(arc
					(start 401.075652 -416.556444)
					(mid 401.053334 -416.502562)
					(end 400.999452 -416.480244)
				)
				(arc
					(start 400.804888 -416.480244)
					(mid 400.783144 -416.483412)
					(end 400.763232 -416.49269)
				)
				(arc
					(start 400.467068 -416.685476)
					(mid 400.425384 -416.697698)
					(end 400.383756 -416.685222)
				)
				(arc
					(start 400.090132 -416.49269)
					(mid 400.070208 -416.483454)
					(end 400.048476 -416.480244)
				)
				(arc
					(start 399.853912 -416.480244)
					(mid 399.80003 -416.502562)
					(end 399.777712 -416.556444)
				)
			)
		)
	)
	(zone
		(layers "In15.Cu" "In16.Cu")
		(hatch none 0.5)
		(connect_pads
			(clearance 0)
		)
		(min_thickness 0.25)
		(keepout
			(tracks not_allowed)
			(vias allowed)
			(pads allowed)
			(copperpour not_allowed)
			(footprints allowed)
		)
		(placement
			(enabled no)
			(sheetname "")
		)
		(fill yes
			(thermal_gap 0.5)
			(thermal_bridge_width 0.5)
			(island_removal_mode 0)
		)
		(polygon
			(pts
				(arc
					(start 378.335032 -417.242244)
					(mid 378.35735 -417.296126)
					(end 378.411232 -417.318444)
				)
				(arc
					(start 378.606812 -417.318444)
					(mid 378.628688 -417.315312)
					(end 378.648722 -417.305998)
				)
				(arc
					(start 378.942346 -417.113466)
					(mid 378.984002 -417.101064)
					(end 379.025658 -417.113466)
				)
				(arc
					(start 379.320552 -417.305998)
					(mid 379.340476 -417.315234)
					(end 379.362208 -417.318444)
				)
				(arc
					(start 379.556772 -417.318444)
					(mid 379.610654 -417.296126)
					(end 379.632972 -417.242244)
				)
				(arc
					(start 379.632972 -416.556444)
					(mid 379.610654 -416.502562)
					(end 379.556772 -416.480244)
				)
				(arc
					(start 379.362208 -416.480244)
					(mid 379.340464 -416.483412)
					(end 379.320552 -416.49269)
				)
				(arc
					(start 379.024388 -416.685476)
					(mid 378.982704 -416.697698)
					(end 378.941076 -416.685222)
				)
				(arc
					(start 378.647452 -416.49269)
					(mid 378.627528 -416.483454)
					(end 378.605796 -416.480244)
				)
				(arc
					(start 378.411232 -416.480244)
					(mid 378.35735 -416.502562)
					(end 378.335032 -416.556444)
				)
			)
		)
	)
	(zone
		(layers "In15.Cu" "In16.Cu")
		(hatch none 0.5)
		(connect_pads
			(clearance 0)
		)
		(min_thickness 0.25)
		(keepout
			(tracks not_allowed)
			(vias allowed)
			(pads allowed)
			(copperpour not_allowed)
			(footprints allowed)
		)
		(placement
			(enabled no)
			(sheetname "")
		)
		(fill yes
			(thermal_gap 0.5)
			(thermal_bridge_width 0.5)
			(island_removal_mode 0)
		)
		(polygon
			(pts
				(arc
					(start 91.993974 -408.860244)
					(mid 92.016292 -408.914126)
					(end 92.070174 -408.936444)
				)
				(arc
					(start 92.265754 -408.936444)
					(mid 92.28763 -408.933312)
					(end 92.307664 -408.923998)
				)
				(arc
					(start 92.601288 -408.731466)
					(mid 92.642944 -408.719064)
					(end 92.6846 -408.731466)
				)
				(arc
					(start 92.979494 -408.923998)
					(mid 92.999418 -408.933234)
					(end 93.02115 -408.936444)
				)
				(arc
					(start 93.215714 -408.936444)
					(mid 93.269596 -408.914126)
					(end 93.291914 -408.860244)
				)
				(arc
					(start 93.291914 -408.174444)
					(mid 93.269596 -408.120562)
					(end 93.215714 -408.098244)
				)
				(arc
					(start 93.02115 -408.098244)
					(mid 92.999406 -408.101412)
					(end 92.979494 -408.11069)
				)
				(arc
					(start 92.68333 -408.303476)
					(mid 92.641646 -408.315698)
					(end 92.600018 -408.303222)
				)
				(arc
					(start 92.306394 -408.11069)
					(mid 92.28647 -408.101454)
					(end 92.264738 -408.098244)
				)
				(arc
					(start 92.070174 -408.098244)
					(mid 92.016292 -408.120562)
					(end 91.993974 -408.174444)
				)
			)
		)
	)
	(zone
		(layers "In15.Cu" "In16.Cu")
		(hatch none 0.5)
		(connect_pads
			(clearance 0)
		)
		(min_thickness 0.25)
		(keepout
			(tracks not_allowed)
			(vias allowed)
			(pads allowed)
			(copperpour not_allowed)
			(footprints allowed)
		)
		(placement
			(enabled no)
			(sheetname "")
		)
		(fill yes
			(thermal_gap 0.5)
			(thermal_bridge_width 0.5)
			(island_removal_mode 0)
		)
		(polygon
			(pts
				(arc
					(start 344.930476 -417.242244)
					(mid 344.952794 -417.296126)
					(end 345.006676 -417.318444)
				)
				(arc
					(start 345.202256 -417.318444)
					(mid 345.224132 -417.315312)
					(end 345.244166 -417.305998)
				)
				(arc
					(start 345.53779 -417.113466)
					(mid 345.579446 -417.101064)
					(end 345.621102 -417.113466)
				)
				(arc
					(start 345.915996 -417.305998)
					(mid 345.93592 -417.315234)
					(end 345.957652 -417.318444)
				)
				(arc
					(start 346.152216 -417.318444)
					(mid 346.206098 -417.296126)
					(end 346.228416 -417.242244)
				)
				(arc
					(start 346.228416 -416.556444)
					(mid 346.206098 -416.502562)
					(end 346.152216 -416.480244)
				)
				(arc
					(start 345.957652 -416.480244)
					(mid 345.935908 -416.483412)
					(end 345.915996 -416.49269)
				)
				(arc
					(start 345.619832 -416.685476)
					(mid 345.578148 -416.697698)
					(end 345.53652 -416.685222)
				)
				(arc
					(start 345.242896 -416.49269)
					(mid 345.222972 -416.483454)
					(end 345.20124 -416.480244)
				)
				(arc
					(start 345.006676 -416.480244)
					(mid 344.952794 -416.502562)
					(end 344.930476 -416.556444)
				)
			)
		)
	)
	(zone
		(layers "In15.Cu" "In16.Cu")
		(hatch none 0.5)
		(connect_pads
			(clearance 0)
		)
		(min_thickness 0.25)
		(keepout
			(tracks not_allowed)
			(vias allowed)
			(pads allowed)
			(copperpour not_allowed)
			(footprints allowed)
		)
		(placement
			(enabled no)
			(sheetname "")
		)
		(fill yes
			(thermal_gap 0.5)
			(thermal_bridge_width 0.5)
			(island_removal_mode 0)
		)
		(polygon
			(pts
				(arc
					(start 125.398276 -408.860244)
					(mid 125.420594 -408.914126)
					(end 125.474476 -408.936444)
				)
				(arc
					(start 125.670056 -408.936444)
					(mid 125.691932 -408.933312)
					(end 125.711966 -408.923998)
				)
				(arc
					(start 126.00559 -408.731466)
					(mid 126.047246 -408.719064)
					(end 126.088902 -408.731466)
				)
				(arc
					(start 126.383796 -408.923998)
					(mid 126.40372 -408.933234)
					(end 126.425452 -408.936444)
				)
				(arc
					(start 126.620016 -408.936444)
					(mid 126.673898 -408.914126)
					(end 126.696216 -408.860244)
				)
				(arc
					(start 126.696216 -408.174444)
					(mid 126.673898 -408.120562)
					(end 126.620016 -408.098244)
				)
				(arc
					(start 126.425452 -408.098244)
					(mid 126.403708 -408.101412)
					(end 126.383796 -408.11069)
				)
				(arc
					(start 126.087632 -408.303476)
					(mid 126.045948 -408.315698)
					(end 126.00432 -408.303222)
				)
				(arc
					(start 125.710696 -408.11069)
					(mid 125.690772 -408.101454)
					(end 125.66904 -408.098244)
				)
				(arc
					(start 125.474476 -408.098244)
					(mid 125.420594 -408.120562)
					(end 125.398276 -408.174444)
				)
			)
		)
	)
	(zone
		(layers "In15.Cu" "In16.Cu")
		(hatch none 0.5)
		(connect_pads
			(clearance 0)
		)
		(min_thickness 0.25)
		(keepout
			(tracks not_allowed)
			(vias allowed)
			(pads allowed)
			(copperpour not_allowed)
			(footprints allowed)
		)
		(placement
			(enabled no)
			(sheetname "")
		)
		(fill yes
			(thermal_gap 0.5)
			(thermal_bridge_width 0.5)
			(island_removal_mode 0)
		)
		(polygon
			(pts
				(arc
					(start 140.714476 -408.860244)
					(mid 140.736794 -408.914126)
					(end 140.790676 -408.936444)
				)
				(arc
					(start 140.986256 -408.936444)
					(mid 141.008132 -408.933312)
					(end 141.028166 -408.923998)
				)
				(arc
					(start 141.32179 -408.731466)
					(mid 141.363446 -408.719064)
					(end 141.405102 -408.731466)
				)
				(arc
					(start 141.699996 -408.923998)
					(mid 141.71992 -408.933234)
					(end 141.741652 -408.936444)
				)
				(arc
					(start 141.936216 -408.936444)
					(mid 141.990098 -408.914126)
					(end 142.012416 -408.860244)
				)
				(arc
					(start 142.012416 -408.174444)
					(mid 141.990098 -408.120562)
					(end 141.936216 -408.098244)
				)
				(arc
					(start 141.741652 -408.098244)
					(mid 141.719908 -408.101412)
					(end 141.699996 -408.11069)
				)
				(arc
					(start 141.403832 -408.303476)
					(mid 141.362148 -408.315698)
					(end 141.32052 -408.303222)
				)
				(arc
					(start 141.026896 -408.11069)
					(mid 141.006972 -408.101454)
					(end 140.98524 -408.098244)
				)
				(arc
					(start 140.790676 -408.098244)
					(mid 140.736794 -408.120562)
					(end 140.714476 -408.174444)
				)
			)
		)
	)
	(zone
		(layers "In15.Cu" "In16.Cu")
		(hatch none 0.5)
		(connect_pads
			(clearance 0)
		)
		(min_thickness 0.25)
		(keepout
			(tracks not_allowed)
			(vias allowed)
			(pads allowed)
			(copperpour not_allowed)
			(footprints allowed)
		)
		(placement
			(enabled no)
			(sheetname "")
		)
		(fill yes
			(thermal_gap 0.5)
			(thermal_bridge_width 0.5)
			(island_removal_mode 0)
		)
		(polygon
			(pts
				(arc
					(start 332.677516 -417.242244)
					(mid 332.699834 -417.296126)
					(end 332.753716 -417.318444)
				)
				(arc
					(start 332.949296 -417.318444)
					(mid 332.971172 -417.315312)
					(end 332.991206 -417.305998)
				)
				(arc
					(start 333.28483 -417.113466)
					(mid 333.326486 -417.101064)
					(end 333.368142 -417.113466)
				)
				(arc
					(start 333.663036 -417.305998)
					(mid 333.68296 -417.315234)
					(end 333.704692 -417.318444)
				)
				(arc
					(start 333.899256 -417.318444)
					(mid 333.953138 -417.296126)
					(end 333.975456 -417.242244)
				)
				(arc
					(start 333.975456 -416.556444)
					(mid 333.953138 -416.502562)
					(end 333.899256 -416.480244)
				)
				(arc
					(start 333.704692 -416.480244)
					(mid 333.682948 -416.483412)
					(end 333.663036 -416.49269)
				)
				(arc
					(start 333.366872 -416.685476)
					(mid 333.325188 -416.697698)
					(end 333.28356 -416.685222)
				)
				(arc
					(start 332.989936 -416.49269)
					(mid 332.970012 -416.483454)
					(end 332.94828 -416.480244)
				)
				(arc
					(start 332.753716 -416.480244)
					(mid 332.699834 -416.502562)
					(end 332.677516 -416.556444)
				)
			)
		)
	)
	(zone
		(layers "In15.Cu" "In16.Cu")
		(hatch none 0.5)
		(connect_pads
			(clearance 0)
		)
		(min_thickness 0.25)
		(keepout
			(tracks not_allowed)
			(vias allowed)
			(pads allowed)
			(copperpour not_allowed)
			(footprints allowed)
		)
		(placement
			(enabled no)
			(sheetname "")
		)
		(fill yes
			(thermal_gap 0.5)
			(thermal_bridge_width 0.5)
			(island_removal_mode 0)
		)
		(polygon
			(pts
				(arc
					(start 122.335036 -408.860244)
					(mid 122.357354 -408.914126)
					(end 122.411236 -408.936444)
				)
				(arc
					(start 122.606816 -408.936444)
					(mid 122.628692 -408.933312)
					(end 122.648726 -408.923998)
				)
				(arc
					(start 122.94235 -408.731466)
					(mid 122.984006 -408.719064)
					(end 123.025662 -408.731466)
				)
				(arc
					(start 123.320556 -408.923998)
					(mid 123.34048 -408.933234)
					(end 123.362212 -408.936444)
				)
				(arc
					(start 123.556776 -408.936444)
					(mid 123.610658 -408.914126)
					(end 123.632976 -408.860244)
				)
				(arc
					(start 123.632976 -408.174444)
					(mid 123.610658 -408.120562)
					(end 123.556776 -408.098244)
				)
				(arc
					(start 123.362212 -408.098244)
					(mid 123.340468 -408.101412)
					(end 123.320556 -408.11069)
				)
				(arc
					(start 123.024392 -408.303476)
					(mid 122.982708 -408.315698)
					(end 122.94108 -408.303222)
				)
				(arc
					(start 122.647456 -408.11069)
					(mid 122.627532 -408.101454)
					(end 122.6058 -408.098244)
				)
				(arc
					(start 122.411236 -408.098244)
					(mid 122.357354 -408.120562)
					(end 122.335036 -408.174444)
				)
			)
		)
	)
	(zone
		(layers "In15.Cu" "In16.Cu")
		(hatch none 0.5)
		(connect_pads
			(clearance 0)
		)
		(min_thickness 0.25)
		(keepout
			(tracks not_allowed)
			(vias allowed)
			(pads allowed)
			(copperpour not_allowed)
			(footprints allowed)
		)
		(placement
			(enabled no)
			(sheetname "")
		)
		(fill yes
			(thermal_gap 0.5)
			(thermal_bridge_width 0.5)
			(island_removal_mode 0)
		)
		(polygon
			(pts
				(arc
					(start 131.524756 -408.860244)
					(mid 131.547074 -408.914126)
					(end 131.600956 -408.936444)
				)
				(arc
					(start 131.796536 -408.936444)
					(mid 131.818412 -408.933312)
					(end 131.838446 -408.923998)
				)
				(arc
					(start 132.13207 -408.731466)
					(mid 132.173726 -408.719064)
					(end 132.215382 -408.731466)
				)
				(arc
					(start 132.510276 -408.923998)
					(mid 132.5302 -408.933234)
					(end 132.551932 -408.936444)
				)
				(arc
					(start 132.746496 -408.936444)
					(mid 132.800378 -408.914126)
					(end 132.822696 -408.860244)
				)
				(arc
					(start 132.822696 -408.174444)
					(mid 132.800378 -408.120562)
					(end 132.746496 -408.098244)
				)
				(arc
					(start 132.551932 -408.098244)
					(mid 132.530188 -408.101412)
					(end 132.510276 -408.11069)
				)
				(arc
					(start 132.214112 -408.303476)
					(mid 132.172428 -408.315698)
					(end 132.1308 -408.303222)
				)
				(arc
					(start 131.837176 -408.11069)
					(mid 131.817252 -408.101454)
					(end 131.79552 -408.098244)
				)
				(arc
					(start 131.600956 -408.098244)
					(mid 131.547074 -408.120562)
					(end 131.524756 -408.174444)
				)
			)
		)
	)
	(zone
		(layers "In15.Cu" "In16.Cu")
		(hatch none 0.5)
		(connect_pads
			(clearance 0)
		)
		(min_thickness 0.25)
		(keepout
			(tracks not_allowed)
			(vias allowed)
			(pads allowed)
			(copperpour not_allowed)
			(footprints allowed)
		)
		(placement
			(enabled no)
			(sheetname "")
		)
		(fill yes
			(thermal_gap 0.5)
			(thermal_bridge_width 0.5)
			(island_removal_mode 0)
		)
		(polygon
			(pts
				(arc
					(start 49.108614 -408.860244)
					(mid 49.130932 -408.914126)
					(end 49.184814 -408.936444)
				)
				(arc
					(start 49.380394 -408.936444)
					(mid 49.40227 -408.933312)
					(end 49.422304 -408.923998)
				)
				(arc
					(start 49.715928 -408.731466)
					(mid 49.757584 -408.719064)
					(end 49.79924 -408.731466)
				)
				(arc
					(start 50.094134 -408.923998)
					(mid 50.114058 -408.933234)
					(end 50.13579 -408.936444)
				)
				(arc
					(start 50.330354 -408.936444)
					(mid 50.384236 -408.914126)
					(end 50.406554 -408.860244)
				)
				(arc
					(start 50.406554 -408.174444)
					(mid 50.384236 -408.120562)
					(end 50.330354 -408.098244)
				)
				(arc
					(start 50.13579 -408.098244)
					(mid 50.114046 -408.101412)
					(end 50.094134 -408.11069)
				)
				(arc
					(start 49.79797 -408.303476)
					(mid 49.756286 -408.315698)
					(end 49.714658 -408.303222)
				)
				(arc
					(start 49.421034 -408.11069)
					(mid 49.40111 -408.101454)
					(end 49.379378 -408.098244)
				)
				(arc
					(start 49.184814 -408.098244)
					(mid 49.130932 -408.120562)
					(end 49.108614 -408.174444)
				)
			)
		)
	)
	(zone
		(layers "In15.Cu" "In16.Cu")
		(hatch none 0.5)
		(connect_pads
			(clearance 0)
		)
		(min_thickness 0.25)
		(keepout
			(tracks not_allowed)
			(vias allowed)
			(pads allowed)
			(copperpour not_allowed)
			(footprints allowed)
		)
		(placement
			(enabled no)
			(sheetname "")
		)
		(fill yes
			(thermal_gap 0.5)
			(thermal_bridge_width 0.5)
			(island_removal_mode 0)
		)
		(polygon
			(pts
				(arc
					(start 149.904196 -408.860244)
					(mid 149.926514 -408.914126)
					(end 149.980396 -408.936444)
				)
				(arc
					(start 150.175976 -408.936444)
					(mid 150.197852 -408.933312)
					(end 150.217886 -408.923998)
				)
				(arc
					(start 150.51151 -408.731466)
					(mid 150.553166 -408.719064)
					(end 150.594822 -408.731466)
				)
				(arc
					(start 150.889716 -408.923998)
					(mid 150.90964 -408.933234)
					(end 150.931372 -408.936444)
				)
				(arc
					(start 151.125936 -408.936444)
					(mid 151.179818 -408.914126)
					(end 151.202136 -408.860244)
				)
				(arc
					(start 151.202136 -408.174444)
					(mid 151.179818 -408.120562)
					(end 151.125936 -408.098244)
				)
				(arc
					(start 150.931372 -408.098244)
					(mid 150.909628 -408.101412)
					(end 150.889716 -408.11069)
				)
				(arc
					(start 150.593552 -408.303476)
					(mid 150.551868 -408.315698)
					(end 150.51024 -408.303222)
				)
				(arc
					(start 150.216616 -408.11069)
					(mid 150.196692 -408.101454)
					(end 150.17496 -408.098244)
				)
				(arc
					(start 149.980396 -408.098244)
					(mid 149.926514 -408.120562)
					(end 149.904196 -408.174444)
				)
			)
		)
	)
	(zone
		(layers "In15.Cu" "In16.Cu")
		(hatch none 0.5)
		(connect_pads
			(clearance 0)
		)
		(min_thickness 0.25)
		(keepout
			(tracks not_allowed)
			(vias allowed)
			(pads allowed)
			(copperpour not_allowed)
			(footprints allowed)
		)
		(placement
			(enabled no)
			(sheetname "")
		)
		(fill yes
			(thermal_gap 0.5)
			(thermal_bridge_width 0.5)
			(island_removal_mode 0)
		)
		(polygon
			(pts
				(arc
					(start 418.157152 -417.242244)
					(mid 418.17947 -417.296126)
					(end 418.233352 -417.318444)
				)
				(arc
					(start 418.428932 -417.318444)
					(mid 418.450808 -417.315312)
					(end 418.470842 -417.305998)
				)
				(arc
					(start 418.764466 -417.113466)
					(mid 418.806122 -417.101064)
					(end 418.847778 -417.113466)
				)
				(arc
					(start 419.142672 -417.305998)
					(mid 419.162596 -417.315234)
					(end 419.184328 -417.318444)
				)
				(arc
					(start 419.378892 -417.318444)
					(mid 419.432774 -417.296126)
					(end 419.455092 -417.242244)
				)
				(arc
					(start 419.455092 -416.556444)
					(mid 419.432774 -416.502562)
					(end 419.378892 -416.480244)
				)
				(arc
					(start 419.184328 -416.480244)
					(mid 419.162584 -416.483412)
					(end 419.142672 -416.49269)
				)
				(arc
					(start 418.846508 -416.685476)
					(mid 418.804824 -416.697698)
					(end 418.763196 -416.685222)
				)
				(arc
					(start 418.469572 -416.49269)
					(mid 418.449648 -416.483454)
					(end 418.427916 -416.480244)
				)
				(arc
					(start 418.233352 -416.480244)
					(mid 418.17947 -416.502562)
					(end 418.157152 -416.556444)
				)
			)
		)
	)
	(zone
		(layers "In15.Cu" "In16.Cu")
		(hatch none 0.5)
		(connect_pads
			(clearance 0)
		)
		(min_thickness 0.25)
		(keepout
			(tracks not_allowed)
			(vias allowed)
			(pads allowed)
			(copperpour not_allowed)
			(footprints allowed)
		)
		(placement
			(enabled no)
			(sheetname "")
		)
		(fill yes
			(thermal_gap 0.5)
			(thermal_bridge_width 0.5)
			(island_removal_mode 0)
		)
		(polygon
			(pts
				(arc
					(start 85.867494 -408.860244)
					(mid 85.889812 -408.914126)
					(end 85.943694 -408.936444)
				)
				(arc
					(start 86.139274 -408.936444)
					(mid 86.16115 -408.933312)
					(end 86.181184 -408.923998)
				)
				(arc
					(start 86.474808 -408.731466)
					(mid 86.516464 -408.719064)
					(end 86.55812 -408.731466)
				)
				(arc
					(start 86.853014 -408.923998)
					(mid 86.872938 -408.933234)
					(end 86.89467 -408.936444)
				)
				(arc
					(start 87.089234 -408.936444)
					(mid 87.143116 -408.914126)
					(end 87.165434 -408.860244)
				)
				(arc
					(start 87.165434 -408.174444)
					(mid 87.143116 -408.120562)
					(end 87.089234 -408.098244)
				)
				(arc
					(start 86.89467 -408.098244)
					(mid 86.872926 -408.101412)
					(end 86.853014 -408.11069)
				)
				(arc
					(start 86.55685 -408.303476)
					(mid 86.515166 -408.315698)
					(end 86.473538 -408.303222)
				)
				(arc
					(start 86.179914 -408.11069)
					(mid 86.15999 -408.101454)
					(end 86.138258 -408.098244)
				)
				(arc
					(start 85.943694 -408.098244)
					(mid 85.889812 -408.120562)
					(end 85.867494 -408.174444)
				)
			)
		)
	)
	(zone
		(layers "In15.Cu" "In16.Cu")
		(hatch none 0.5)
		(connect_pads
			(clearance 0)
		)
		(min_thickness 0.25)
		(keepout
			(tracks not_allowed)
			(vias allowed)
			(pads allowed)
			(copperpour not_allowed)
			(footprints allowed)
		)
		(placement
			(enabled no)
			(sheetname "")
		)
		(fill yes
			(thermal_gap 0.5)
			(thermal_bridge_width 0.5)
			(island_removal_mode 0)
		)
		(polygon
			(pts
				(arc
					(start 61.361574 -408.860244)
					(mid 61.383892 -408.914126)
					(end 61.437774 -408.936444)
				)
				(arc
					(start 61.633354 -408.936444)
					(mid 61.65523 -408.933312)
					(end 61.675264 -408.923998)
				)
				(arc
					(start 61.968888 -408.731466)
					(mid 62.010544 -408.719064)
					(end 62.0522 -408.731466)
				)
				(arc
					(start 62.347094 -408.923998)
					(mid 62.367018 -408.933234)
					(end 62.38875 -408.936444)
				)
				(arc
					(start 62.583314 -408.936444)
					(mid 62.637196 -408.914126)
					(end 62.659514 -408.860244)
				)
				(arc
					(start 62.659514 -408.174444)
					(mid 62.637196 -408.120562)
					(end 62.583314 -408.098244)
				)
				(arc
					(start 62.38875 -408.098244)
					(mid 62.367006 -408.101412)
					(end 62.347094 -408.11069)
				)
				(arc
					(start 62.05093 -408.303476)
					(mid 62.009246 -408.315698)
					(end 61.967618 -408.303222)
				)
				(arc
					(start 61.673994 -408.11069)
					(mid 61.65407 -408.101454)
					(end 61.632338 -408.098244)
				)
				(arc
					(start 61.437774 -408.098244)
					(mid 61.383892 -408.120562)
					(end 61.361574 -408.174444)
				)
			)
		)
	)
	(zone
		(layers "In15.Cu" "In16.Cu")
		(hatch none 0.5)
		(connect_pads
			(clearance 0)
		)
		(min_thickness 0.25)
		(keepout
			(tracks not_allowed)
			(vias allowed)
			(pads allowed)
			(copperpour not_allowed)
			(footprints allowed)
		)
		(placement
			(enabled no)
			(sheetname "")
		)
		(fill yes
			(thermal_gap 0.5)
			(thermal_bridge_width 0.5)
			(island_removal_mode 0)
		)
		(polygon
			(pts
				(arc
					(start 408.967432 -417.242244)
					(mid 408.98975 -417.296126)
					(end 409.043632 -417.318444)
				)
				(arc
					(start 409.239212 -417.318444)
					(mid 409.261088 -417.315312)
					(end 409.281122 -417.305998)
				)
				(arc
					(start 409.574746 -417.113466)
					(mid 409.616402 -417.101064)
					(end 409.658058 -417.113466)
				)
				(arc
					(start 409.952952 -417.305998)
					(mid 409.972876 -417.315234)
					(end 409.994608 -417.318444)
				)
				(arc
					(start 410.189172 -417.318444)
					(mid 410.243054 -417.296126)
					(end 410.265372 -417.242244)
				)
				(arc
					(start 410.265372 -416.556444)
					(mid 410.243054 -416.502562)
					(end 410.189172 -416.480244)
				)
				(arc
					(start 409.994608 -416.480244)
					(mid 409.972864 -416.483412)
					(end 409.952952 -416.49269)
				)
				(arc
					(start 409.656788 -416.685476)
					(mid 409.615104 -416.697698)
					(end 409.573476 -416.685222)
				)
				(arc
					(start 409.279852 -416.49269)
					(mid 409.259928 -416.483454)
					(end 409.238196 -416.480244)
				)
				(arc
					(start 409.043632 -416.480244)
					(mid 408.98975 -416.502562)
					(end 408.967432 -416.556444)
				)
			)
		)
	)
	(zone
		(layers "In15.Cu" "In16.Cu")
		(hatch none 0.5)
		(connect_pads
			(clearance 0)
		)
		(min_thickness 0.25)
		(keepout
			(tracks not_allowed)
			(vias allowed)
			(pads allowed)
			(copperpour not_allowed)
			(footprints allowed)
		)
		(placement
			(enabled no)
			(sheetname "")
		)
		(fill yes
			(thermal_gap 0.5)
			(thermal_bridge_width 0.5)
			(island_removal_mode 0)
		)
		(polygon
			(pts
				(arc
					(start 73.614534 -408.860244)
					(mid 73.636852 -408.914126)
					(end 73.690734 -408.936444)
				)
				(arc
					(start 73.886314 -408.936444)
					(mid 73.90819 -408.933312)
					(end 73.928224 -408.923998)
				)
				(arc
					(start 74.221848 -408.731466)
					(mid 74.263504 -408.719064)
					(end 74.30516 -408.731466)
				)
				(arc
					(start 74.600054 -408.923998)
					(mid 74.619978 -408.933234)
					(end 74.64171 -408.936444)
				)
				(arc
					(start 74.836274 -408.936444)
					(mid 74.890156 -408.914126)
					(end 74.912474 -408.860244)
				)
				(arc
					(start 74.912474 -408.174444)
					(mid 74.890156 -408.120562)
					(end 74.836274 -408.098244)
				)
				(arc
					(start 74.64171 -408.098244)
					(mid 74.619966 -408.101412)
					(end 74.600054 -408.11069)
				)
				(arc
					(start 74.30389 -408.303476)
					(mid 74.262206 -408.315698)
					(end 74.220578 -408.303222)
				)
				(arc
					(start 73.926954 -408.11069)
					(mid 73.90703 -408.101454)
					(end 73.885298 -408.098244)
				)
				(arc
					(start 73.690734 -408.098244)
					(mid 73.636852 -408.120562)
					(end 73.614534 -408.174444)
				)
			)
		)
	)
	(zone
		(layers "In15.Cu" "In16.Cu")
		(hatch none 0.5)
		(connect_pads
			(clearance 0)
		)
		(min_thickness 0.25)
		(keepout
			(tracks not_allowed)
			(vias allowed)
			(pads allowed)
			(copperpour not_allowed)
			(footprints allowed)
		)
		(placement
			(enabled no)
			(sheetname "")
		)
		(fill yes
			(thermal_gap 0.5)
			(thermal_bridge_width 0.5)
			(island_removal_mode 0)
		)
		(polygon
			(pts
				(arc
					(start 51.392074 -415.861246)
					(mid 51.338192 -415.883564)
					(end 51.315874 -415.937446)
				)
				(arc
					(start 51.315874 -416.133026)
					(mid 51.319006 -416.154902)
					(end 51.32832 -416.174936)
				)
				(arc
					(start 51.520852 -416.46856)
					(mid 51.533254 -416.510216)
					(end 51.520852 -416.551872)
				)
				(arc
					(start 51.32832 -416.846766)
					(mid 51.319084 -416.86669)
					(end 51.315874 -416.888422)
				)
				(arc
					(start 51.315874 -417.082986)
					(mid 51.338192 -417.136868)
					(end 51.392074 -417.159186)
				)
				(arc
					(start 52.077874 -417.159186)
					(mid 52.131756 -417.136868)
					(end 52.154074 -417.082986)
				)
				(arc
					(start 52.154074 -416.888422)
					(mid 52.150906 -416.866678)
					(end 52.141628 -416.846766)
				)
				(arc
					(start 51.948842 -416.550602)
					(mid 51.93662 -416.508918)
					(end 51.949096 -416.46729)
				)
				(arc
					(start 52.141628 -416.173666)
					(mid 52.150864 -416.153742)
					(end 52.154074 -416.13201)
				)
				(arc
					(start 52.154074 -415.937446)
					(mid 52.131756 -415.883564)
					(end 52.077874 -415.861246)
				)
			)
		)
	)
	(zone
		(layers "In15.Cu" "In16.Cu")
		(hatch none 0.5)
		(connect_pads
			(clearance 0)
		)
		(min_thickness 0.25)
		(keepout
			(tracks not_allowed)
			(vias allowed)
			(pads allowed)
			(copperpour not_allowed)
			(footprints allowed)
		)
		(placement
			(enabled no)
			(sheetname "")
		)
		(fill yes
			(thermal_gap 0.5)
			(thermal_bridge_width 0.5)
			(island_removal_mode 0)
		)
		(polygon
			(pts
				(arc
					(start 338.803996 -417.242244)
					(mid 338.826314 -417.296126)
					(end 338.880196 -417.318444)
				)
				(arc
					(start 339.075776 -417.318444)
					(mid 339.097652 -417.315312)
					(end 339.117686 -417.305998)
				)
				(arc
					(start 339.41131 -417.113466)
					(mid 339.452966 -417.101064)
					(end 339.494622 -417.113466)
				)
				(arc
					(start 339.789516 -417.305998)
					(mid 339.80944 -417.315234)
					(end 339.831172 -417.318444)
				)
				(arc
					(start 340.025736 -417.318444)
					(mid 340.079618 -417.296126)
					(end 340.101936 -417.242244)
				)
				(arc
					(start 340.101936 -416.556444)
					(mid 340.079618 -416.502562)
					(end 340.025736 -416.480244)
				)
				(arc
					(start 339.831172 -416.480244)
					(mid 339.809428 -416.483412)
					(end 339.789516 -416.49269)
				)
				(arc
					(start 339.493352 -416.685476)
					(mid 339.451668 -416.697698)
					(end 339.41004 -416.685222)
				)
				(arc
					(start 339.116416 -416.49269)
					(mid 339.096492 -416.483454)
					(end 339.07476 -416.480244)
				)
				(arc
					(start 338.880196 -416.480244)
					(mid 338.826314 -416.502562)
					(end 338.803996 -416.556444)
				)
			)
		)
	)
	(zone
		(layers "In15.Cu" "In16.Cu")
		(hatch none 0.5)
		(connect_pads
			(clearance 0)
		)
		(min_thickness 0.25)
		(keepout
			(tracks not_allowed)
			(vias allowed)
			(pads allowed)
			(copperpour not_allowed)
			(footprints allowed)
		)
		(placement
			(enabled no)
			(sheetname "")
		)
		(fill yes
			(thermal_gap 0.5)
			(thermal_bridge_width 0.5)
			(island_removal_mode 0)
		)
		(polygon
			(pts
				(arc
					(start 43.80611 -412.623508)
					(mid 43.752228 -412.645826)
					(end 43.72991 -412.699708)
				)
				(arc
					(start 43.72991 -412.895288)
					(mid 43.733042 -412.917164)
					(end 43.742356 -412.937198)
				)
				(arc
					(start 43.934888 -413.230822)
					(mid 43.94729 -413.272478)
					(end 43.934888 -413.314134)
				)
				(arc
					(start 43.742356 -413.609028)
					(mid 43.73312 -413.628952)
					(end 43.72991 -413.650684)
				)
				(arc
					(start 43.72991 -413.845248)
					(mid 43.752228 -413.89913)
					(end 43.80611 -413.921448)
				)
				(arc
					(start 44.49191 -413.921448)
					(mid 44.545792 -413.89913)
					(end 44.56811 -413.845248)
				)
				(arc
					(start 44.56811 -413.650684)
					(mid 44.564942 -413.62894)
					(end 44.555664 -413.609028)
				)
				(arc
					(start 44.362878 -413.312864)
					(mid 44.350656 -413.27118)
					(end 44.363132 -413.229552)
				)
				(arc
					(start 44.555664 -412.935928)
					(mid 44.5649 -412.916004)
					(end 44.56811 -412.894272)
				)
				(arc
					(start 44.56811 -412.699708)
					(mid 44.545792 -412.645826)
					(end 44.49191 -412.623508)
				)
			)
		)
	)
	(zone
		(layers "In15.Cu" "In16.Cu")
		(hatch none 0.5)
		(connect_pads
			(clearance 0)
		)
		(min_thickness 0.25)
		(keepout
			(tracks not_allowed)
			(vias allowed)
			(pads allowed)
			(copperpour not_allowed)
			(footprints allowed)
		)
		(placement
			(enabled no)
			(sheetname "")
		)
		(fill yes
			(thermal_gap 0.5)
			(thermal_bridge_width 0.5)
			(island_removal_mode 0)
		)
		(polygon
			(pts
				(arc
					(start 390.587992 -417.242244)
					(mid 390.61031 -417.296126)
					(end 390.664192 -417.318444)
				)
				(arc
					(start 390.859772 -417.318444)
					(mid 390.881648 -417.315312)
					(end 390.901682 -417.305998)
				)
				(arc
					(start 391.195306 -417.113466)
					(mid 391.236962 -417.101064)
					(end 391.278618 -417.113466)
				)
				(arc
					(start 391.573512 -417.305998)
					(mid 391.593436 -417.315234)
					(end 391.615168 -417.318444)
				)
				(arc
					(start 391.809732 -417.318444)
					(mid 391.863614 -417.296126)
					(end 391.885932 -417.242244)
				)
				(arc
					(start 391.885932 -416.556444)
					(mid 391.863614 -416.502562)
					(end 391.809732 -416.480244)
				)
				(arc
					(start 391.615168 -416.480244)
					(mid 391.593424 -416.483412)
					(end 391.573512 -416.49269)
				)
				(arc
					(start 391.277348 -416.685476)
					(mid 391.235664 -416.697698)
					(end 391.194036 -416.685222)
				)
				(arc
					(start 390.900412 -416.49269)
					(mid 390.880488 -416.483454)
					(end 390.858756 -416.480244)
				)
				(arc
					(start 390.664192 -416.480244)
					(mid 390.61031 -416.502562)
					(end 390.587992 -416.556444)
				)
			)
		)
	)
	(zone
		(layers "In15.Cu" "In16.Cu")
		(hatch none 0.5)
		(connect_pads
			(clearance 0)
		)
		(min_thickness 0.25)
		(keepout
			(tracks not_allowed)
			(vias allowed)
			(pads allowed)
			(copperpour not_allowed)
			(footprints allowed)
		)
		(placement
			(enabled no)
			(sheetname "")
		)
		(fill yes
			(thermal_gap 0.5)
			(thermal_bridge_width 0.5)
			(island_removal_mode 0)
		)
		(polygon
			(pts
				(arc
					(start 326.551036 -417.242244)
					(mid 326.573354 -417.296126)
					(end 326.627236 -417.318444)
				)
				(arc
					(start 326.822816 -417.318444)
					(mid 326.844692 -417.315312)
					(end 326.864726 -417.305998)
				)
				(arc
					(start 327.15835 -417.113466)
					(mid 327.200006 -417.101064)
					(end 327.241662 -417.113466)
				)
				(arc
					(start 327.536556 -417.305998)
					(mid 327.55648 -417.315234)
					(end 327.578212 -417.318444)
				)
				(arc
					(start 327.772776 -417.318444)
					(mid 327.826658 -417.296126)
					(end 327.848976 -417.242244)
				)
				(arc
					(start 327.848976 -416.556444)
					(mid 327.826658 -416.502562)
					(end 327.772776 -416.480244)
				)
				(arc
					(start 327.578212 -416.480244)
					(mid 327.556468 -416.483412)
					(end 327.536556 -416.49269)
				)
				(arc
					(start 327.240392 -416.685476)
					(mid 327.198708 -416.697698)
					(end 327.15708 -416.685222)
				)
				(arc
					(start 326.863456 -416.49269)
					(mid 326.843532 -416.483454)
					(end 326.8218 -416.480244)
				)
				(arc
					(start 326.627236 -416.480244)
					(mid 326.573354 -416.502562)
					(end 326.551036 -416.556444)
				)
			)
		)
	)
	(zone
		(layers "In15.Cu" "In16.Cu")
		(hatch none 0.5)
		(connect_pads
			(clearance 0)
		)
		(min_thickness 0.25)
		(keepout
			(tracks not_allowed)
			(vias allowed)
			(pads allowed)
			(copperpour not_allowed)
			(footprints allowed)
		)
		(placement
			(enabled no)
			(sheetname "")
		)
		(fill yes
			(thermal_gap 0.5)
			(thermal_bridge_width 0.5)
			(island_removal_mode 0)
		)
		(polygon
			(pts
				(arc
					(start 162.157156 -408.860244)
					(mid 162.179474 -408.914126)
					(end 162.233356 -408.936444)
				)
				(arc
					(start 162.428936 -408.936444)
					(mid 162.450812 -408.933312)
					(end 162.470846 -408.923998)
				)
				(arc
					(start 162.76447 -408.731466)
					(mid 162.806126 -408.719064)
					(end 162.847782 -408.731466)
				)
				(arc
					(start 163.142676 -408.923998)
					(mid 163.1626 -408.933234)
					(end 163.184332 -408.936444)
				)
				(arc
					(start 163.378896 -408.936444)
					(mid 163.432778 -408.914126)
					(end 163.455096 -408.860244)
				)
				(arc
					(start 163.455096 -408.174444)
					(mid 163.432778 -408.120562)
					(end 163.378896 -408.098244)
				)
				(arc
					(start 163.184332 -408.098244)
					(mid 163.162588 -408.101412)
					(end 163.142676 -408.11069)
				)
				(arc
					(start 162.846512 -408.303476)
					(mid 162.804828 -408.315698)
					(end 162.7632 -408.303222)
				)
				(arc
					(start 162.469576 -408.11069)
					(mid 162.449652 -408.101454)
					(end 162.42792 -408.098244)
				)
				(arc
					(start 162.233356 -408.098244)
					(mid 162.179474 -408.120562)
					(end 162.157156 -408.174444)
				)
			)
		)
	)
	(zone
		(layers "In15.Cu" "In16.Cu")
		(hatch none 0.5)
		(connect_pads
			(clearance 0)
		)
		(min_thickness 0.25)
		(keepout
			(tracks not_allowed)
			(vias allowed)
			(pads allowed)
			(copperpour not_allowed)
			(footprints allowed)
		)
		(placement
			(enabled no)
			(sheetname "")
		)
		(fill yes
			(thermal_gap 0.5)
			(thermal_bridge_width 0.5)
			(island_removal_mode 0)
		)
		(polygon
			(pts
				(arc
					(start 314.298076 -417.242244)
					(mid 314.320394 -417.296126)
					(end 314.374276 -417.318444)
				)
				(arc
					(start 314.569856 -417.318444)
					(mid 314.591732 -417.315312)
					(end 314.611766 -417.305998)
				)
				(arc
					(start 314.90539 -417.113466)
					(mid 314.947046 -417.101064)
					(end 314.988702 -417.113466)
				)
				(arc
					(start 315.283596 -417.305998)
					(mid 315.30352 -417.315234)
					(end 315.325252 -417.318444)
				)
				(arc
					(start 315.519816 -417.318444)
					(mid 315.573698 -417.296126)
					(end 315.596016 -417.242244)
				)
				(arc
					(start 315.596016 -416.556444)
					(mid 315.573698 -416.502562)
					(end 315.519816 -416.480244)
				)
				(arc
					(start 315.325252 -416.480244)
					(mid 315.303508 -416.483412)
					(end 315.283596 -416.49269)
				)
				(arc
					(start 314.987432 -416.685476)
					(mid 314.945748 -416.697698)
					(end 314.90412 -416.685222)
				)
				(arc
					(start 314.610496 -416.49269)
					(mid 314.590572 -416.483454)
					(end 314.56884 -416.480244)
				)
				(arc
					(start 314.374276 -416.480244)
					(mid 314.320394 -416.502562)
					(end 314.298076 -416.556444)
				)
			)
		)
	)
	(zone
		(layers "In15.Cu" "In16.Cu")
		(hatch none 0.5)
		(connect_pads
			(clearance 0)
		)
		(min_thickness 0.25)
		(keepout
			(tracks not_allowed)
			(vias allowed)
			(pads allowed)
			(copperpour not_allowed)
			(footprints allowed)
		)
		(placement
			(enabled no)
			(sheetname "")
		)
		(fill yes
			(thermal_gap 0.5)
			(thermal_bridge_width 0.5)
			(island_removal_mode 0)
		)
		(polygon
			(pts
				(arc
					(start 67.488054 -408.860244)
					(mid 67.510372 -408.914126)
					(end 67.564254 -408.936444)
				)
				(arc
					(start 67.759834 -408.936444)
					(mid 67.78171 -408.933312)
					(end 67.801744 -408.923998)
				)
				(arc
					(start 68.095368 -408.731466)
					(mid 68.137024 -408.719064)
					(end 68.17868 -408.731466)
				)
				(arc
					(start 68.473574 -408.923998)
					(mid 68.493498 -408.933234)
					(end 68.51523 -408.936444)
				)
				(arc
					(start 68.709794 -408.936444)
					(mid 68.763676 -408.914126)
					(end 68.785994 -408.860244)
				)
				(arc
					(start 68.785994 -408.174444)
					(mid 68.763676 -408.120562)
					(end 68.709794 -408.098244)
				)
				(arc
					(start 68.51523 -408.098244)
					(mid 68.493486 -408.101412)
					(end 68.473574 -408.11069)
				)
				(arc
					(start 68.17741 -408.303476)
					(mid 68.135726 -408.315698)
					(end 68.094098 -408.303222)
				)
				(arc
					(start 67.800474 -408.11069)
					(mid 67.78055 -408.101454)
					(end 67.758818 -408.098244)
				)
				(arc
					(start 67.564254 -408.098244)
					(mid 67.510372 -408.120562)
					(end 67.488054 -408.174444)
				)
			)
		)
	)
	(zone
		(layers "In15.Cu" "In16.Cu")
		(hatch none 0.5)
		(connect_pads
			(clearance 0)
		)
		(min_thickness 0.25)
		(keepout
			(tracks not_allowed)
			(vias allowed)
			(pads allowed)
			(copperpour not_allowed)
			(footprints allowed)
		)
		(placement
			(enabled no)
			(sheetname "")
		)
		(fill yes
			(thermal_gap 0.5)
			(thermal_bridge_width 0.5)
			(island_removal_mode 0)
		)
		(polygon
			(pts
				(arc
					(start 137.651236 -408.860244)
					(mid 137.673554 -408.914126)
					(end 137.727436 -408.936444)
				)
				(arc
					(start 137.923016 -408.936444)
					(mid 137.944892 -408.933312)
					(end 137.964926 -408.923998)
				)
				(arc
					(start 138.25855 -408.731466)
					(mid 138.300206 -408.719064)
					(end 138.341862 -408.731466)
				)
				(arc
					(start 138.636756 -408.923998)
					(mid 138.65668 -408.933234)
					(end 138.678412 -408.936444)
				)
				(arc
					(start 138.872976 -408.936444)
					(mid 138.926858 -408.914126)
					(end 138.949176 -408.860244)
				)
				(arc
					(start 138.949176 -408.174444)
					(mid 138.926858 -408.120562)
					(end 138.872976 -408.098244)
				)
				(arc
					(start 138.678412 -408.098244)
					(mid 138.656668 -408.101412)
					(end 138.636756 -408.11069)
				)
				(arc
					(start 138.340592 -408.303476)
					(mid 138.298908 -408.315698)
					(end 138.25728 -408.303222)
				)
				(arc
					(start 137.963656 -408.11069)
					(mid 137.943732 -408.101454)
					(end 137.922 -408.098244)
				)
				(arc
					(start 137.727436 -408.098244)
					(mid 137.673554 -408.120562)
					(end 137.651236 -408.174444)
				)
			)
		)
	)
	(zone
		(layers "In15.Cu" "In16.Cu")
		(hatch none 0.5)
		(connect_pads
			(clearance 0)
		)
		(min_thickness 0.25)
		(keepout
			(tracks not_allowed)
			(vias allowed)
			(pads allowed)
			(copperpour not_allowed)
			(footprints allowed)
		)
		(placement
			(enabled no)
			(sheetname "")
		)
		(fill yes
			(thermal_gap 0.5)
			(thermal_bridge_width 0.5)
			(island_removal_mode 0)
		)
		(polygon
			(pts
				(arc
					(start 88.930734 -408.860244)
					(mid 88.953052 -408.914126)
					(end 89.006934 -408.936444)
				)
				(arc
					(start 89.202514 -408.936444)
					(mid 89.22439 -408.933312)
					(end 89.244424 -408.923998)
				)
				(arc
					(start 89.538048 -408.731466)
					(mid 89.579704 -408.719064)
					(end 89.62136 -408.731466)
				)
				(arc
					(start 89.916254 -408.923998)
					(mid 89.936178 -408.933234)
					(end 89.95791 -408.936444)
				)
				(arc
					(start 90.152474 -408.936444)
					(mid 90.206356 -408.914126)
					(end 90.228674 -408.860244)
				)
				(arc
					(start 90.228674 -408.174444)
					(mid 90.206356 -408.120562)
					(end 90.152474 -408.098244)
				)
				(arc
					(start 89.95791 -408.098244)
					(mid 89.936166 -408.101412)
					(end 89.916254 -408.11069)
				)
				(arc
					(start 89.62009 -408.303476)
					(mid 89.578406 -408.315698)
					(end 89.536778 -408.303222)
				)
				(arc
					(start 89.243154 -408.11069)
					(mid 89.22323 -408.101454)
					(end 89.201498 -408.098244)
				)
				(arc
					(start 89.006934 -408.098244)
					(mid 88.953052 -408.120562)
					(end 88.930734 -408.174444)
				)
			)
		)
	)
	(zone
		(layers "In15.Cu" "In16.Cu")
		(hatch none 0.5)
		(connect_pads
			(clearance 0)
		)
		(min_thickness 0.25)
		(keepout
			(tracks not_allowed)
			(vias allowed)
			(pads allowed)
			(copperpour not_allowed)
			(footprints allowed)
		)
		(placement
			(enabled no)
			(sheetname "")
		)
		(fill yes
			(thermal_gap 0.5)
			(thermal_bridge_width 0.5)
			(island_removal_mode 0)
		)
		(polygon
			(pts
				(arc
					(start 55.235094 -408.860244)
					(mid 55.257412 -408.914126)
					(end 55.311294 -408.936444)
				)
				(arc
					(start 55.506874 -408.936444)
					(mid 55.52875 -408.933312)
					(end 55.548784 -408.923998)
				)
				(arc
					(start 55.842408 -408.731466)
					(mid 55.884064 -408.719064)
					(end 55.92572 -408.731466)
				)
				(arc
					(start 56.220614 -408.923998)
					(mid 56.240538 -408.933234)
					(end 56.26227 -408.936444)
				)
				(arc
					(start 56.456834 -408.936444)
					(mid 56.510716 -408.914126)
					(end 56.533034 -408.860244)
				)
				(arc
					(start 56.533034 -408.174444)
					(mid 56.510716 -408.120562)
					(end 56.456834 -408.098244)
				)
				(arc
					(start 56.26227 -408.098244)
					(mid 56.240526 -408.101412)
					(end 56.220614 -408.11069)
				)
				(arc
					(start 55.92445 -408.303476)
					(mid 55.882766 -408.315698)
					(end 55.841138 -408.303222)
				)
				(arc
					(start 55.547514 -408.11069)
					(mid 55.52759 -408.101454)
					(end 55.505858 -408.098244)
				)
				(arc
					(start 55.311294 -408.098244)
					(mid 55.257412 -408.120562)
					(end 55.235094 -408.174444)
				)
			)
		)
	)
	(zone
		(layers "In15.Cu" "In16.Cu")
		(hatch none 0.5)
		(connect_pads
			(clearance 0)
		)
		(min_thickness 0.25)
		(keepout
			(tracks not_allowed)
			(vias allowed)
			(pads allowed)
			(copperpour not_allowed)
			(footprints allowed)
		)
		(placement
			(enabled no)
			(sheetname "")
		)
		(fill yes
			(thermal_gap 0.5)
			(thermal_bridge_width 0.5)
			(island_removal_mode 0)
		)
		(polygon
			(pts
				(arc
					(start 95.057214 -408.860244)
					(mid 95.079532 -408.914126)
					(end 95.133414 -408.936444)
				)
				(arc
					(start 95.328994 -408.936444)
					(mid 95.35087 -408.933312)
					(end 95.370904 -408.923998)
				)
				(arc
					(start 95.664528 -408.731466)
					(mid 95.706184 -408.719064)
					(end 95.74784 -408.731466)
				)
				(arc
					(start 96.042734 -408.923998)
					(mid 96.062658 -408.933234)
					(end 96.08439 -408.936444)
				)
				(arc
					(start 96.278954 -408.936444)
					(mid 96.332836 -408.914126)
					(end 96.355154 -408.860244)
				)
				(arc
					(start 96.355154 -408.174444)
					(mid 96.332836 -408.120562)
					(end 96.278954 -408.098244)
				)
				(arc
					(start 96.08439 -408.098244)
					(mid 96.062646 -408.101412)
					(end 96.042734 -408.11069)
				)
				(arc
					(start 95.74657 -408.303476)
					(mid 95.704886 -408.315698)
					(end 95.663258 -408.303222)
				)
				(arc
					(start 95.369634 -408.11069)
					(mid 95.34971 -408.101454)
					(end 95.327978 -408.098244)
				)
				(arc
					(start 95.133414 -408.098244)
					(mid 95.079532 -408.120562)
					(end 95.057214 -408.174444)
				)
			)
		)
	)
	(zone
		(layers "In15.Cu" "In16.Cu")
		(hatch none 0.5)
		(connect_pads
			(clearance 0)
		)
		(min_thickness 0.25)
		(keepout
			(tracks not_allowed)
			(vias allowed)
			(pads allowed)
			(copperpour not_allowed)
			(footprints allowed)
		)
		(placement
			(enabled no)
			(sheetname "")
		)
		(fill yes
			(thermal_gap 0.5)
			(thermal_bridge_width 0.5)
			(island_removal_mode 0)
		)
		(polygon
			(pts
				(arc
					(start 311.234836 -417.242244)
					(mid 311.257154 -417.296126)
					(end 311.311036 -417.318444)
				)
				(arc
					(start 311.506616 -417.318444)
					(mid 311.528492 -417.315312)
					(end 311.548526 -417.305998)
				)
				(arc
					(start 311.84215 -417.113466)
					(mid 311.883806 -417.101064)
					(end 311.925462 -417.113466)
				)
				(arc
					(start 312.220356 -417.305998)
					(mid 312.24028 -417.315234)
					(end 312.262012 -417.318444)
				)
				(arc
					(start 312.456576 -417.318444)
					(mid 312.510458 -417.296126)
					(end 312.532776 -417.242244)
				)
				(arc
					(start 312.532776 -416.556444)
					(mid 312.510458 -416.502562)
					(end 312.456576 -416.480244)
				)
				(arc
					(start 312.262012 -416.480244)
					(mid 312.240268 -416.483412)
					(end 312.220356 -416.49269)
				)
				(arc
					(start 311.924192 -416.685476)
					(mid 311.882508 -416.697698)
					(end 311.84088 -416.685222)
				)
				(arc
					(start 311.547256 -416.49269)
					(mid 311.527332 -416.483454)
					(end 311.5056 -416.480244)
				)
				(arc
					(start 311.311036 -416.480244)
					(mid 311.257154 -416.502562)
					(end 311.234836 -416.556444)
				)
			)
		)
	)
	(zone
		(layers "In15.Cu" "In16.Cu")
		(hatch none 0.5)
		(connect_pads
			(clearance 0)
		)
		(min_thickness 0.25)
		(keepout
			(tracks not_allowed)
			(vias allowed)
			(pads allowed)
			(copperpour not_allowed)
			(footprints allowed)
		)
		(placement
			(enabled no)
			(sheetname "")
		)
		(fill yes
			(thermal_gap 0.5)
			(thermal_bridge_width 0.5)
			(island_removal_mode 0)
		)
		(polygon
			(pts
				(arc
					(start 70.551294 -408.860244)
					(mid 70.573612 -408.914126)
					(end 70.627494 -408.936444)
				)
				(arc
					(start 70.823074 -408.936444)
					(mid 70.84495 -408.933312)
					(end 70.864984 -408.923998)
				)
				(arc
					(start 71.158608 -408.731466)
					(mid 71.200264 -408.719064)
					(end 71.24192 -408.731466)
				)
				(arc
					(start 71.536814 -408.923998)
					(mid 71.556738 -408.933234)
					(end 71.57847 -408.936444)
				)
				(arc
					(start 71.773034 -408.936444)
					(mid 71.826916 -408.914126)
					(end 71.849234 -408.860244)
				)
				(arc
					(start 71.849234 -408.174444)
					(mid 71.826916 -408.120562)
					(end 71.773034 -408.098244)
				)
				(arc
					(start 71.57847 -408.098244)
					(mid 71.556726 -408.101412)
					(end 71.536814 -408.11069)
				)
				(arc
					(start 71.24065 -408.303476)
					(mid 71.198966 -408.315698)
					(end 71.157338 -408.303222)
				)
				(arc
					(start 70.863714 -408.11069)
					(mid 70.84379 -408.101454)
					(end 70.822058 -408.098244)
				)
				(arc
					(start 70.627494 -408.098244)
					(mid 70.573612 -408.120562)
					(end 70.551294 -408.174444)
				)
			)
		)
	)
	(zone
		(layers "In15.Cu" "In16.Cu")
		(hatch none 0.5)
		(connect_pads
			(clearance 0)
		)
		(min_thickness 0.25)
		(keepout
			(tracks not_allowed)
			(vias allowed)
			(pads allowed)
			(copperpour not_allowed)
			(footprints allowed)
		)
		(placement
			(enabled no)
			(sheetname "")
		)
		(fill yes
			(thermal_gap 0.5)
			(thermal_bridge_width 0.5)
			(island_removal_mode 0)
		)
		(polygon
			(pts
				(arc
					(start 58.298334 -408.860244)
					(mid 58.320652 -408.914126)
					(end 58.374534 -408.936444)
				)
				(arc
					(start 58.570114 -408.936444)
					(mid 58.59199 -408.933312)
					(end 58.612024 -408.923998)
				)
				(arc
					(start 58.905648 -408.731466)
					(mid 58.947304 -408.719064)
					(end 58.98896 -408.731466)
				)
				(arc
					(start 59.283854 -408.923998)
					(mid 59.303778 -408.933234)
					(end 59.32551 -408.936444)
				)
				(arc
					(start 59.520074 -408.936444)
					(mid 59.573956 -408.914126)
					(end 59.596274 -408.860244)
				)
				(arc
					(start 59.596274 -408.174444)
					(mid 59.573956 -408.120562)
					(end 59.520074 -408.098244)
				)
				(arc
					(start 59.32551 -408.098244)
					(mid 59.303766 -408.101412)
					(end 59.283854 -408.11069)
				)
				(arc
					(start 58.98769 -408.303476)
					(mid 58.946006 -408.315698)
					(end 58.904378 -408.303222)
				)
				(arc
					(start 58.610754 -408.11069)
					(mid 58.59083 -408.101454)
					(end 58.569098 -408.098244)
				)
				(arc
					(start 58.374534 -408.098244)
					(mid 58.320652 -408.120562)
					(end 58.298334 -408.174444)
				)
			)
		)
	)
	(zone
		(layers "In15.Cu" "In16.Cu")
		(hatch none 0.5)
		(connect_pads
			(clearance 0)
		)
		(min_thickness 0.25)
		(keepout
			(tracks not_allowed)
			(vias allowed)
			(pads allowed)
			(copperpour not_allowed)
			(footprints allowed)
		)
		(placement
			(enabled no)
			(sheetname "")
		)
		(fill yes
			(thermal_gap 0.5)
			(thermal_bridge_width 0.5)
			(island_removal_mode 0)
		)
		(polygon
			(pts
				(arc
					(start 79.741014 -408.860244)
					(mid 79.763332 -408.914126)
					(end 79.817214 -408.936444)
				)
				(arc
					(start 80.012794 -408.936444)
					(mid 80.03467 -408.933312)
					(end 80.054704 -408.923998)
				)
				(arc
					(start 80.348328 -408.731466)
					(mid 80.389984 -408.719064)
					(end 80.43164 -408.731466)
				)
				(arc
					(start 80.726534 -408.923998)
					(mid 80.746458 -408.933234)
					(end 80.76819 -408.936444)
				)
				(arc
					(start 80.962754 -408.936444)
					(mid 81.016636 -408.914126)
					(end 81.038954 -408.860244)
				)
				(arc
					(start 81.038954 -408.174444)
					(mid 81.016636 -408.120562)
					(end 80.962754 -408.098244)
				)
				(arc
					(start 80.76819 -408.098244)
					(mid 80.746446 -408.101412)
					(end 80.726534 -408.11069)
				)
				(arc
					(start 80.43037 -408.303476)
					(mid 80.388686 -408.315698)
					(end 80.347058 -408.303222)
				)
				(arc
					(start 80.053434 -408.11069)
					(mid 80.03351 -408.101454)
					(end 80.011778 -408.098244)
				)
				(arc
					(start 79.817214 -408.098244)
					(mid 79.763332 -408.120562)
					(end 79.741014 -408.174444)
				)
			)
		)
	)
	(zone
		(layers "In15.Cu" "In16.Cu")
		(hatch none 0.5)
		(connect_pads
			(clearance 0)
		)
		(min_thickness 0.25)
		(keepout
			(tracks not_allowed)
			(vias allowed)
			(pads allowed)
			(copperpour not_allowed)
			(footprints allowed)
		)
		(placement
			(enabled no)
			(sheetname "")
		)
		(fill yes
			(thermal_gap 0.5)
			(thermal_bridge_width 0.5)
			(island_removal_mode 0)
		)
		(polygon
			(pts
				(arc
					(start 384.461512 -417.242244)
					(mid 384.48383 -417.296126)
					(end 384.537712 -417.318444)
				)
				(arc
					(start 384.733292 -417.318444)
					(mid 384.755168 -417.315312)
					(end 384.775202 -417.305998)
				)
				(arc
					(start 385.068826 -417.113466)
					(mid 385.110482 -417.101064)
					(end 385.152138 -417.113466)
				)
				(arc
					(start 385.447032 -417.305998)
					(mid 385.466956 -417.315234)
					(end 385.488688 -417.318444)
				)
				(arc
					(start 385.683252 -417.318444)
					(mid 385.737134 -417.296126)
					(end 385.759452 -417.242244)
				)
				(arc
					(start 385.759452 -416.556444)
					(mid 385.737134 -416.502562)
					(end 385.683252 -416.480244)
				)
				(arc
					(start 385.488688 -416.480244)
					(mid 385.466944 -416.483412)
					(end 385.447032 -416.49269)
				)
				(arc
					(start 385.150868 -416.685476)
					(mid 385.109184 -416.697698)
					(end 385.067556 -416.685222)
				)
				(arc
					(start 384.773932 -416.49269)
					(mid 384.754008 -416.483454)
					(end 384.732276 -416.480244)
				)
				(arc
					(start 384.537712 -416.480244)
					(mid 384.48383 -416.502562)
					(end 384.461512 -416.556444)
				)
			)
		)
	)
	(zone
		(layers "In15.Cu" "In16.Cu")
		(hatch none 0.5)
		(connect_pads
			(clearance 0)
		)
		(min_thickness 0.25)
		(keepout
			(tracks not_allowed)
			(vias allowed)
			(pads allowed)
			(copperpour not_allowed)
			(footprints allowed)
		)
		(placement
			(enabled no)
			(sheetname "")
		)
		(fill yes
			(thermal_gap 0.5)
			(thermal_bridge_width 0.5)
			(island_removal_mode 0)
		)
		(polygon
			(pts
				(arc
					(start 393.651232 -417.242244)
					(mid 393.67355 -417.296126)
					(end 393.727432 -417.318444)
				)
				(arc
					(start 393.923012 -417.318444)
					(mid 393.944888 -417.315312)
					(end 393.964922 -417.305998)
				)
				(arc
					(start 394.258546 -417.113466)
					(mid 394.300202 -417.101064)
					(end 394.341858 -417.113466)
				)
				(arc
					(start 394.636752 -417.305998)
					(mid 394.656676 -417.315234)
					(end 394.678408 -417.318444)
				)
				(arc
					(start 394.872972 -417.318444)
					(mid 394.926854 -417.296126)
					(end 394.949172 -417.242244)
				)
				(arc
					(start 394.949172 -416.556444)
					(mid 394.926854 -416.502562)
					(end 394.872972 -416.480244)
				)
				(arc
					(start 394.678408 -416.480244)
					(mid 394.656664 -416.483412)
					(end 394.636752 -416.49269)
				)
				(arc
					(start 394.340588 -416.685476)
					(mid 394.298904 -416.697698)
					(end 394.257276 -416.685222)
				)
				(arc
					(start 393.963652 -416.49269)
					(mid 393.943728 -416.483454)
					(end 393.921996 -416.480244)
				)
				(arc
					(start 393.727432 -416.480244)
					(mid 393.67355 -416.502562)
					(end 393.651232 -416.556444)
				)
			)
		)
	)
	(zone
		(layers "In15.Cu" "In16.Cu")
		(hatch none 0.5)
		(connect_pads
			(clearance 0)
		)
		(min_thickness 0.25)
		(keepout
			(tracks not_allowed)
			(vias allowed)
			(pads allowed)
			(copperpour not_allowed)
			(footprints allowed)
		)
		(placement
			(enabled no)
			(sheetname "")
		)
		(fill yes
			(thermal_gap 0.5)
			(thermal_bridge_width 0.5)
			(island_removal_mode 0)
		)
		(polygon
			(pts
				(arc
					(start 134.587996 -408.860244)
					(mid 134.610314 -408.914126)
					(end 134.664196 -408.936444)
				)
				(arc
					(start 134.859776 -408.936444)
					(mid 134.881652 -408.933312)
					(end 134.901686 -408.923998)
				)
				(arc
					(start 135.19531 -408.731466)
					(mid 135.236966 -408.719064)
					(end 135.278622 -408.731466)
				)
				(arc
					(start 135.573516 -408.923998)
					(mid 135.59344 -408.933234)
					(end 135.615172 -408.936444)
				)
				(arc
					(start 135.809736 -408.936444)
					(mid 135.863618 -408.914126)
					(end 135.885936 -408.860244)
				)
				(arc
					(start 135.885936 -408.174444)
					(mid 135.863618 -408.120562)
					(end 135.809736 -408.098244)
				)
				(arc
					(start 135.615172 -408.098244)
					(mid 135.593428 -408.101412)
					(end 135.573516 -408.11069)
				)
				(arc
					(start 135.277352 -408.303476)
					(mid 135.235668 -408.315698)
					(end 135.19404 -408.303222)
				)
				(arc
					(start 134.900416 -408.11069)
					(mid 134.880492 -408.101454)
					(end 134.85876 -408.098244)
				)
				(arc
					(start 134.664196 -408.098244)
					(mid 134.610314 -408.120562)
					(end 134.587996 -408.174444)
				)
			)
		)
	)
	(zone
		(layers "In15.Cu" "In16.Cu")
		(hatch none 0.5)
		(connect_pads
			(clearance 0)
		)
		(min_thickness 0.25)
		(keepout
			(tracks not_allowed)
			(vias allowed)
			(pads allowed)
			(copperpour not_allowed)
			(footprints allowed)
		)
		(placement
			(enabled no)
			(sheetname "")
		)
		(fill yes
			(thermal_gap 0.5)
			(thermal_bridge_width 0.5)
			(island_removal_mode 0)
		)
		(polygon
			(pts
				(arc
					(start 351.056956 -417.242244)
					(mid 351.079274 -417.296126)
					(end 351.133156 -417.318444)
				)
				(arc
					(start 351.328736 -417.318444)
					(mid 351.350612 -417.315312)
					(end 351.370646 -417.305998)
				)
				(arc
					(start 351.66427 -417.113466)
					(mid 351.705926 -417.101064)
					(end 351.747582 -417.113466)
				)
				(arc
					(start 352.042476 -417.305998)
					(mid 352.0624 -417.315234)
					(end 352.084132 -417.318444)
				)
				(arc
					(start 352.278696 -417.318444)
					(mid 352.332578 -417.296126)
					(end 352.354896 -417.242244)
				)
				(arc
					(start 352.354896 -416.556444)
					(mid 352.332578 -416.502562)
					(end 352.278696 -416.480244)
				)
				(arc
					(start 352.084132 -416.480244)
					(mid 352.062388 -416.483412)
					(end 352.042476 -416.49269)
				)
				(arc
					(start 351.746312 -416.685476)
					(mid 351.704628 -416.697698)
					(end 351.663 -416.685222)
				)
				(arc
					(start 351.369376 -416.49269)
					(mid 351.349452 -416.483454)
					(end 351.32772 -416.480244)
				)
				(arc
					(start 351.133156 -416.480244)
					(mid 351.079274 -416.502562)
					(end 351.056956 -416.556444)
				)
			)
		)
	)
	(zone
		(layers "In15.Cu" "In16.Cu")
		(hatch none 0.5)
		(connect_pads
			(clearance 0)
		)
		(min_thickness 0.25)
		(keepout
			(tracks not_allowed)
			(vias allowed)
			(pads allowed)
			(copperpour not_allowed)
			(footprints allowed)
		)
		(placement
			(enabled no)
			(sheetname "")
		)
		(fill yes
			(thermal_gap 0.5)
			(thermal_bridge_width 0.5)
			(island_removal_mode 0)
		)
		(polygon
			(pts
				(arc
					(start 76.677774 -408.860244)
					(mid 76.700092 -408.914126)
					(end 76.753974 -408.936444)
				)
				(arc
					(start 76.949554 -408.936444)
					(mid 76.97143 -408.933312)
					(end 76.991464 -408.923998)
				)
				(arc
					(start 77.285088 -408.731466)
					(mid 77.326744 -408.719064)
					(end 77.3684 -408.731466)
				)
				(arc
					(start 77.663294 -408.923998)
					(mid 77.683218 -408.933234)
					(end 77.70495 -408.936444)
				)
				(arc
					(start 77.899514 -408.936444)
					(mid 77.953396 -408.914126)
					(end 77.975714 -408.860244)
				)
				(arc
					(start 77.975714 -408.174444)
					(mid 77.953396 -408.120562)
					(end 77.899514 -408.098244)
				)
				(arc
					(start 77.70495 -408.098244)
					(mid 77.683206 -408.101412)
					(end 77.663294 -408.11069)
				)
				(arc
					(start 77.36713 -408.303476)
					(mid 77.325446 -408.315698)
					(end 77.283818 -408.303222)
				)
				(arc
					(start 76.990194 -408.11069)
					(mid 76.97027 -408.101454)
					(end 76.948538 -408.098244)
				)
				(arc
					(start 76.753974 -408.098244)
					(mid 76.700092 -408.120562)
					(end 76.677774 -408.174444)
				)
			)
		)
	)
	(zone
		(layers "In15.Cu" "In16.Cu")
		(hatch none 0.5)
		(connect_pads
			(clearance 0)
		)
		(min_thickness 0.25)
		(keepout
			(tracks not_allowed)
			(vias allowed)
			(pads allowed)
			(copperpour not_allowed)
			(footprints allowed)
		)
		(placement
			(enabled no)
			(sheetname "")
		)
		(fill yes
			(thermal_gap 0.5)
			(thermal_bridge_width 0.5)
			(island_removal_mode 0)
		)
		(polygon
			(pts
				(arc
					(start 372.208552 -417.242244)
					(mid 372.23087 -417.296126)
					(end 372.284752 -417.318444)
				)
				(arc
					(start 372.480332 -417.318444)
					(mid 372.502208 -417.315312)
					(end 372.522242 -417.305998)
				)
				(arc
					(start 372.815866 -417.113466)
					(mid 372.857522 -417.101064)
					(end 372.899178 -417.113466)
				)
				(arc
					(start 373.194072 -417.305998)
					(mid 373.213996 -417.315234)
					(end 373.235728 -417.318444)
				)
				(arc
					(start 373.430292 -417.318444)
					(mid 373.484174 -417.296126)
					(end 373.506492 -417.242244)
				)
				(arc
					(start 373.506492 -416.556444)
					(mid 373.484174 -416.502562)
					(end 373.430292 -416.480244)
				)
				(arc
					(start 373.235728 -416.480244)
					(mid 373.213984 -416.483412)
					(end 373.194072 -416.49269)
				)
				(arc
					(start 372.897908 -416.685476)
					(mid 372.856224 -416.697698)
					(end 372.814596 -416.685222)
				)
				(arc
					(start 372.520972 -416.49269)
					(mid 372.501048 -416.483454)
					(end 372.479316 -416.480244)
				)
				(arc
					(start 372.284752 -416.480244)
					(mid 372.23087 -416.502562)
					(end 372.208552 -416.556444)
				)
			)
		)
	)
	(zone
		(layers "In15.Cu" "In16.Cu")
		(hatch none 0.5)
		(connect_pads
			(clearance 0)
		)
		(min_thickness 0.25)
		(keepout
			(tracks not_allowed)
			(vias allowed)
			(pads allowed)
			(copperpour not_allowed)
			(footprints allowed)
		)
		(placement
			(enabled no)
			(sheetname "")
		)
		(fill yes
			(thermal_gap 0.5)
			(thermal_bridge_width 0.5)
			(island_removal_mode 0)
		)
		(polygon
			(pts
				(arc
					(start 119.271796 -408.860244)
					(mid 119.294114 -408.914126)
					(end 119.347996 -408.936444)
				)
				(arc
					(start 119.543576 -408.936444)
					(mid 119.565452 -408.933312)
					(end 119.585486 -408.923998)
				)
				(arc
					(start 119.87911 -408.731466)
					(mid 119.920766 -408.719064)
					(end 119.962422 -408.731466)
				)
				(arc
					(start 120.257316 -408.923998)
					(mid 120.27724 -408.933234)
					(end 120.298972 -408.936444)
				)
				(arc
					(start 120.493536 -408.936444)
					(mid 120.547418 -408.914126)
					(end 120.569736 -408.860244)
				)
				(arc
					(start 120.569736 -408.174444)
					(mid 120.547418 -408.120562)
					(end 120.493536 -408.098244)
				)
				(arc
					(start 120.298972 -408.098244)
					(mid 120.277228 -408.101412)
					(end 120.257316 -408.11069)
				)
				(arc
					(start 119.961152 -408.303476)
					(mid 119.919468 -408.315698)
					(end 119.87784 -408.303222)
				)
				(arc
					(start 119.584216 -408.11069)
					(mid 119.564292 -408.101454)
					(end 119.54256 -408.098244)
				)
				(arc
					(start 119.347996 -408.098244)
					(mid 119.294114 -408.120562)
					(end 119.271796 -408.174444)
				)
			)
		)
	)
	(zone
		(layers "In15.Cu" "In16.Cu")
		(hatch none 0.5)
		(connect_pads
			(clearance 0)
		)
		(min_thickness 0.25)
		(keepout
			(tracks not_allowed)
			(vias allowed)
			(pads allowed)
			(copperpour not_allowed)
			(footprints allowed)
		)
		(placement
			(enabled no)
			(sheetname "")
		)
		(fill yes
			(thermal_gap 0.5)
			(thermal_bridge_width 0.5)
			(island_removal_mode 0)
		)
		(polygon
			(pts
				(arc
					(start 323.487796 -417.242244)
					(mid 323.510114 -417.296126)
					(end 323.563996 -417.318444)
				)
				(arc
					(start 323.759576 -417.318444)
					(mid 323.781452 -417.315312)
					(end 323.801486 -417.305998)
				)
				(arc
					(start 324.09511 -417.113466)
					(mid 324.136766 -417.101064)
					(end 324.178422 -417.113466)
				)
				(arc
					(start 324.473316 -417.305998)
					(mid 324.49324 -417.315234)
					(end 324.514972 -417.318444)
				)
				(arc
					(start 324.709536 -417.318444)
					(mid 324.763418 -417.296126)
					(end 324.785736 -417.242244)
				)
				(arc
					(start 324.785736 -416.556444)
					(mid 324.763418 -416.502562)
					(end 324.709536 -416.480244)
				)
				(arc
					(start 324.514972 -416.480244)
					(mid 324.493228 -416.483412)
					(end 324.473316 -416.49269)
				)
				(arc
					(start 324.177152 -416.685476)
					(mid 324.135468 -416.697698)
					(end 324.09384 -416.685222)
				)
				(arc
					(start 323.800216 -416.49269)
					(mid 323.780292 -416.483454)
					(end 323.75856 -416.480244)
				)
				(arc
					(start 323.563996 -416.480244)
					(mid 323.510114 -416.502562)
					(end 323.487796 -416.556444)
				)
			)
		)
	)
	(zone
		(layers "In15.Cu" "In16.Cu")
		(hatch none 0.5)
		(connect_pads
			(clearance 0)
		)
		(min_thickness 0.25)
		(keepout
			(tracks not_allowed)
			(vias allowed)
			(pads allowed)
			(copperpour not_allowed)
			(footprints allowed)
		)
		(placement
			(enabled no)
			(sheetname "")
		)
		(fill yes
			(thermal_gap 0.5)
			(thermal_bridge_width 0.5)
			(island_removal_mode 0)
		)
		(polygon
			(pts
				(arc
					(start 52.171854 -408.860244)
					(mid 52.194172 -408.914126)
					(end 52.248054 -408.936444)
				)
				(arc
					(start 52.443634 -408.936444)
					(mid 52.46551 -408.933312)
					(end 52.485544 -408.923998)
				)
				(arc
					(start 52.779168 -408.731466)
					(mid 52.820824 -408.719064)
					(end 52.86248 -408.731466)
				)
				(arc
					(start 53.157374 -408.923998)
					(mid 53.177298 -408.933234)
					(end 53.19903 -408.936444)
				)
				(arc
					(start 53.393594 -408.936444)
					(mid 53.447476 -408.914126)
					(end 53.469794 -408.860244)
				)
				(arc
					(start 53.469794 -408.174444)
					(mid 53.447476 -408.120562)
					(end 53.393594 -408.098244)
				)
				(arc
					(start 53.19903 -408.098244)
					(mid 53.177286 -408.101412)
					(end 53.157374 -408.11069)
				)
				(arc
					(start 52.86121 -408.303476)
					(mid 52.819526 -408.315698)
					(end 52.777898 -408.303222)
				)
				(arc
					(start 52.484274 -408.11069)
					(mid 52.46435 -408.101454)
					(end 52.442618 -408.098244)
				)
				(arc
					(start 52.248054 -408.098244)
					(mid 52.194172 -408.120562)
					(end 52.171854 -408.174444)
				)
			)
		)
	)
	(zone
		(layers "In15.Cu" "In16.Cu")
		(hatch none 0.5)
		(connect_pads
			(clearance 0)
		)
		(min_thickness 0.25)
		(keepout
			(tracks not_allowed)
			(vias allowed)
			(pads allowed)
			(copperpour not_allowed)
			(footprints allowed)
		)
		(placement
			(enabled no)
			(sheetname "")
		)
		(fill yes
			(thermal_gap 0.5)
			(thermal_bridge_width 0.5)
			(island_removal_mode 0)
		)
		(polygon
			(pts
				(arc
					(start 64.424814 -408.860244)
					(mid 64.447132 -408.914126)
					(end 64.501014 -408.936444)
				)
				(arc
					(start 64.696594 -408.936444)
					(mid 64.71847 -408.933312)
					(end 64.738504 -408.923998)
				)
				(arc
					(start 65.032128 -408.731466)
					(mid 65.073784 -408.719064)
					(end 65.11544 -408.731466)
				)
				(arc
					(start 65.410334 -408.923998)
					(mid 65.430258 -408.933234)
					(end 65.45199 -408.936444)
				)
				(arc
					(start 65.646554 -408.936444)
					(mid 65.700436 -408.914126)
					(end 65.722754 -408.860244)
				)
				(arc
					(start 65.722754 -408.174444)
					(mid 65.700436 -408.120562)
					(end 65.646554 -408.098244)
				)
				(arc
					(start 65.45199 -408.098244)
					(mid 65.430246 -408.101412)
					(end 65.410334 -408.11069)
				)
				(arc
					(start 65.11417 -408.303476)
					(mid 65.072486 -408.315698)
					(end 65.030858 -408.303222)
				)
				(arc
					(start 64.737234 -408.11069)
					(mid 64.71731 -408.101454)
					(end 64.695578 -408.098244)
				)
				(arc
					(start 64.501014 -408.098244)
					(mid 64.447132 -408.120562)
					(end 64.424814 -408.174444)
				)
			)
		)
	)
	(zone
		(layers "In15.Cu" "In16.Cu")
		(hatch none 0.5)
		(connect_pads
			(clearance 0)
		)
		(min_thickness 0.25)
		(keepout
			(tracks not_allowed)
			(vias allowed)
			(pads allowed)
			(copperpour not_allowed)
			(footprints allowed)
		)
		(placement
			(enabled no)
			(sheetname "")
		)
		(fill yes
			(thermal_gap 0.5)
			(thermal_bridge_width 0.5)
			(island_removal_mode 0)
		)
		(polygon
			(pts
				(arc
					(start 146.840956 -408.860244)
					(mid 146.863274 -408.914126)
					(end 146.917156 -408.936444)
				)
				(arc
					(start 147.112736 -408.936444)
					(mid 147.134612 -408.933312)
					(end 147.154646 -408.923998)
				)
				(arc
					(start 147.44827 -408.731466)
					(mid 147.489926 -408.719064)
					(end 147.531582 -408.731466)
				)
				(arc
					(start 147.826476 -408.923998)
					(mid 147.8464 -408.933234)
					(end 147.868132 -408.936444)
				)
				(arc
					(start 148.062696 -408.936444)
					(mid 148.116578 -408.914126)
					(end 148.138896 -408.860244)
				)
				(arc
					(start 148.138896 -408.174444)
					(mid 148.116578 -408.120562)
					(end 148.062696 -408.098244)
				)
				(arc
					(start 147.868132 -408.098244)
					(mid 147.846388 -408.101412)
					(end 147.826476 -408.11069)
				)
				(arc
					(start 147.530312 -408.303476)
					(mid 147.488628 -408.315698)
					(end 147.447 -408.303222)
				)
				(arc
					(start 147.153376 -408.11069)
					(mid 147.133452 -408.101454)
					(end 147.11172 -408.098244)
				)
				(arc
					(start 146.917156 -408.098244)
					(mid 146.863274 -408.120562)
					(end 146.840956 -408.174444)
				)
			)
		)
	)
	(zone
		(layers "In15.Cu" "In16.Cu")
		(hatch none 0.5)
		(connect_pads
			(clearance 0)
		)
		(min_thickness 0.25)
		(keepout
			(tracks not_allowed)
			(vias allowed)
			(pads allowed)
			(copperpour not_allowed)
			(footprints allowed)
		)
		(placement
			(enabled no)
			(sheetname "")
		)
		(fill yes
			(thermal_gap 0.5)
			(thermal_bridge_width 0.5)
			(island_removal_mode 0)
		)
		(polygon
			(pts
				(arc
					(start 320.424556 -417.242244)
					(mid 320.446874 -417.296126)
					(end 320.500756 -417.318444)
				)
				(arc
					(start 320.696336 -417.318444)
					(mid 320.718212 -417.315312)
					(end 320.738246 -417.305998)
				)
				(arc
					(start 321.03187 -417.113466)
					(mid 321.073526 -417.101064)
					(end 321.115182 -417.113466)
				)
				(arc
					(start 321.410076 -417.305998)
					(mid 321.43 -417.315234)
					(end 321.451732 -417.318444)
				)
				(arc
					(start 321.646296 -417.318444)
					(mid 321.700178 -417.296126)
					(end 321.722496 -417.242244)
				)
				(arc
					(start 321.722496 -416.556444)
					(mid 321.700178 -416.502562)
					(end 321.646296 -416.480244)
				)
				(arc
					(start 321.451732 -416.480244)
					(mid 321.429988 -416.483412)
					(end 321.410076 -416.49269)
				)
				(arc
					(start 321.113912 -416.685476)
					(mid 321.072228 -416.697698)
					(end 321.0306 -416.685222)
				)
				(arc
					(start 320.736976 -416.49269)
					(mid 320.717052 -416.483454)
					(end 320.69532 -416.480244)
				)
				(arc
					(start 320.500756 -416.480244)
					(mid 320.446874 -416.502562)
					(end 320.424556 -416.556444)
				)
			)
		)
	)
	(zone
		(layers "In15.Cu" "In16.Cu")
		(hatch none 0.5)
		(connect_pads
			(clearance 0)
		)
		(min_thickness 0.25)
		(keepout
			(tracks not_allowed)
			(vias allowed)
			(pads allowed)
			(copperpour not_allowed)
			(footprints allowed)
		)
		(placement
			(enabled no)
			(sheetname "")
		)
		(fill yes
			(thermal_gap 0.5)
			(thermal_bridge_width 0.5)
			(island_removal_mode 0)
		)
		(polygon
			(pts
				(arc
					(start 381.398272 -417.242244)
					(mid 381.42059 -417.296126)
					(end 381.474472 -417.318444)
				)
				(arc
					(start 381.670052 -417.318444)
					(mid 381.691928 -417.315312)
					(end 381.711962 -417.305998)
				)
				(arc
					(start 382.005586 -417.113466)
					(mid 382.047242 -417.101064)
					(end 382.088898 -417.113466)
				)
				(arc
					(start 382.383792 -417.305998)
					(mid 382.403716 -417.315234)
					(end 382.425448 -417.318444)
				)
				(arc
					(start 382.620012 -417.318444)
					(mid 382.673894 -417.296126)
					(end 382.696212 -417.242244)
				)
				(arc
					(start 382.696212 -416.556444)
					(mid 382.673894 -416.502562)
					(end 382.620012 -416.480244)
				)
				(arc
					(start 382.425448 -416.480244)
					(mid 382.403704 -416.483412)
					(end 382.383792 -416.49269)
				)
				(arc
					(start 382.087628 -416.685476)
					(mid 382.045944 -416.697698)
					(end 382.004316 -416.685222)
				)
				(arc
					(start 381.710692 -416.49269)
					(mid 381.690768 -416.483454)
					(end 381.669036 -416.480244)
				)
				(arc
					(start 381.474472 -416.480244)
					(mid 381.42059 -416.502562)
					(end 381.398272 -416.556444)
				)
			)
		)
	)
	(zone
		(layers "In15.Cu" "In16.Cu")
		(hatch none 0.5)
		(connect_pads
			(clearance 0)
		)
		(min_thickness 0.25)
		(keepout
			(tracks not_allowed)
			(vias allowed)
			(pads allowed)
			(copperpour not_allowed)
			(footprints allowed)
		)
		(placement
			(enabled no)
			(sheetname "")
		)
		(fill yes
			(thermal_gap 0.5)
			(thermal_bridge_width 0.5)
			(island_removal_mode 0)
		)
		(polygon
			(pts
				(arc
					(start 347.993716 -417.242244)
					(mid 348.016034 -417.296126)
					(end 348.069916 -417.318444)
				)
				(arc
					(start 348.265496 -417.318444)
					(mid 348.287372 -417.315312)
					(end 348.307406 -417.305998)
				)
				(arc
					(start 348.60103 -417.113466)
					(mid 348.642686 -417.101064)
					(end 348.684342 -417.113466)
				)
				(arc
					(start 348.979236 -417.305998)
					(mid 348.99916 -417.315234)
					(end 349.020892 -417.318444)
				)
				(arc
					(start 349.215456 -417.318444)
					(mid 349.269338 -417.296126)
					(end 349.291656 -417.242244)
				)
				(arc
					(start 349.291656 -416.556444)
					(mid 349.269338 -416.502562)
					(end 349.215456 -416.480244)
				)
				(arc
					(start 349.020892 -416.480244)
					(mid 348.999148 -416.483412)
					(end 348.979236 -416.49269)
				)
				(arc
					(start 348.683072 -416.685476)
					(mid 348.641388 -416.697698)
					(end 348.59976 -416.685222)
				)
				(arc
					(start 348.306136 -416.49269)
					(mid 348.286212 -416.483454)
					(end 348.26448 -416.480244)
				)
				(arc
					(start 348.069916 -416.480244)
					(mid 348.016034 -416.502562)
					(end 347.993716 -416.556444)
				)
			)
		)
	)
	(zone
		(layers "In15.Cu" "In16.Cu")
		(hatch none 0.5)
		(connect_pads
			(clearance 0)
		)
		(min_thickness 0.25)
		(keepout
			(tracks not_allowed)
			(vias allowed)
			(pads allowed)
			(copperpour not_allowed)
			(footprints allowed)
		)
		(placement
			(enabled no)
			(sheetname "")
		)
		(fill yes
			(thermal_gap 0.5)
			(thermal_bridge_width 0.5)
			(island_removal_mode 0)
		)
		(polygon
			(pts
				(arc
					(start 82.804254 -408.860244)
					(mid 82.826572 -408.914126)
					(end 82.880454 -408.936444)
				)
				(arc
					(start 83.076034 -408.936444)
					(mid 83.09791 -408.933312)
					(end 83.117944 -408.923998)
				)
				(arc
					(start 83.411568 -408.731466)
					(mid 83.453224 -408.719064)
					(end 83.49488 -408.731466)
				)
				(arc
					(start 83.789774 -408.923998)
					(mid 83.809698 -408.933234)
					(end 83.83143 -408.936444)
				)
				(arc
					(start 84.025994 -408.936444)
					(mid 84.079876 -408.914126)
					(end 84.102194 -408.860244)
				)
				(arc
					(start 84.102194 -408.174444)
					(mid 84.079876 -408.120562)
					(end 84.025994 -408.098244)
				)
				(arc
					(start 83.83143 -408.098244)
					(mid 83.809686 -408.101412)
					(end 83.789774 -408.11069)
				)
				(arc
					(start 83.49361 -408.303476)
					(mid 83.451926 -408.315698)
					(end 83.410298 -408.303222)
				)
				(arc
					(start 83.116674 -408.11069)
					(mid 83.09675 -408.101454)
					(end 83.075018 -408.098244)
				)
				(arc
					(start 82.880454 -408.098244)
					(mid 82.826572 -408.120562)
					(end 82.804254 -408.174444)
				)
			)
		)
	)
	(zone
		(layers "In15.Cu" "In16.Cu")
		(hatch none 0.5)
		(connect_pads
			(clearance 0)
		)
		(min_thickness 0.25)
		(keepout
			(tracks not_allowed)
			(vias allowed)
			(pads allowed)
			(copperpour not_allowed)
			(footprints allowed)
		)
		(placement
			(enabled no)
			(sheetname "")
		)
		(fill yes
			(thermal_gap 0.5)
			(thermal_bridge_width 0.5)
			(island_removal_mode 0)
		)
		(polygon
			(pts
				(arc
					(start 387.524752 -417.242244)
					(mid 387.54707 -417.296126)
					(end 387.600952 -417.318444)
				)
				(arc
					(start 387.796532 -417.318444)
					(mid 387.818408 -417.315312)
					(end 387.838442 -417.305998)
				)
				(arc
					(start 388.132066 -417.113466)
					(mid 388.173722 -417.101064)
					(end 388.215378 -417.113466)
				)
				(arc
					(start 388.510272 -417.305998)
					(mid 388.530196 -417.315234)
					(end 388.551928 -417.318444)
				)
				(arc
					(start 388.746492 -417.318444)
					(mid 388.800374 -417.296126)
					(end 388.822692 -417.242244)
				)
				(arc
					(start 388.822692 -416.556444)
					(mid 388.800374 -416.502562)
					(end 388.746492 -416.480244)
				)
				(arc
					(start 388.551928 -416.480244)
					(mid 388.530184 -416.483412)
					(end 388.510272 -416.49269)
				)
				(arc
					(start 388.214108 -416.685476)
					(mid 388.172424 -416.697698)
					(end 388.130796 -416.685222)
				)
				(arc
					(start 387.837172 -416.49269)
					(mid 387.817248 -416.483454)
					(end 387.795516 -416.480244)
				)
				(arc
					(start 387.600952 -416.480244)
					(mid 387.54707 -416.502562)
					(end 387.524752 -416.556444)
				)
			)
		)
	)
	(zone
		(layers "In15.Cu" "In16.Cu")
		(hatch none 0.5)
		(connect_pads
			(clearance 0)
		)
		(min_thickness 0.25)
		(keepout
			(tracks not_allowed)
			(vias allowed)
			(pads allowed)
			(copperpour not_allowed)
			(footprints allowed)
		)
		(placement
			(enabled no)
			(sheetname "")
		)
		(fill yes
			(thermal_gap 0.5)
			(thermal_bridge_width 0.5)
			(island_removal_mode 0)
		)
		(polygon
			(pts
				(arc
					(start 317.361316 -417.242244)
					(mid 317.383634 -417.296126)
					(end 317.437516 -417.318444)
				)
				(arc
					(start 317.633096 -417.318444)
					(mid 317.654972 -417.315312)
					(end 317.675006 -417.305998)
				)
				(arc
					(start 317.96863 -417.113466)
					(mid 318.010286 -417.101064)
					(end 318.051942 -417.113466)
				)
				(arc
					(start 318.346836 -417.305998)
					(mid 318.36676 -417.315234)
					(end 318.388492 -417.318444)
				)
				(arc
					(start 318.583056 -417.318444)
					(mid 318.636938 -417.296126)
					(end 318.659256 -417.242244)
				)
				(arc
					(start 318.659256 -416.556444)
					(mid 318.636938 -416.502562)
					(end 318.583056 -416.480244)
				)
				(arc
					(start 318.388492 -416.480244)
					(mid 318.366748 -416.483412)
					(end 318.346836 -416.49269)
				)
				(arc
					(start 318.050672 -416.685476)
					(mid 318.008988 -416.697698)
					(end 317.96736 -416.685222)
				)
				(arc
					(start 317.673736 -416.49269)
					(mid 317.653812 -416.483454)
					(end 317.63208 -416.480244)
				)
				(arc
					(start 317.437516 -416.480244)
					(mid 317.383634 -416.502562)
					(end 317.361316 -416.556444)
				)
			)
		)
	)
	(zone
		(layers "In15.Cu" "In16.Cu")
		(hatch none 0.5)
		(connect_pads
			(clearance 0)
		)
		(min_thickness 0.25)
		(keepout
			(tracks not_allowed)
			(vias allowed)
			(pads allowed)
			(copperpour not_allowed)
			(footprints allowed)
		)
		(placement
			(enabled no)
			(sheetname "")
		)
		(fill yes
			(thermal_gap 0.5)
			(thermal_bridge_width 0.5)
			(island_removal_mode 0)
		)
		(polygon
			(pts
				(arc
					(start 396.714472 -417.242244)
					(mid 396.73679 -417.296126)
					(end 396.790672 -417.318444)
				)
				(arc
					(start 396.986252 -417.318444)
					(mid 397.008128 -417.315312)
					(end 397.028162 -417.305998)
				)
				(arc
					(start 397.321786 -417.113466)
					(mid 397.363442 -417.101064)
					(end 397.405098 -417.113466)
				)
				(arc
					(start 397.699992 -417.305998)
					(mid 397.719916 -417.315234)
					(end 397.741648 -417.318444)
				)
				(arc
					(start 397.936212 -417.318444)
					(mid 397.990094 -417.296126)
					(end 398.012412 -417.242244)
				)
				(arc
					(start 398.012412 -416.556444)
					(mid 397.990094 -416.502562)
					(end 397.936212 -416.480244)
				)
				(arc
					(start 397.741648 -416.480244)
					(mid 397.719904 -416.483412)
					(end 397.699992 -416.49269)
				)
				(arc
					(start 397.403828 -416.685476)
					(mid 397.362144 -416.697698)
					(end 397.320516 -416.685222)
				)
				(arc
					(start 397.026892 -416.49269)
					(mid 397.006968 -416.483454)
					(end 396.985236 -416.480244)
				)
				(arc
					(start 396.790672 -416.480244)
					(mid 396.73679 -416.502562)
					(end 396.714472 -416.556444)
				)
			)
		)
	)
	(zone
		(layers "In15.Cu" "In16.Cu")
		(hatch none 0.5)
		(connect_pads
			(clearance 0)
		)
		(min_thickness 0.25)
		(keepout
			(tracks not_allowed)
			(vias allowed)
			(pads allowed)
			(copperpour not_allowed)
			(footprints allowed)
		)
		(placement
			(enabled no)
			(sheetname "")
		)
		(fill yes
			(thermal_gap 0.5)
			(thermal_bridge_width 0.5)
			(island_removal_mode 0)
		)
		(polygon
			(pts
				(arc
					(start 128.461516 -408.860244)
					(mid 128.483834 -408.914126)
					(end 128.537716 -408.936444)
				)
				(arc
					(start 128.733296 -408.936444)
					(mid 128.755172 -408.933312)
					(end 128.775206 -408.923998)
				)
				(arc
					(start 129.06883 -408.731466)
					(mid 129.110486 -408.719064)
					(end 129.152142 -408.731466)
				)
				(arc
					(start 129.447036 -408.923998)
					(mid 129.46696 -408.933234)
					(end 129.488692 -408.936444)
				)
				(arc
					(start 129.683256 -408.936444)
					(mid 129.737138 -408.914126)
					(end 129.759456 -408.860244)
				)
				(arc
					(start 129.759456 -408.174444)
					(mid 129.737138 -408.120562)
					(end 129.683256 -408.098244)
				)
				(arc
					(start 129.488692 -408.098244)
					(mid 129.466948 -408.101412)
					(end 129.447036 -408.11069)
				)
				(arc
					(start 129.150872 -408.303476)
					(mid 129.109188 -408.315698)
					(end 129.06756 -408.303222)
				)
				(arc
					(start 128.773936 -408.11069)
					(mid 128.754012 -408.101454)
					(end 128.73228 -408.098244)
				)
				(arc
					(start 128.537716 -408.098244)
					(mid 128.483834 -408.120562)
					(end 128.461516 -408.174444)
				)
			)
		)
	)
	(zone
		(layers "In15.Cu" "In16.Cu")
		(hatch none 0.5)
		(connect_pads
			(clearance 0)
		)
		(min_thickness 0.25)
		(keepout
			(tracks not_allowed)
			(vias allowed)
			(pads allowed)
			(copperpour not_allowed)
			(footprints allowed)
		)
		(placement
			(enabled no)
			(sheetname "")
		)
		(fill yes
			(thermal_gap 0.5)
			(thermal_bridge_width 0.5)
			(island_removal_mode 0)
		)
		(polygon
			(pts
				(arc
					(start 116.208556 -408.860244)
					(mid 116.230874 -408.914126)
					(end 116.284756 -408.936444)
				)
				(arc
					(start 116.480336 -408.936444)
					(mid 116.502212 -408.933312)
					(end 116.522246 -408.923998)
				)
				(arc
					(start 116.81587 -408.731466)
					(mid 116.857526 -408.719064)
					(end 116.899182 -408.731466)
				)
				(arc
					(start 117.194076 -408.923998)
					(mid 117.214 -408.933234)
					(end 117.235732 -408.936444)
				)
				(arc
					(start 117.430296 -408.936444)
					(mid 117.484178 -408.914126)
					(end 117.506496 -408.860244)
				)
				(arc
					(start 117.506496 -408.174444)
					(mid 117.484178 -408.120562)
					(end 117.430296 -408.098244)
				)
				(arc
					(start 117.235732 -408.098244)
					(mid 117.213988 -408.101412)
					(end 117.194076 -408.11069)
				)
				(arc
					(start 116.897912 -408.303476)
					(mid 116.856228 -408.315698)
					(end 116.8146 -408.303222)
				)
				(arc
					(start 116.520976 -408.11069)
					(mid 116.501052 -408.101454)
					(end 116.47932 -408.098244)
				)
				(arc
					(start 116.284756 -408.098244)
					(mid 116.230874 -408.120562)
					(end 116.208556 -408.174444)
				)
			)
		)
	)
	(zone
		(layer "In16.Cu")
		(hatch none 0.5)
		(connect_pads
			(clearance 0)
		)
		(min_thickness 0.25)
		(keepout
			(tracks not_allowed)
			(vias allowed)
			(pads allowed)
			(copperpour not_allowed)
			(footprints allowed)
		)
		(placement
			(enabled no)
			(sheetname "")
		)
		(fill
			(thermal_gap 0.5)
			(thermal_bridge_width 0.5)
			(island_removal_mode 0)
		)
		(polygon
			(pts
				(arc
					(start 314.141612 -438.760616)
					(mid 314.16393 -438.814498)
					(end 314.217812 -438.836816)
				)
				(arc
					(start 315.157612 -438.836816)
					(mid 315.211494 -438.814498)
					(end 315.233812 -438.760616)
				)
				(arc
					(start 315.233812 -436.219092)
					(mid 315.211494 -436.16521)
					(end 315.157612 -436.142892)
				)
				(arc
					(start 314.217812 -436.142892)
					(mid 314.16393 -436.16521)
					(end 314.141612 -436.219092)
				)
				(arc
					(start 314.141612 -436.946548)
					(mid 314.143611 -436.963889)
					(end 314.149486 -436.98033)
				)
				(arc
					(start 314.382912 -437.45658)
					(mid 314.390695 -437.490108)
					(end 314.382912 -437.523636)
				)
				(arc
					(start 314.149486 -437.999886)
					(mid 314.143591 -438.016322)
					(end 314.141612 -438.033668)
				)
			)
		)
	)
	(zone
		(layer "In16.Cu")
		(hatch none 0.5)
		(connect_pads
			(clearance 0)
		)
		(min_thickness 0.25)
		(keepout
			(tracks not_allowed)
			(vias allowed)
			(pads allowed)
			(copperpour not_allowed)
			(footprints allowed)
		)
		(placement
			(enabled no)
			(sheetname "")
		)
		(fill
			(thermal_gap 0.5)
			(thermal_bridge_width 0.5)
			(island_removal_mode 0)
		)
		(polygon
			(pts
				(arc
					(start 142.242032 -438.760616)
					(mid 142.26435 -438.814498)
					(end 142.318232 -438.836816)
				)
				(arc
					(start 143.258032 -438.836816)
					(mid 143.311914 -438.814498)
					(end 143.334232 -438.760616)
				)
				(arc
					(start 143.334232 -436.219092)
					(mid 143.311914 -436.16521)
					(end 143.258032 -436.142892)
				)
				(arc
					(start 142.318232 -436.142892)
					(mid 142.26435 -436.16521)
					(end 142.242032 -436.219092)
				)
				(arc
					(start 142.242032 -436.946548)
					(mid 142.244031 -436.963889)
					(end 142.249906 -436.98033)
				)
				(arc
					(start 142.483332 -437.45658)
					(mid 142.491115 -437.490108)
					(end 142.483332 -437.523636)
				)
				(arc
					(start 142.249906 -437.999886)
					(mid 142.244011 -438.016322)
					(end 142.242032 -438.033668)
				)
			)
		)
	)
	(zone
		(layer "In16.Cu")
		(hatch none 0.5)
		(connect_pads
			(clearance 0)
		)
		(min_thickness 0.25)
		(keepout
			(tracks not_allowed)
			(vias allowed)
			(pads allowed)
			(copperpour not_allowed)
			(footprints allowed)
		)
		(placement
			(enabled no)
			(sheetname "")
		)
		(fill
			(thermal_gap 0.5)
			(thermal_bridge_width 0.5)
			(island_removal_mode 0)
		)
		(polygon
			(pts
				(arc
					(start 185.513726 2.972054)
					(mid 185.491408 2.918172)
					(end 185.437526 2.895854)
				)
				(arc
					(start 184.825386 2.895854)
					(mid 184.771504 2.918172)
					(end 184.749186 2.972054)
				)
				(arc
					(start 184.749186 4.069334)
					(mid 184.771504 4.123216)
					(end 184.825386 4.145534)
				)
				(arc
					(start 185.437526 4.145534)
					(mid 185.491408 4.123216)
					(end 185.513726 4.069334)
				)
			)
		)
	)
	(zone
		(layer "In16.Cu")
		(hatch none 0.5)
		(connect_pads
			(clearance 0)
		)
		(min_thickness 0.25)
		(keepout
			(tracks not_allowed)
			(vias allowed)
			(pads allowed)
			(copperpour not_allowed)
			(footprints allowed)
		)
		(placement
			(enabled no)
			(sheetname "")
		)
		(fill
			(thermal_gap 0.5)
			(thermal_bridge_width 0.5)
			(island_removal_mode 0)
		)
		(polygon
			(pts
				(arc
					(start 212.820504 8.173974)
					(mid 212.842822 8.227856)
					(end 212.896704 8.250174)
				)
				(arc
					(start 213.508844 8.250174)
					(mid 213.562726 8.227856)
					(end 213.585044 8.173974)
				)
				(arc
					(start 213.585044 7.076694)
					(mid 213.562726 7.022812)
					(end 213.508844 7.000494)
				)
				(arc
					(start 212.896704 7.000494)
					(mid 212.842822 7.022812)
					(end 212.820504 7.076694)
				)
			)
		)
	)
	(zone
		(layer "In16.Cu")
		(hatch none 0.5)
		(connect_pads
			(clearance 0)
		)
		(min_thickness 0.25)
		(keepout
			(tracks not_allowed)
			(vias allowed)
			(pads allowed)
			(copperpour not_allowed)
			(footprints allowed)
		)
		(placement
			(enabled no)
			(sheetname "")
		)
		(fill
			(thermal_gap 0.5)
			(thermal_bridge_width 0.5)
			(island_removal_mode 0)
		)
		(polygon
			(pts
				(arc
					(start 320.1416 -439.760614)
					(mid 320.163918 -439.814496)
					(end 320.2178 -439.836814)
				)
				(arc
					(start 321.1576 -439.836814)
					(mid 321.211482 -439.814496)
					(end 321.2338 -439.760614)
				)
				(arc
					(start 321.2338 -437.21909)
					(mid 321.211482 -437.165208)
					(end 321.1576 -437.14289)
				)
				(arc
					(start 320.2178 -437.14289)
					(mid 320.163918 -437.165208)
					(end 320.1416 -437.21909)
				)
				(arc
					(start 320.1416 -437.946546)
					(mid 320.143599 -437.963887)
					(end 320.149474 -437.980328)
				)
				(arc
					(start 320.3829 -438.456578)
					(mid 320.390683 -438.490106)
					(end 320.3829 -438.523634)
				)
				(arc
					(start 320.149474 -438.999884)
					(mid 320.143579 -439.01632)
					(end 320.1416 -439.033666)
				)
			)
		)
	)
	(zone
		(layer "In16.Cu")
		(hatch none 0.5)
		(connect_pads
			(clearance 0)
		)
		(min_thickness 0.25)
		(keepout
			(tracks not_allowed)
			(vias allowed)
			(pads allowed)
			(copperpour not_allowed)
			(footprints allowed)
		)
		(placement
			(enabled no)
			(sheetname "")
		)
		(fill
			(thermal_gap 0.5)
			(thermal_bridge_width 0.5)
			(island_removal_mode 0)
		)
		(polygon
			(pts
				(arc
					(start 318.141604 -438.760616)
					(mid 318.163922 -438.814498)
					(end 318.217804 -438.836816)
				)
				(arc
					(start 319.157604 -438.836816)
					(mid 319.211486 -438.814498)
					(end 319.233804 -438.760616)
				)
				(arc
					(start 319.233804 -436.219092)
					(mid 319.211486 -436.16521)
					(end 319.157604 -436.142892)
				)
				(arc
					(start 318.217804 -436.142892)
					(mid 318.163922 -436.16521)
					(end 318.141604 -436.219092)
				)
				(arc
					(start 318.141604 -436.946548)
					(mid 318.143603 -436.963889)
					(end 318.149478 -436.98033)
				)
				(arc
					(start 318.382904 -437.45658)
					(mid 318.390687 -437.490108)
					(end 318.382904 -437.523636)
				)
				(arc
					(start 318.149478 -437.999886)
					(mid 318.143583 -438.016322)
					(end 318.141604 -438.033668)
				)
			)
		)
	)
	(zone
		(layer "In16.Cu")
		(hatch none 0.5)
		(connect_pads
			(clearance 0)
		)
		(min_thickness 0.25)
		(keepout
			(tracks not_allowed)
			(vias allowed)
			(pads allowed)
			(copperpour not_allowed)
			(footprints allowed)
		)
		(placement
			(enabled no)
			(sheetname "")
		)
		(fill
			(thermal_gap 0.5)
			(thermal_bridge_width 0.5)
			(island_removal_mode 0)
		)
		(polygon
			(pts
				(arc
					(start 322.141596 -438.760616)
					(mid 322.163914 -438.814498)
					(end 322.217796 -438.836816)
				)
				(arc
					(start 323.157596 -438.836816)
					(mid 323.211478 -438.814498)
					(end 323.233796 -438.760616)
				)
				(arc
					(start 323.233796 -436.219092)
					(mid 323.211478 -436.16521)
					(end 323.157596 -436.142892)
				)
				(arc
					(start 322.217796 -436.142892)
					(mid 322.163914 -436.16521)
					(end 322.141596 -436.219092)
				)
				(arc
					(start 322.141596 -436.946548)
					(mid 322.143595 -436.963889)
					(end 322.14947 -436.98033)
				)
				(arc
					(start 322.382896 -437.45658)
					(mid 322.390679 -437.490108)
					(end 322.382896 -437.523636)
				)
				(arc
					(start 322.14947 -437.999886)
					(mid 322.143575 -438.016322)
					(end 322.141596 -438.033668)
				)
			)
		)
	)
	(zone
		(layer "In16.Cu")
		(hatch none 0.5)
		(connect_pads
			(clearance 0)
		)
		(min_thickness 0.25)
		(keepout
			(tracks not_allowed)
			(vias allowed)
			(pads allowed)
			(copperpour not_allowed)
			(footprints allowed)
		)
		(placement
			(enabled no)
			(sheetname "")
		)
		(fill
			(thermal_gap 0.5)
			(thermal_bridge_width 0.5)
			(island_removal_mode 0)
		)
		(polygon
			(pts
				(arc
					(start 89.142062 -439.760614)
					(mid 89.16438 -439.814496)
					(end 89.218262 -439.836814)
				)
				(arc
					(start 90.158062 -439.836814)
					(mid 90.211944 -439.814496)
					(end 90.234262 -439.760614)
				)
				(arc
					(start 90.234262 -437.21909)
					(mid 90.211944 -437.165208)
					(end 90.158062 -437.14289)
				)
				(arc
					(start 89.218262 -437.14289)
					(mid 89.16438 -437.165208)
					(end 89.142062 -437.21909)
				)
				(arc
					(start 89.142062 -437.946546)
					(mid 89.144061 -437.963887)
					(end 89.149936 -437.980328)
				)
				(arc
					(start 89.383362 -438.456578)
					(mid 89.391145 -438.490106)
					(end 89.383362 -438.523634)
				)
				(arc
					(start 89.149936 -438.999884)
					(mid 89.144041 -439.01632)
					(end 89.142062 -439.033666)
				)
			)
		)
	)
	(zone
		(layer "In16.Cu")
		(hatch none 0.5)
		(connect_pads
			(clearance 0)
		)
		(min_thickness 0.25)
		(keepout
			(tracks not_allowed)
			(vias allowed)
			(pads allowed)
			(copperpour not_allowed)
			(footprints allowed)
		)
		(placement
			(enabled no)
			(sheetname "")
		)
		(fill
			(thermal_gap 0.5)
			(thermal_bridge_width 0.5)
			(island_removal_mode 0)
		)
		(polygon
			(pts
				(arc
					(start 154.242008 -438.760616)
					(mid 154.264326 -438.814498)
					(end 154.318208 -438.836816)
				)
				(arc
					(start 155.258008 -438.836816)
					(mid 155.31189 -438.814498)
					(end 155.334208 -438.760616)
				)
				(arc
					(start 155.334208 -436.219092)
					(mid 155.31189 -436.16521)
					(end 155.258008 -436.142892)
				)
				(arc
					(start 154.318208 -436.142892)
					(mid 154.264326 -436.16521)
					(end 154.242008 -436.219092)
				)
				(arc
					(start 154.242008 -436.946548)
					(mid 154.244007 -436.963889)
					(end 154.249882 -436.98033)
				)
				(arc
					(start 154.483308 -437.45658)
					(mid 154.491091 -437.490108)
					(end 154.483308 -437.523636)
				)
				(arc
					(start 154.249882 -437.999886)
					(mid 154.243987 -438.016322)
					(end 154.242008 -438.033668)
				)
			)
		)
	)
	(zone
		(layer "In16.Cu")
		(hatch none 0.5)
		(connect_pads
			(clearance 0)
		)
		(min_thickness 0.25)
		(keepout
			(tracks not_allowed)
			(vias allowed)
			(pads allowed)
			(copperpour not_allowed)
			(footprints allowed)
		)
		(placement
			(enabled no)
			(sheetname "")
		)
		(fill
			(thermal_gap 0.5)
			(thermal_bridge_width 0.5)
			(island_removal_mode 0)
		)
		(polygon
			(pts
				(arc
					(start 387.241796 -439.760614)
					(mid 387.264114 -439.814496)
					(end 387.317996 -439.836814)
				)
				(arc
					(start 388.257796 -439.836814)
					(mid 388.311678 -439.814496)
					(end 388.333996 -439.760614)
				)
				(arc
					(start 388.333996 -437.21909)
					(mid 388.311678 -437.165208)
					(end 388.257796 -437.14289)
				)
				(arc
					(start 387.317996 -437.14289)
					(mid 387.264114 -437.165208)
					(end 387.241796 -437.21909)
				)
				(arc
					(start 387.241796 -437.946546)
					(mid 387.243795 -437.963887)
					(end 387.24967 -437.980328)
				)
				(arc
					(start 387.483096 -438.456578)
					(mid 387.490879 -438.490106)
					(end 387.483096 -438.523634)
				)
				(arc
					(start 387.24967 -438.999884)
					(mid 387.243775 -439.01632)
					(end 387.241796 -439.033666)
				)
			)
		)
	)
	(zone
		(layer "In16.Cu")
		(hatch none 0.5)
		(connect_pads
			(clearance 0)
		)
		(min_thickness 0.25)
		(keepout
			(tracks not_allowed)
			(vias allowed)
			(pads allowed)
			(copperpour not_allowed)
			(footprints allowed)
		)
		(placement
			(enabled no)
			(sheetname "")
		)
		(fill
			(thermal_gap 0.5)
			(thermal_bridge_width 0.5)
			(island_removal_mode 0)
		)
		(polygon
			(pts
				(arc
					(start 150.242016 -438.760616)
					(mid 150.264334 -438.814498)
					(end 150.318216 -438.836816)
				)
				(arc
					(start 151.258016 -438.836816)
					(mid 151.311898 -438.814498)
					(end 151.334216 -438.760616)
				)
				(arc
					(start 151.334216 -436.219092)
					(mid 151.311898 -436.16521)
					(end 151.258016 -436.142892)
				)
				(arc
					(start 150.318216 -436.142892)
					(mid 150.264334 -436.16521)
					(end 150.242016 -436.219092)
				)
				(arc
					(start 150.242016 -436.946548)
					(mid 150.244015 -436.963889)
					(end 150.24989 -436.98033)
				)
				(arc
					(start 150.483316 -437.45658)
					(mid 150.491099 -437.490108)
					(end 150.483316 -437.523636)
				)
				(arc
					(start 150.24989 -437.999886)
					(mid 150.243995 -438.016322)
					(end 150.242016 -438.033668)
				)
			)
		)
	)
	(zone
		(layer "In16.Cu")
		(hatch none 0.5)
		(connect_pads
			(clearance 0)
		)
		(min_thickness 0.25)
		(keepout
			(tracks not_allowed)
			(vias allowed)
			(pads allowed)
			(copperpour not_allowed)
			(footprints allowed)
		)
		(placement
			(enabled no)
			(sheetname "")
		)
		(fill
			(thermal_gap 0.5)
			(thermal_bridge_width 0.5)
			(island_removal_mode 0)
		)
		(polygon
			(pts
				(arc
					(start 87.142066 -438.760616)
					(mid 87.164384 -438.814498)
					(end 87.218266 -438.836816)
				)
				(arc
					(start 88.158066 -438.836816)
					(mid 88.211948 -438.814498)
					(end 88.234266 -438.760616)
				)
				(arc
					(start 88.234266 -436.219092)
					(mid 88.211948 -436.16521)
					(end 88.158066 -436.142892)
				)
				(arc
					(start 87.218266 -436.142892)
					(mid 87.164384 -436.16521)
					(end 87.142066 -436.219092)
				)
				(arc
					(start 87.142066 -436.946548)
					(mid 87.144065 -436.963889)
					(end 87.14994 -436.98033)
				)
				(arc
					(start 87.383366 -437.45658)
					(mid 87.391149 -437.490108)
					(end 87.383366 -437.523636)
				)
				(arc
					(start 87.14994 -437.999886)
					(mid 87.144045 -438.016322)
					(end 87.142066 -438.033668)
				)
			)
		)
	)
	(zone
		(layer "In16.Cu")
		(hatch none 0.5)
		(connect_pads
			(clearance 0)
		)
		(min_thickness 0.25)
		(keepout
			(tracks not_allowed)
			(vias allowed)
			(pads allowed)
			(copperpour not_allowed)
			(footprints allowed)
		)
		(placement
			(enabled no)
			(sheetname "")
		)
		(fill
			(thermal_gap 0.5)
			(thermal_bridge_width 0.5)
			(island_removal_mode 0)
		)
		(polygon
			(pts
				(arc
					(start 300.189392 7.071614)
					(mid 300.167074 7.017732)
					(end 300.113192 6.995414)
				)
				(arc
					(start 299.501052 6.995414)
					(mid 299.44717 7.017732)
					(end 299.424852 7.071614)
				)
				(arc
					(start 299.424852 8.168894)
					(mid 299.44717 8.222776)
					(end 299.501052 8.245094)
				)
				(arc
					(start 300.113192 8.245094)
					(mid 300.167074 8.222776)
					(end 300.189392 8.168894)
				)
			)
		)
	)
	(zone
		(layer "In16.Cu")
		(hatch none 0.5)
		(connect_pads
			(clearance 0)
		)
		(min_thickness 0.25)
		(keepout
			(tracks not_allowed)
			(vias allowed)
			(pads allowed)
			(copperpour not_allowed)
			(footprints allowed)
		)
		(placement
			(enabled no)
			(sheetname "")
		)
		(fill
			(thermal_gap 0.5)
			(thermal_bridge_width 0.5)
			(island_removal_mode 0)
		)
		(polygon
			(pts
				(arc
					(start 12.187682 -112.663732)
					(mid 12.202561 -112.627811)
					(end 12.238482 -112.612932)
				)
				(arc
					(start 12.314682 -112.612932)
					(mid 12.350603 -112.627811)
					(end 12.365482 -112.663732)
				)
				(arc
					(start 12.365482 -113.374932)
					(mid 12.350603 -113.410853)
					(end 12.314682 -113.425732)
				)
				(arc
					(start 12.238482 -113.425732)
					(mid 12.202561 -113.410853)
					(end 12.187682 -113.374932)
				)
			)
		)
	)
	(zone
		(layer "In16.Cu")
		(hatch none 0.5)
		(connect_pads
			(clearance 0)
		)
		(min_thickness 0.25)
		(keepout
			(tracks not_allowed)
			(vias allowed)
			(pads allowed)
			(copperpour not_allowed)
			(footprints allowed)
		)
		(placement
			(enabled no)
			(sheetname "")
		)
		(fill
			(thermal_gap 0.5)
			(thermal_bridge_width 0.5)
			(island_removal_mode 0)
		)
		(polygon
			(pts
				(arc
					(start 365.939578 1.991614)
					(mid 365.91726 1.937732)
					(end 365.863378 1.915414)
				)
				(arc
					(start 365.251238 1.915414)
					(mid 365.197356 1.937732)
					(end 365.175038 1.991614)
				)
				(arc
					(start 365.175038 3.088894)
					(mid 365.197356 3.142776)
					(end 365.251238 3.165094)
				)
				(arc
					(start 365.863378 3.165094)
					(mid 365.91726 3.142776)
					(end 365.939578 3.088894)
				)
			)
		)
	)
	(zone
		(layer "In16.Cu")
		(hatch none 0.5)
		(connect_pads
			(clearance 0)
		)
		(min_thickness 0.25)
		(keepout
			(tracks not_allowed)
			(vias allowed)
			(pads allowed)
			(copperpour not_allowed)
			(footprints allowed)
		)
		(placement
			(enabled no)
			(sheetname "")
		)
		(fill
			(thermal_gap 0.5)
			(thermal_bridge_width 0.5)
			(island_removal_mode 0)
		)
		(polygon
			(pts
				(arc
					(start 50.007774 -419.46957)
					(mid 50.030092 -419.415688)
					(end 50.083974 -419.39337)
				)
				(arc
					(start 51.353212 -419.39337)
					(mid 51.407094 -419.415688)
					(end 51.429412 -419.46957)
				)
				(arc
					(start 51.429412 -419.979602)
					(mid 51.407094 -420.033484)
					(end 51.353212 -420.055802)
				)
				(arc
					(start 50.083974 -420.055802)
					(mid 50.030092 -420.033484)
					(end 50.007774 -419.979602)
				)
			)
		)
	)
	(zone
		(layer "In16.Cu")
		(hatch none 0.5)
		(connect_pads
			(clearance 0)
		)
		(min_thickness 0.25)
		(keepout
			(tracks not_allowed)
			(vias allowed)
			(pads allowed)
			(copperpour not_allowed)
			(footprints allowed)
		)
		(placement
			(enabled no)
			(sheetname "")
		)
		(fill
			(thermal_gap 0.5)
			(thermal_bridge_width 0.5)
			(island_removal_mode 0)
		)
		(polygon
			(pts
				(arc
					(start 316.141608 -439.760614)
					(mid 316.163926 -439.814496)
					(end 316.217808 -439.836814)
				)
				(arc
					(start 317.157608 -439.836814)
					(mid 317.21149 -439.814496)
					(end 317.233808 -439.760614)
				)
				(arc
					(start 317.233808 -437.21909)
					(mid 317.21149 -437.165208)
					(end 317.157608 -437.14289)
				)
				(arc
					(start 316.217808 -437.14289)
					(mid 316.163926 -437.165208)
					(end 316.141608 -437.21909)
				)
				(arc
					(start 316.141608 -437.946546)
					(mid 316.143607 -437.963887)
					(end 316.149482 -437.980328)
				)
				(arc
					(start 316.382908 -438.456578)
					(mid 316.390691 -438.490106)
					(end 316.382908 -438.523634)
				)
				(arc
					(start 316.149482 -438.999884)
					(mid 316.143587 -439.01632)
					(end 316.141608 -439.033666)
				)
			)
		)
	)
	(zone
		(layer "In16.Cu")
		(hatch none 0.5)
		(connect_pads
			(clearance 0)
		)
		(min_thickness 0.25)
		(keepout
			(tracks not_allowed)
			(vias allowed)
			(pads allowed)
			(copperpour not_allowed)
			(footprints allowed)
		)
		(placement
			(enabled no)
			(sheetname "")
		)
		(fill
			(thermal_gap 0.5)
			(thermal_bridge_width 0.5)
			(island_removal_mode 0)
		)
		(polygon
			(pts
				(arc
					(start 389.241792 -438.760616)
					(mid 389.26411 -438.814498)
					(end 389.317992 -438.836816)
				)
				(arc
					(start 390.257792 -438.836816)
					(mid 390.311674 -438.814498)
					(end 390.333992 -438.760616)
				)
				(arc
					(start 390.333992 -436.219092)
					(mid 390.311674 -436.16521)
					(end 390.257792 -436.142892)
				)
				(arc
					(start 389.317992 -436.142892)
					(mid 389.26411 -436.16521)
					(end 389.241792 -436.219092)
				)
				(arc
					(start 389.241792 -436.946548)
					(mid 389.243791 -436.963889)
					(end 389.249666 -436.98033)
				)
				(arc
					(start 389.483092 -437.45658)
					(mid 389.490875 -437.490108)
					(end 389.483092 -437.523636)
				)
				(arc
					(start 389.249666 -437.999886)
					(mid 389.243771 -438.016322)
					(end 389.241792 -438.033668)
				)
			)
		)
	)
	(zone
		(layer "In16.Cu")
		(hatch none 0.5)
		(connect_pads
			(clearance 0)
		)
		(min_thickness 0.25)
		(keepout
			(tracks not_allowed)
			(vias allowed)
			(pads allowed)
			(copperpour not_allowed)
			(footprints allowed)
		)
		(placement
			(enabled no)
			(sheetname "")
		)
		(fill
			(thermal_gap 0.5)
			(thermal_bridge_width 0.5)
			(island_removal_mode 0)
		)
		(polygon
			(pts
				(arc
					(start 326.141588 -438.760616)
					(mid 326.163906 -438.814498)
					(end 326.217788 -438.836816)
				)
				(arc
					(start 327.157588 -438.836816)
					(mid 327.21147 -438.814498)
					(end 327.233788 -438.760616)
				)
				(arc
					(start 327.233788 -436.219092)
					(mid 327.21147 -436.16521)
					(end 327.157588 -436.142892)
				)
				(arc
					(start 326.217788 -436.142892)
					(mid 326.163906 -436.16521)
					(end 326.141588 -436.219092)
				)
				(arc
					(start 326.141588 -436.946548)
					(mid 326.143587 -436.963889)
					(end 326.149462 -436.98033)
				)
				(arc
					(start 326.382888 -437.45658)
					(mid 326.390671 -437.490108)
					(end 326.382888 -437.523636)
				)
				(arc
					(start 326.149462 -437.999886)
					(mid 326.143567 -438.016322)
					(end 326.141588 -438.033668)
				)
			)
		)
	)
	(zone
		(layer "In16.Cu")
		(hatch none 0.5)
		(connect_pads
			(clearance 0)
		)
		(min_thickness 0.25)
		(keepout
			(tracks not_allowed)
			(vias allowed)
			(pads allowed)
			(copperpour not_allowed)
			(footprints allowed)
		)
		(placement
			(enabled no)
			(sheetname "")
		)
		(fill
			(thermal_gap 0.5)
			(thermal_bridge_width 0.5)
			(island_removal_mode 0)
		)
		(polygon
			(pts
				(arc
					(start 146.242024 -438.760616)
					(mid 146.264342 -438.814498)
					(end 146.318224 -438.836816)
				)
				(arc
					(start 147.258024 -438.836816)
					(mid 147.311906 -438.814498)
					(end 147.334224 -438.760616)
				)
				(arc
					(start 147.334224 -436.219092)
					(mid 147.311906 -436.16521)
					(end 147.258024 -436.142892)
				)
				(arc
					(start 146.318224 -436.142892)
					(mid 146.264342 -436.16521)
					(end 146.242024 -436.219092)
				)
				(arc
					(start 146.242024 -436.946548)
					(mid 146.244023 -436.963889)
					(end 146.249898 -436.98033)
				)
				(arc
					(start 146.483324 -437.45658)
					(mid 146.491107 -437.490108)
					(end 146.483324 -437.523636)
				)
				(arc
					(start 146.249898 -437.999886)
					(mid 146.244003 -438.016322)
					(end 146.242024 -438.033668)
				)
			)
		)
	)
	(zone
		(layer "In16.Cu")
		(hatch none 0.5)
		(connect_pads
			(clearance 0)
		)
		(min_thickness 0.25)
		(keepout
			(tracks not_allowed)
			(vias allowed)
			(pads allowed)
			(copperpour not_allowed)
			(footprints allowed)
		)
		(placement
			(enabled no)
			(sheetname "")
		)
		(fill
			(thermal_gap 0.5)
			(thermal_bridge_width 0.5)
			(island_removal_mode 0)
		)
		(polygon
			(pts
				(arc
					(start 11.787886 -111.263684)
					(mid 11.802765 -111.227763)
					(end 11.838686 -111.212884)
				)
				(arc
					(start 11.914886 -111.212884)
					(mid 11.950807 -111.227763)
					(end 11.965686 -111.263684)
				)
				(arc
					(start 11.965686 -111.974884)
					(mid 11.950807 -112.010805)
					(end 11.914886 -112.025684)
				)
				(arc
					(start 11.838686 -112.025684)
					(mid 11.802765 -112.010805)
					(end 11.787886 -111.974884)
				)
			)
		)
	)
	(zone
		(layer "In16.Cu")
		(hatch none 0.5)
		(connect_pads
			(clearance 0)
		)
		(min_thickness 0.25)
		(keepout
			(tracks not_allowed)
			(vias allowed)
			(pads allowed)
			(copperpour not_allowed)
			(footprints allowed)
		)
		(placement
			(enabled no)
			(sheetname "")
		)
		(fill
			(thermal_gap 0.5)
			(thermal_bridge_width 0.5)
			(island_removal_mode 0)
		)
		(polygon
			(pts
				(arc
					(start 85.14207 -439.760614)
					(mid 85.164388 -439.814496)
					(end 85.21827 -439.836814)
				)
				(arc
					(start 86.15807 -439.836814)
					(mid 86.211952 -439.814496)
					(end 86.23427 -439.760614)
				)
				(arc
					(start 86.23427 -437.21909)
					(mid 86.211952 -437.165208)
					(end 86.15807 -437.14289)
				)
				(arc
					(start 85.21827 -437.14289)
					(mid 85.164388 -437.165208)
					(end 85.14207 -437.21909)
				)
				(arc
					(start 85.14207 -437.946546)
					(mid 85.144069 -437.963887)
					(end 85.149944 -437.980328)
				)
				(arc
					(start 85.38337 -438.456578)
					(mid 85.391153 -438.490106)
					(end 85.38337 -438.523634)
				)
				(arc
					(start 85.149944 -438.999884)
					(mid 85.144049 -439.01632)
					(end 85.14207 -439.033666)
				)
			)
		)
	)
	(zone
		(layer "In16.Cu")
		(hatch none 0.5)
		(connect_pads
			(clearance 0)
		)
		(min_thickness 0.25)
		(keepout
			(tracks not_allowed)
			(vias allowed)
			(pads allowed)
			(copperpour not_allowed)
			(footprints allowed)
		)
		(placement
			(enabled no)
			(sheetname "")
		)
		(fill
			(thermal_gap 0.5)
			(thermal_bridge_width 0.5)
			(island_removal_mode 0)
		)
		(polygon
			(pts
				(arc
					(start 75.14209 -438.760616)
					(mid 75.164408 -438.814498)
					(end 75.21829 -438.836816)
				)
				(arc
					(start 76.15809 -438.836816)
					(mid 76.211972 -438.814498)
					(end 76.23429 -438.760616)
				)
				(arc
					(start 76.23429 -436.219092)
					(mid 76.211972 -436.16521)
					(end 76.15809 -436.142892)
				)
				(arc
					(start 75.21829 -436.142892)
					(mid 75.164408 -436.16521)
					(end 75.14209 -436.219092)
				)
				(arc
					(start 75.14209 -436.946548)
					(mid 75.144089 -436.963889)
					(end 75.149964 -436.98033)
				)
				(arc
					(start 75.38339 -437.45658)
					(mid 75.391173 -437.490108)
					(end 75.38339 -437.523636)
				)
				(arc
					(start 75.149964 -437.999886)
					(mid 75.144069 -438.016322)
					(end 75.14209 -438.033668)
				)
			)
		)
	)
	(zone
		(layer "In16.Cu")
		(hatch none 0.5)
		(connect_pads
			(clearance 0)
		)
		(min_thickness 0.25)
		(keepout
			(tracks not_allowed)
			(vias allowed)
			(pads allowed)
			(copperpour not_allowed)
			(footprints allowed)
		)
		(placement
			(enabled no)
			(sheetname "")
		)
		(fill
			(thermal_gap 0.5)
			(thermal_bridge_width 0.5)
			(island_removal_mode 0)
		)
		(polygon
			(pts
				(arc
					(start 50.007774 -418.45357)
					(mid 50.030092 -418.399688)
					(end 50.083974 -418.37737)
				)
				(arc
					(start 51.353212 -418.37737)
					(mid 51.407094 -418.399688)
					(end 51.429412 -418.45357)
				)
				(arc
					(start 51.429412 -418.963602)
					(mid 51.407094 -419.017484)
					(end 51.353212 -419.039802)
				)
				(arc
					(start 50.083974 -419.039802)
					(mid 50.030092 -419.017484)
					(end 50.007774 -418.963602)
				)
			)
		)
	)
	(zone
		(layer "In16.Cu")
		(hatch none 0.5)
		(connect_pads
			(clearance 0)
		)
		(min_thickness 0.25)
		(keepout
			(tracks not_allowed)
			(vias allowed)
			(pads allowed)
			(copperpour not_allowed)
			(footprints allowed)
		)
		(placement
			(enabled no)
			(sheetname "")
		)
		(fill
			(thermal_gap 0.5)
			(thermal_bridge_width 0.5)
			(island_removal_mode 0)
		)
		(polygon
			(pts
				(arc
					(start 77.142086 -439.760614)
					(mid 77.164404 -439.814496)
					(end 77.218286 -439.836814)
				)
				(arc
					(start 78.158086 -439.836814)
					(mid 78.211968 -439.814496)
					(end 78.234286 -439.760614)
				)
				(arc
					(start 78.234286 -437.21909)
					(mid 78.211968 -437.165208)
					(end 78.158086 -437.14289)
				)
				(arc
					(start 77.218286 -437.14289)
					(mid 77.164404 -437.165208)
					(end 77.142086 -437.21909)
				)
				(arc
					(start 77.142086 -437.946546)
					(mid 77.144085 -437.963887)
					(end 77.14996 -437.980328)
				)
				(arc
					(start 77.383386 -438.456578)
					(mid 77.391169 -438.490106)
					(end 77.383386 -438.523634)
				)
				(arc
					(start 77.14996 -438.999884)
					(mid 77.144065 -439.01632)
					(end 77.142086 -439.033666)
				)
			)
		)
	)
	(zone
		(layer "In16.Cu")
		(hatch none 0.5)
		(connect_pads
			(clearance 0)
		)
		(min_thickness 0.25)
		(keepout
			(tracks not_allowed)
			(vias allowed)
			(pads allowed)
			(copperpour not_allowed)
			(footprints allowed)
		)
		(placement
			(enabled no)
			(sheetname "")
		)
		(fill
			(thermal_gap 0.5)
			(thermal_bridge_width 0.5)
			(island_removal_mode 0)
		)
		(polygon
			(pts
				(arc
					(start 320.736722 -394.552424)
					(mid 320.846693 -394.653478)
					(end 320.991484 -394.690092)
				)
				(arc
					(start 320.991484 -394.690092)
					(mid 321.20701 -394.600818)
					(end 321.296284 -394.385292)
				)
				(arc
					(start 321.296284 -394.385292)
					(mid 321.285947 -394.306553)
					(end 321.255644 -394.233146)
				)
				(arc
					(start 320.863214 -393.554204)
					(mid 320.750817 -393.432587)
					(end 320.591434 -393.38758)
				)
				(arc
					(start 320.591434 -393.38758)
					(mid 320.375908 -393.476854)
					(end 320.286634 -393.69238)
				)
				(arc
					(start 320.286634 -393.69238)
					(mid 320.296212 -393.768442)
					(end 320.32448 -393.8397)
				)
				(xy 320.721736 -394.527024) (xy 320.733928 -394.54836) (xy 320.736468 -394.552678)
			)
		)
	)
	(zone
		(layer "In16.Cu")
		(hatch none 0.5)
		(connect_pads
			(clearance 0)
		)
		(min_thickness 0.25)
		(keepout
			(tracks not_allowed)
			(vias allowed)
			(pads allowed)
			(copperpour not_allowed)
			(footprints allowed)
		)
		(placement
			(enabled no)
			(sheetname "")
		)
		(fill
			(thermal_gap 0.5)
			(thermal_bridge_width 0.5)
			(island_removal_mode 0)
		)
		(polygon
			(pts
				(arc
					(start 385.2418 -438.760616)
					(mid 385.264118 -438.814498)
					(end 385.318 -438.836816)
				)
				(arc
					(start 386.2578 -438.836816)
					(mid 386.311682 -438.814498)
					(end 386.334 -438.760616)
				)
				(arc
					(start 386.334 -436.219092)
					(mid 386.311682 -436.16521)
					(end 386.2578 -436.142892)
				)
				(arc
					(start 385.318 -436.142892)
					(mid 385.264118 -436.16521)
					(end 385.2418 -436.219092)
				)
				(arc
					(start 385.2418 -436.946548)
					(mid 385.243799 -436.963889)
					(end 385.249674 -436.98033)
				)
				(arc
					(start 385.4831 -437.45658)
					(mid 385.490883 -437.490108)
					(end 385.4831 -437.523636)
				)
				(arc
					(start 385.249674 -437.999886)
					(mid 385.243779 -438.016322)
					(end 385.2418 -438.033668)
				)
			)
		)
	)
	(zone
		(layer "In16.Cu")
		(hatch none 0.5)
		(connect_pads
			(clearance 0)
		)
		(min_thickness 0.25)
		(keepout
			(tracks not_allowed)
			(vias allowed)
			(pads allowed)
			(copperpour not_allowed)
			(footprints allowed)
		)
		(placement
			(enabled no)
			(sheetname "")
		)
		(fill
			(thermal_gap 0.5)
			(thermal_bridge_width 0.5)
			(island_removal_mode 0)
		)
		(polygon
			(pts
				(arc
					(start 383.241804 -439.760614)
					(mid 383.264122 -439.814496)
					(end 383.318004 -439.836814)
				)
				(arc
					(start 384.257804 -439.836814)
					(mid 384.311686 -439.814496)
					(end 384.334004 -439.760614)
				)
				(arc
					(start 384.334004 -437.21909)
					(mid 384.311686 -437.165208)
					(end 384.257804 -437.14289)
				)
				(arc
					(start 383.318004 -437.14289)
					(mid 383.264122 -437.165208)
					(end 383.241804 -437.21909)
				)
				(arc
					(start 383.241804 -437.946546)
					(mid 383.243803 -437.963887)
					(end 383.249678 -437.980328)
				)
				(arc
					(start 383.483104 -438.456578)
					(mid 383.490887 -438.490106)
					(end 383.483104 -438.523634)
				)
				(arc
					(start 383.249678 -438.999884)
					(mid 383.243783 -439.01632)
					(end 383.241804 -439.033666)
				)
			)
		)
	)
	(zone
		(layer "In16.Cu")
		(hatch none 0.5)
		(connect_pads
			(clearance 0)
		)
		(min_thickness 0.25)
		(keepout
			(tracks not_allowed)
			(vias allowed)
			(pads allowed)
			(copperpour not_allowed)
			(footprints allowed)
		)
		(placement
			(enabled no)
			(sheetname "")
		)
		(fill
			(thermal_gap 0.5)
			(thermal_bridge_width 0.5)
			(island_removal_mode 0)
		)
		(polygon
			(pts
				(arc
					(start 381.241808 -438.760616)
					(mid 381.264126 -438.814498)
					(end 381.318008 -438.836816)
				)
				(arc
					(start 382.257808 -438.836816)
					(mid 382.31169 -438.814498)
					(end 382.334008 -438.760616)
				)
				(arc
					(start 382.334008 -436.219092)
					(mid 382.31169 -436.16521)
					(end 382.257808 -436.142892)
				)
				(arc
					(start 381.318008 -436.142892)
					(mid 381.264126 -436.16521)
					(end 381.241808 -436.219092)
				)
				(arc
					(start 381.241808 -436.946548)
					(mid 381.243807 -436.963889)
					(end 381.249682 -436.98033)
				)
				(arc
					(start 381.483108 -437.45658)
					(mid 381.490891 -437.490108)
					(end 381.483108 -437.523636)
				)
				(arc
					(start 381.249682 -437.999886)
					(mid 381.243787 -438.016322)
					(end 381.241808 -438.033668)
				)
			)
		)
	)
	(zone
		(layer "In16.Cu")
		(hatch none 0.5)
		(connect_pads
			(clearance 0)
		)
		(min_thickness 0.25)
		(keepout
			(tracks not_allowed)
			(vias allowed)
			(pads allowed)
			(copperpour not_allowed)
			(footprints allowed)
		)
		(placement
			(enabled no)
			(sheetname "")
		)
		(fill
			(thermal_gap 0.5)
			(thermal_bridge_width 0.5)
			(island_removal_mode 0)
		)
		(polygon
			(pts
				(arc
					(start 12.187682 -111.263684)
					(mid 12.202561 -111.227763)
					(end 12.238482 -111.212884)
				)
				(arc
					(start 12.314682 -111.212884)
					(mid 12.350603 -111.227763)
					(end 12.365482 -111.263684)
				)
				(arc
					(start 12.365482 -111.974884)
					(mid 12.350603 -112.010805)
					(end 12.314682 -112.025684)
				)
				(arc
					(start 12.238482 -112.025684)
					(mid 12.202561 -112.010805)
					(end 12.187682 -111.974884)
				)
			)
		)
	)
	(zone
		(layer "In16.Cu")
		(hatch none 0.5)
		(connect_pads
			(clearance 0)
		)
		(min_thickness 0.25)
		(keepout
			(tracks not_allowed)
			(vias allowed)
			(pads allowed)
			(copperpour not_allowed)
			(footprints allowed)
		)
		(placement
			(enabled no)
			(sheetname "")
		)
		(fill
			(thermal_gap 0.5)
			(thermal_bridge_width 0.5)
			(island_removal_mode 0)
		)
		(polygon
			(pts
				(arc
					(start 318.336676 -394.552424)
					(mid 318.446647 -394.653478)
					(end 318.591438 -394.690092)
				)
				(arc
					(start 318.591438 -394.690092)
					(mid 318.806964 -394.600818)
					(end 318.896238 -394.385292)
				)
				(arc
					(start 318.896238 -394.385292)
					(mid 318.885901 -394.306553)
					(end 318.855598 -394.233146)
				)
				(arc
					(start 318.463168 -393.554204)
					(mid 318.350771 -393.432587)
					(end 318.191388 -393.38758)
				)
				(arc
					(start 318.191388 -393.38758)
					(mid 317.975862 -393.476854)
					(end 317.886588 -393.69238)
				)
				(arc
					(start 317.886588 -393.69238)
					(mid 317.896166 -393.768442)
					(end 317.924434 -393.8397)
				)
				(xy 318.32169 -394.527024) (xy 318.333882 -394.54836) (xy 318.336422 -394.552678)
			)
		)
	)
	(zone
		(layer "In16.Cu")
		(hatch none 0.5)
		(connect_pads
			(clearance 0)
		)
		(min_thickness 0.25)
		(keepout
			(tracks not_allowed)
			(vias allowed)
			(pads allowed)
			(copperpour not_allowed)
			(footprints allowed)
		)
		(placement
			(enabled no)
			(sheetname "")
		)
		(fill
			(thermal_gap 0.5)
			(thermal_bridge_width 0.5)
			(island_removal_mode 0)
		)
		(polygon
			(pts
				(arc
					(start 315.314584 3.093974)
					(mid 315.336902 3.147856)
					(end 315.390784 3.170174)
				)
				(arc
					(start 316.002924 3.170174)
					(mid 316.056806 3.147856)
					(end 316.079124 3.093974)
				)
				(arc
					(start 316.079124 1.996694)
					(mid 316.056806 1.942812)
					(end 316.002924 1.920494)
				)
				(arc
					(start 315.390784 1.920494)
					(mid 315.336902 1.942812)
					(end 315.314584 1.996694)
				)
			)
		)
	)
	(zone
		(layer "In16.Cu")
		(hatch none 0.5)
		(connect_pads
			(clearance 0)
		)
		(min_thickness 0.25)
		(keepout
			(tracks not_allowed)
			(vias allowed)
			(pads allowed)
			(copperpour not_allowed)
			(footprints allowed)
		)
		(placement
			(enabled no)
			(sheetname "")
		)
		(fill
			(thermal_gap 0.5)
			(thermal_bridge_width 0.5)
			(island_removal_mode 0)
		)
		(polygon
			(pts
				(arc
					(start 440.436254 8.138668)
					(mid 440.413936 8.084786)
					(end 440.360054 8.062468)
				)
				(arc
					(start 439.747914 8.062468)
					(mid 439.694032 8.084786)
					(end 439.671714 8.138668)
				)
				(arc
					(start 439.671714 9.235948)
					(mid 439.694032 9.28983)
					(end 439.747914 9.312148)
				)
				(arc
					(start 440.360054 9.312148)
					(mid 440.413936 9.28983)
					(end 440.436254 9.235948)
				)
			)
		)
	)
	(zone
		(layer "In16.Cu")
		(hatch none 0.5)
		(connect_pads
			(clearance 0)
		)
		(min_thickness 0.25)
		(keepout
			(tracks not_allowed)
			(vias allowed)
			(pads allowed)
			(copperpour not_allowed)
			(footprints allowed)
		)
		(placement
			(enabled no)
			(sheetname "")
		)
		(fill
			(thermal_gap 0.5)
			(thermal_bridge_width 0.5)
			(island_removal_mode 0)
		)
		(polygon
			(pts
				(arc
					(start 152.242012 -439.760614)
					(mid 152.26433 -439.814496)
					(end 152.318212 -439.836814)
				)
				(arc
					(start 153.258012 -439.836814)
					(mid 153.311894 -439.814496)
					(end 153.334212 -439.760614)
				)
				(arc
					(start 153.334212 -437.21909)
					(mid 153.311894 -437.165208)
					(end 153.258012 -437.14289)
				)
				(arc
					(start 152.318212 -437.14289)
					(mid 152.26433 -437.165208)
					(end 152.242012 -437.21909)
				)
				(arc
					(start 152.242012 -437.946546)
					(mid 152.244011 -437.963887)
					(end 152.249886 -437.980328)
				)
				(arc
					(start 152.483312 -438.456578)
					(mid 152.491095 -438.490106)
					(end 152.483312 -438.523634)
				)
				(arc
					(start 152.249886 -438.999884)
					(mid 152.243991 -439.01632)
					(end 152.242012 -439.033666)
				)
			)
		)
	)
	(zone
		(layer "In16.Cu")
		(hatch none 0.5)
		(connect_pads
			(clearance 0)
		)
		(min_thickness 0.25)
		(keepout
			(tracks not_allowed)
			(vias allowed)
			(pads allowed)
			(copperpour not_allowed)
			(footprints allowed)
		)
		(placement
			(enabled no)
			(sheetname "")
		)
		(fill
			(thermal_gap 0.5)
			(thermal_bridge_width 0.5)
			(island_removal_mode 0)
		)
		(polygon
			(pts
				(arc
					(start 212.820504 -1.986026)
					(mid 212.842822 -1.932144)
					(end 212.896704 -1.909826)
				)
				(arc
					(start 213.508844 -1.909826)
					(mid 213.562726 -1.932144)
					(end 213.585044 -1.986026)
				)
				(arc
					(start 213.585044 -3.083306)
					(mid 213.562726 -3.137188)
					(end 213.508844 -3.159506)
				)
				(arc
					(start 212.896704 -3.159506)
					(mid 212.842822 -3.137188)
					(end 212.820504 -3.083306)
				)
			)
		)
	)
	(zone
		(layer "In16.Cu")
		(hatch none 0.5)
		(connect_pads
			(clearance 0)
		)
		(min_thickness 0.25)
		(keepout
			(tracks not_allowed)
			(vias allowed)
			(pads allowed)
			(copperpour not_allowed)
			(footprints allowed)
		)
		(placement
			(enabled no)
			(sheetname "")
		)
		(fill
			(thermal_gap 0.5)
			(thermal_bridge_width 0.5)
			(island_removal_mode 0)
		)
		(polygon
			(pts
				(arc
					(start 365.939578 -3.088386)
					(mid 365.91726 -3.142268)
					(end 365.863378 -3.164586)
				)
				(arc
					(start 365.251238 -3.164586)
					(mid 365.197356 -3.142268)
					(end 365.175038 -3.088386)
				)
				(arc
					(start 365.175038 -1.991106)
					(mid 365.197356 -1.937224)
					(end 365.251238 -1.914906)
				)
				(arc
					(start 365.863378 -1.914906)
					(mid 365.91726 -1.937224)
					(end 365.939578 -1.991106)
				)
			)
		)
	)
	(zone
		(layer "In16.Cu")
		(hatch none 0.5)
		(connect_pads
			(clearance 0)
		)
		(min_thickness 0.25)
		(keepout
			(tracks not_allowed)
			(vias allowed)
			(pads allowed)
			(copperpour not_allowed)
			(footprints allowed)
		)
		(placement
			(enabled no)
			(sheetname "")
		)
		(fill
			(thermal_gap 0.5)
			(thermal_bridge_width 0.5)
			(island_removal_mode 0)
		)
		(polygon
			(pts
				(arc
					(start 156.242004 -439.760614)
					(mid 156.264322 -439.814496)
					(end 156.318204 -439.836814)
				)
				(arc
					(start 157.258004 -439.836814)
					(mid 157.311886 -439.814496)
					(end 157.334204 -439.760614)
				)
				(arc
					(start 157.334204 -437.21909)
					(mid 157.311886 -437.165208)
					(end 157.258004 -437.14289)
				)
				(arc
					(start 156.318204 -437.14289)
					(mid 156.264322 -437.165208)
					(end 156.242004 -437.21909)
				)
				(arc
					(start 156.242004 -437.946546)
					(mid 156.244003 -437.963887)
					(end 156.249878 -437.980328)
				)
				(arc
					(start 156.483304 -438.456578)
					(mid 156.491087 -438.490106)
					(end 156.483304 -438.523634)
				)
				(arc
					(start 156.249878 -438.999884)
					(mid 156.243983 -439.01632)
					(end 156.242004 -439.033666)
				)
			)
		)
	)
	(zone
		(layer "In16.Cu")
		(hatch none 0.5)
		(connect_pads
			(clearance 0)
		)
		(min_thickness 0.25)
		(keepout
			(tracks not_allowed)
			(vias allowed)
			(pads allowed)
			(copperpour not_allowed)
			(footprints allowed)
		)
		(placement
			(enabled no)
			(sheetname "")
		)
		(fill
			(thermal_gap 0.5)
			(thermal_bridge_width 0.5)
			(island_removal_mode 0)
		)
		(polygon
			(pts
				(arc
					(start 393.241784 -438.760616)
					(mid 393.264102 -438.814498)
					(end 393.317984 -438.836816)
				)
				(arc
					(start 394.257784 -438.836816)
					(mid 394.311666 -438.814498)
					(end 394.333984 -438.760616)
				)
				(arc
					(start 394.333984 -436.219092)
					(mid 394.311666 -436.16521)
					(end 394.257784 -436.142892)
				)
				(arc
					(start 393.317984 -436.142892)
					(mid 393.264102 -436.16521)
					(end 393.241784 -436.219092)
				)
				(arc
					(start 393.241784 -436.946548)
					(mid 393.243783 -436.963889)
					(end 393.249658 -436.98033)
				)
				(arc
					(start 393.483084 -437.45658)
					(mid 393.490867 -437.490108)
					(end 393.483084 -437.523636)
				)
				(arc
					(start 393.249658 -437.999886)
					(mid 393.243763 -438.016322)
					(end 393.241784 -438.033668)
				)
			)
		)
	)
	(zone
		(layer "In16.Cu")
		(hatch none 0.5)
		(connect_pads
			(clearance 0)
		)
		(min_thickness 0.25)
		(keepout
			(tracks not_allowed)
			(vias allowed)
			(pads allowed)
			(copperpour not_allowed)
			(footprints allowed)
		)
		(placement
			(enabled no)
			(sheetname "")
		)
		(fill
			(thermal_gap 0.5)
			(thermal_bridge_width 0.5)
			(island_removal_mode 0)
		)
		(polygon
			(pts
				(arc
					(start 81.142078 -439.760614)
					(mid 81.164396 -439.814496)
					(end 81.218278 -439.836814)
				)
				(arc
					(start 82.158078 -439.836814)
					(mid 82.21196 -439.814496)
					(end 82.234278 -439.760614)
				)
				(arc
					(start 82.234278 -437.21909)
					(mid 82.21196 -437.165208)
					(end 82.158078 -437.14289)
				)
				(arc
					(start 81.218278 -437.14289)
					(mid 81.164396 -437.165208)
					(end 81.142078 -437.21909)
				)
				(arc
					(start 81.142078 -437.946546)
					(mid 81.144077 -437.963887)
					(end 81.149952 -437.980328)
				)
				(arc
					(start 81.383378 -438.456578)
					(mid 81.391161 -438.490106)
					(end 81.383378 -438.523634)
				)
				(arc
					(start 81.149952 -438.999884)
					(mid 81.144057 -439.01632)
					(end 81.142078 -439.033666)
				)
			)
		)
	)
	(zone
		(layer "In16.Cu")
		(hatch none 0.5)
		(connect_pads
			(clearance 0)
		)
		(min_thickness 0.25)
		(keepout
			(tracks not_allowed)
			(vias allowed)
			(pads allowed)
			(copperpour not_allowed)
			(footprints allowed)
		)
		(placement
			(enabled no)
			(sheetname "")
		)
		(fill
			(thermal_gap 0.5)
			(thermal_bridge_width 0.5)
			(island_removal_mode 0)
		)
		(polygon
			(pts
				(arc
					(start 365.939578 7.071614)
					(mid 365.91726 7.017732)
					(end 365.863378 6.995414)
				)
				(arc
					(start 365.251238 6.995414)
					(mid 365.197356 7.017732)
					(end 365.175038 7.071614)
				)
				(arc
					(start 365.175038 8.168894)
					(mid 365.197356 8.222776)
					(end 365.251238 8.245094)
				)
				(arc
					(start 365.863378 8.245094)
					(mid 365.91726 8.222776)
					(end 365.939578 8.168894)
				)
			)
		)
	)
	(zone
		(layer "In16.Cu")
		(hatch none 0.5)
		(connect_pads
			(clearance 0)
		)
		(min_thickness 0.25)
		(keepout
			(tracks not_allowed)
			(vias allowed)
			(pads allowed)
			(copperpour not_allowed)
			(footprints allowed)
		)
		(placement
			(enabled no)
			(sheetname "")
		)
		(fill
			(thermal_gap 0.5)
			(thermal_bridge_width 0.5)
			(island_removal_mode 0)
		)
		(polygon
			(pts
				(arc
					(start 300.189392 -3.088386)
					(mid 300.167074 -3.142268)
					(end 300.113192 -3.164586)
				)
				(arc
					(start 299.501052 -3.164586)
					(mid 299.44717 -3.142268)
					(end 299.424852 -3.088386)
				)
				(arc
					(start 299.424852 -1.991106)
					(mid 299.44717 -1.937224)
					(end 299.501052 -1.914906)
				)
				(arc
					(start 300.113192 -1.914906)
					(mid 300.167074 -1.937224)
					(end 300.189392 -1.991106)
				)
			)
		)
	)
	(zone
		(layer "In16.Cu")
		(hatch none 0.5)
		(connect_pads
			(clearance 0)
		)
		(min_thickness 0.25)
		(keepout
			(tracks not_allowed)
			(vias allowed)
			(pads allowed)
			(copperpour not_allowed)
			(footprints allowed)
		)
		(placement
			(enabled no)
			(sheetname "")
		)
		(fill
			(thermal_gap 0.5)
			(thermal_bridge_width 0.5)
			(island_removal_mode 0)
		)
		(polygon
			(pts
				(arc
					(start 389.81126 9.241028)
					(mid 389.833578 9.29491)
					(end 389.88746 9.317228)
				)
				(arc
					(start 390.4996 9.317228)
					(mid 390.553482 9.29491)
					(end 390.5758 9.241028)
				)
				(arc
					(start 390.5758 8.143748)
					(mid 390.553482 8.089866)
					(end 390.4996 8.067548)
				)
				(arc
					(start 389.88746 8.067548)
					(mid 389.833578 8.089866)
					(end 389.81126 8.143748)
				)
			)
		)
	)
	(zone
		(layer "In16.Cu")
		(hatch none 0.5)
		(connect_pads
			(clearance 0)
		)
		(min_thickness 0.25)
		(keepout
			(tracks not_allowed)
			(vias allowed)
			(pads allowed)
			(copperpour not_allowed)
			(footprints allowed)
		)
		(placement
			(enabled no)
			(sheetname "")
		)
		(fill
			(thermal_gap 0.5)
			(thermal_bridge_width 0.5)
			(island_removal_mode 0)
		)
		(polygon
			(pts
				(arc
					(start 391.241788 -439.760614)
					(mid 391.264106 -439.814496)
					(end 391.317988 -439.836814)
				)
				(arc
					(start 392.257788 -439.836814)
					(mid 392.31167 -439.814496)
					(end 392.333988 -439.760614)
				)
				(arc
					(start 392.333988 -437.21909)
					(mid 392.31167 -437.165208)
					(end 392.257788 -437.14289)
				)
				(arc
					(start 391.317988 -437.14289)
					(mid 391.264106 -437.165208)
					(end 391.241788 -437.21909)
				)
				(arc
					(start 391.241788 -437.946546)
					(mid 391.243787 -437.963887)
					(end 391.249662 -437.980328)
				)
				(arc
					(start 391.483088 -438.456578)
					(mid 391.490871 -438.490106)
					(end 391.483088 -438.523634)
				)
				(arc
					(start 391.249662 -438.999884)
					(mid 391.243767 -439.01632)
					(end 391.241788 -439.033666)
				)
			)
		)
	)
	(zone
		(layer "In16.Cu")
		(hatch none 0.5)
		(connect_pads
			(clearance 0)
		)
		(min_thickness 0.25)
		(keepout
			(tracks not_allowed)
			(vias allowed)
			(pads allowed)
			(copperpour not_allowed)
			(footprints allowed)
		)
		(placement
			(enabled no)
			(sheetname "")
		)
		(fill
			(thermal_gap 0.5)
			(thermal_bridge_width 0.5)
			(island_removal_mode 0)
		)
		(polygon
			(pts
				(arc
					(start 98.144838 4.074414)
					(mid 98.167156 4.128296)
					(end 98.221038 4.150614)
				)
				(arc
					(start 98.833178 4.150614)
					(mid 98.88706 4.128296)
					(end 98.909378 4.074414)
				)
				(arc
					(start 98.909378 2.977134)
					(mid 98.88706 2.923252)
					(end 98.833178 2.900934)
				)
				(arc
					(start 98.221038 2.900934)
					(mid 98.167156 2.923252)
					(end 98.144838 2.977134)
				)
			)
		)
	)
	(zone
		(layer "In16.Cu")
		(hatch none 0.5)
		(connect_pads
			(clearance 0)
		)
		(min_thickness 0.25)
		(keepout
			(tracks not_allowed)
			(vias allowed)
			(pads allowed)
			(copperpour not_allowed)
			(footprints allowed)
		)
		(placement
			(enabled no)
			(sheetname "")
		)
		(fill
			(thermal_gap 0.5)
			(thermal_bridge_width 0.5)
			(island_removal_mode 0)
		)
		(polygon
			(pts
				(arc
					(start 79.142082 -438.760616)
					(mid 79.1644 -438.814498)
					(end 79.218282 -438.836816)
				)
				(arc
					(start 80.158082 -438.836816)
					(mid 80.211964 -438.814498)
					(end 80.234282 -438.760616)
				)
				(arc
					(start 80.234282 -436.219092)
					(mid 80.211964 -436.16521)
					(end 80.158082 -436.142892)
				)
				(arc
					(start 79.218282 -436.142892)
					(mid 79.1644 -436.16521)
					(end 79.142082 -436.219092)
				)
				(arc
					(start 79.142082 -436.946548)
					(mid 79.144081 -436.963889)
					(end 79.149956 -436.98033)
				)
				(arc
					(start 79.383382 -437.45658)
					(mid 79.391165 -437.490108)
					(end 79.383382 -437.523636)
				)
				(arc
					(start 79.149956 -437.999886)
					(mid 79.144061 -438.016322)
					(end 79.142082 -438.033668)
				)
			)
		)
	)
	(zone
		(layer "In16.Cu")
		(hatch none 0.5)
		(connect_pads
			(clearance 0)
		)
		(min_thickness 0.25)
		(keepout
			(tracks not_allowed)
			(vias allowed)
			(pads allowed)
			(copperpour not_allowed)
			(footprints allowed)
		)
		(placement
			(enabled no)
			(sheetname "")
		)
		(fill
			(thermal_gap 0.5)
			(thermal_bridge_width 0.5)
			(island_removal_mode 0)
		)
		(polygon
			(pts
				(arc
					(start 314.736734 -394.552424)
					(mid 314.846705 -394.653478)
					(end 314.991496 -394.690092)
				)
				(arc
					(start 314.991496 -394.690092)
					(mid 315.207022 -394.600818)
					(end 315.296296 -394.385292)
				)
				(arc
					(start 315.296296 -394.385292)
					(mid 315.285959 -394.306553)
					(end 315.255656 -394.233146)
				)
				(arc
					(start 314.863226 -393.554204)
					(mid 314.750829 -393.432587)
					(end 314.591446 -393.38758)
				)
				(arc
					(start 314.591446 -393.38758)
					(mid 314.37592 -393.476854)
					(end 314.286646 -393.69238)
				)
				(arc
					(start 314.286646 -393.69238)
					(mid 314.296224 -393.768442)
					(end 314.324492 -393.8397)
				)
				(xy 314.721748 -394.527024) (xy 314.73394 -394.54836) (xy 314.73648 -394.552678)
			)
		)
	)
	(zone
		(layer "In16.Cu")
		(hatch none 0.5)
		(connect_pads
			(clearance 0)
		)
		(min_thickness 0.25)
		(keepout
			(tracks not_allowed)
			(vias allowed)
			(pads allowed)
			(copperpour not_allowed)
			(footprints allowed)
		)
		(placement
			(enabled no)
			(sheetname "")
		)
		(fill
			(thermal_gap 0.5)
			(thermal_bridge_width 0.5)
			(island_removal_mode 0)
		)
		(polygon
			(pts
				(arc
					(start 300.189392 1.991614)
					(mid 300.167074 1.937732)
					(end 300.113192 1.915414)
				)
				(arc
					(start 299.501052 1.915414)
					(mid 299.44717 1.937732)
					(end 299.424852 1.991614)
				)
				(arc
					(start 299.424852 3.088894)
					(mid 299.44717 3.142776)
					(end 299.501052 3.165094)
				)
				(arc
					(start 300.113192 3.165094)
					(mid 300.167074 3.142776)
					(end 300.189392 3.088894)
				)
			)
		)
	)
	(zone
		(layer "In16.Cu")
		(hatch none 0.5)
		(connect_pads
			(clearance 0)
		)
		(min_thickness 0.25)
		(keepout
			(tracks not_allowed)
			(vias allowed)
			(pads allowed)
			(copperpour not_allowed)
			(footprints allowed)
		)
		(placement
			(enabled no)
			(sheetname "")
		)
		(fill
			(thermal_gap 0.5)
			(thermal_bridge_width 0.5)
			(island_removal_mode 0)
		)
		(polygon
			(pts
				(arc
					(start 148.24202 -439.760614)
					(mid 148.264338 -439.814496)
					(end 148.31822 -439.836814)
				)
				(arc
					(start 149.25802 -439.836814)
					(mid 149.311902 -439.814496)
					(end 149.33422 -439.760614)
				)
				(arc
					(start 149.33422 -437.21909)
					(mid 149.311902 -437.165208)
					(end 149.25802 -437.14289)
				)
				(arc
					(start 148.31822 -437.14289)
					(mid 148.264338 -437.165208)
					(end 148.24202 -437.21909)
				)
				(arc
					(start 148.24202 -437.946546)
					(mid 148.244019 -437.963887)
					(end 148.249894 -437.980328)
				)
				(arc
					(start 148.48332 -438.456578)
					(mid 148.491103 -438.490106)
					(end 148.48332 -438.523634)
				)
				(arc
					(start 148.249894 -438.999884)
					(mid 148.243999 -439.01632)
					(end 148.24202 -439.033666)
				)
			)
		)
	)
	(zone
		(layer "In16.Cu")
		(hatch none 0.5)
		(connect_pads
			(clearance 0)
		)
		(min_thickness 0.25)
		(keepout
			(tracks not_allowed)
			(vias allowed)
			(pads allowed)
			(copperpour not_allowed)
			(footprints allowed)
		)
		(placement
			(enabled no)
			(sheetname "")
		)
		(fill
			(thermal_gap 0.5)
			(thermal_bridge_width 0.5)
			(island_removal_mode 0)
		)
		(polygon
			(pts
				(arc
					(start 11.787886 -112.663732)
					(mid 11.802765 -112.627811)
					(end 11.838686 -112.612932)
				)
				(arc
					(start 11.914886 -112.612932)
					(mid 11.950807 -112.627811)
					(end 11.965686 -112.663732)
				)
				(arc
					(start 11.965686 -113.374932)
					(mid 11.950807 -113.410853)
					(end 11.914886 -113.425732)
				)
				(arc
					(start 11.838686 -113.425732)
					(mid 11.802765 -113.410853)
					(end 11.787886 -113.374932)
				)
			)
		)
	)
	(zone
		(layer "In16.Cu")
		(hatch none 0.5)
		(connect_pads
			(clearance 0)
		)
		(min_thickness 0.25)
		(keepout
			(tracks not_allowed)
			(vias allowed)
			(pads allowed)
			(copperpour not_allowed)
			(footprints allowed)
		)
		(placement
			(enabled no)
			(sheetname "")
		)
		(fill
			(thermal_gap 0.5)
			(thermal_bridge_width 0.5)
			(island_removal_mode 0)
		)
		(polygon
			(pts
				(arc
					(start 144.242028 -439.760614)
					(mid 144.264346 -439.814496)
					(end 144.318228 -439.836814)
				)
				(arc
					(start 145.258028 -439.836814)
					(mid 145.31191 -439.814496)
					(end 145.334228 -439.760614)
				)
				(arc
					(start 145.334228 -437.21909)
					(mid 145.31191 -437.165208)
					(end 145.258028 -437.14289)
				)
				(arc
					(start 144.318228 -437.14289)
					(mid 144.264346 -437.165208)
					(end 144.242028 -437.21909)
				)
				(arc
					(start 144.242028 -437.946546)
					(mid 144.244027 -437.963887)
					(end 144.249902 -437.980328)
				)
				(arc
					(start 144.483328 -438.456578)
					(mid 144.491111 -438.490106)
					(end 144.483328 -438.523634)
				)
				(arc
					(start 144.249902 -438.999884)
					(mid 144.244007 -439.01632)
					(end 144.242028 -439.033666)
				)
			)
		)
	)
	(zone
		(layer "In16.Cu")
		(hatch none 0.5)
		(connect_pads
			(clearance 0)
		)
		(min_thickness 0.25)
		(keepout
			(tracks not_allowed)
			(vias allowed)
			(pads allowed)
			(copperpour not_allowed)
			(footprints allowed)
		)
		(placement
			(enabled no)
			(sheetname "")
		)
		(fill
			(thermal_gap 0.5)
			(thermal_bridge_width 0.5)
			(island_removal_mode 0)
		)
		(polygon
			(pts
				(arc
					(start 328.141584 -439.760614)
					(mid 328.163902 -439.814496)
					(end 328.217784 -439.836814)
				)
				(arc
					(start 329.157584 -439.836814)
					(mid 329.211466 -439.814496)
					(end 329.233784 -439.760614)
				)
				(arc
					(start 329.233784 -437.21909)
					(mid 329.211466 -437.165208)
					(end 329.157584 -437.14289)
				)
				(arc
					(start 328.217784 -437.14289)
					(mid 328.163902 -437.165208)
					(end 328.141584 -437.21909)
				)
				(arc
					(start 328.141584 -437.946546)
					(mid 328.143583 -437.963887)
					(end 328.149458 -437.980328)
				)
				(arc
					(start 328.382884 -438.456578)
					(mid 328.390667 -438.490106)
					(end 328.382884 -438.523634)
				)
				(arc
					(start 328.149458 -438.999884)
					(mid 328.143563 -439.01632)
					(end 328.141584 -439.033666)
				)
			)
		)
	)
	(zone
		(layer "In16.Cu")
		(hatch none 0.5)
		(connect_pads
			(clearance 0)
		)
		(min_thickness 0.25)
		(keepout
			(tracks not_allowed)
			(vias allowed)
			(pads allowed)
			(copperpour not_allowed)
			(footprints allowed)
		)
		(placement
			(enabled no)
			(sheetname "")
		)
		(fill
			(thermal_gap 0.5)
			(thermal_bridge_width 0.5)
			(island_removal_mode 0)
		)
		(polygon
			(pts
				(arc
					(start 317.13678 -394.552424)
					(mid 317.246751 -394.653478)
					(end 317.391542 -394.690092)
				)
				(arc
					(start 317.391542 -394.690092)
					(mid 317.607068 -394.600818)
					(end 317.696342 -394.385292)
				)
				(arc
					(start 317.696342 -394.385292)
					(mid 317.686005 -394.306553)
					(end 317.655702 -394.233146)
				)
				(arc
					(start 317.263272 -393.554204)
					(mid 317.150875 -393.432587)
					(end 316.991492 -393.38758)
				)
				(arc
					(start 316.991492 -393.38758)
					(mid 316.775966 -393.476854)
					(end 316.686692 -393.69238)
				)
				(arc
					(start 316.686692 -393.69238)
					(mid 316.69627 -393.768442)
					(end 316.724538 -393.8397)
				)
				(xy 317.121794 -394.527024) (xy 317.133986 -394.54836) (xy 317.136526 -394.552678)
			)
		)
	)
	(zone
		(layer "In16.Cu")
		(hatch none 0.5)
		(connect_pads
			(clearance 0)
		)
		(min_thickness 0.25)
		(keepout
			(tracks not_allowed)
			(vias allowed)
			(pads allowed)
			(copperpour not_allowed)
			(footprints allowed)
		)
		(placement
			(enabled no)
			(sheetname "")
		)
		(fill
			(thermal_gap 0.5)
			(thermal_bridge_width 0.5)
			(island_removal_mode 0)
		)
		(polygon
			(pts
				(arc
					(start 315.314584 -1.986026)
					(mid 315.336902 -1.932144)
					(end 315.390784 -1.909826)
				)
				(arc
					(start 316.002924 -1.909826)
					(mid 316.056806 -1.932144)
					(end 316.079124 -1.986026)
				)
				(arc
					(start 316.079124 -3.083306)
					(mid 316.056806 -3.137188)
					(end 316.002924 -3.159506)
				)
				(arc
					(start 315.390784 -3.159506)
					(mid 315.336902 -3.137188)
					(end 315.314584 -3.083306)
				)
			)
		)
	)
	(zone
		(layer "In16.Cu")
		(hatch none 0.5)
		(connect_pads
			(clearance 0)
		)
		(min_thickness 0.25)
		(keepout
			(tracks not_allowed)
			(vias allowed)
			(pads allowed)
			(copperpour not_allowed)
			(footprints allowed)
		)
		(placement
			(enabled no)
			(sheetname "")
		)
		(fill
			(thermal_gap 0.5)
			(thermal_bridge_width 0.5)
			(island_removal_mode 0)
		)
		(polygon
			(pts
				(arc
					(start 83.142074 -438.760616)
					(mid 83.164392 -438.814498)
					(end 83.218274 -438.836816)
				)
				(arc
					(start 84.158074 -438.836816)
					(mid 84.211956 -438.814498)
					(end 84.234274 -438.760616)
				)
				(arc
					(start 84.234274 -436.219092)
					(mid 84.211956 -436.16521)
					(end 84.158074 -436.142892)
				)
				(arc
					(start 83.218274 -436.142892)
					(mid 83.164392 -436.16521)
					(end 83.142074 -436.219092)
				)
				(arc
					(start 83.142074 -436.946548)
					(mid 83.144073 -436.963889)
					(end 83.149948 -436.98033)
				)
				(arc
					(start 83.383374 -437.45658)
					(mid 83.391157 -437.490108)
					(end 83.383374 -437.523636)
				)
				(arc
					(start 83.149948 -437.999886)
					(mid 83.144053 -438.016322)
					(end 83.142074 -438.033668)
				)
			)
		)
	)
	(zone
		(layer "In16.Cu")
		(hatch none 0.5)
		(connect_pads
			(clearance 0)
		)
		(min_thickness 0.25)
		(keepout
			(tracks not_allowed)
			(vias allowed)
			(pads allowed)
			(copperpour not_allowed)
			(footprints allowed)
		)
		(placement
			(enabled no)
			(sheetname "")
		)
		(fill
			(thermal_gap 0.5)
			(thermal_bridge_width 0.5)
			(island_removal_mode 0)
		)
		(polygon
			(pts
				(arc
					(start 395.24178 -439.760614)
					(mid 395.264098 -439.814496)
					(end 395.31798 -439.836814)
				)
				(arc
					(start 396.25778 -439.836814)
					(mid 396.311662 -439.814496)
					(end 396.33398 -439.760614)
				)
				(arc
					(start 396.33398 -437.21909)
					(mid 396.311662 -437.165208)
					(end 396.25778 -437.14289)
				)
				(arc
					(start 395.31798 -437.14289)
					(mid 395.264098 -437.165208)
					(end 395.24178 -437.21909)
				)
				(arc
					(start 395.24178 -437.946546)
					(mid 395.243779 -437.963887)
					(end 395.249654 -437.980328)
				)
				(arc
					(start 395.48308 -438.456578)
					(mid 395.490863 -438.490106)
					(end 395.48308 -438.523634)
				)
				(arc
					(start 395.249654 -438.999884)
					(mid 395.243759 -439.01632)
					(end 395.24178 -439.033666)
				)
			)
		)
	)
	(zone
		(layer "In16.Cu")
		(hatch none 0.5)
		(connect_pads
			(clearance 0)
		)
		(min_thickness 0.25)
		(keepout
			(tracks not_allowed)
			(vias allowed)
			(pads allowed)
			(copperpour not_allowed)
			(footprints allowed)
		)
		(placement
			(enabled no)
			(sheetname "")
		)
		(fill
			(thermal_gap 0.5)
			(thermal_bridge_width 0.5)
			(island_removal_mode 0)
		)
		(polygon
			(pts
				(arc
					(start 212.820504 3.093974)
					(mid 212.842822 3.147856)
					(end 212.896704 3.170174)
				)
				(arc
					(start 213.508844 3.170174)
					(mid 213.562726 3.147856)
					(end 213.585044 3.093974)
				)
				(arc
					(start 213.585044 1.996694)
					(mid 213.562726 1.942812)
					(end 213.508844 1.920494)
				)
				(arc
					(start 212.896704 1.920494)
					(mid 212.842822 1.942812)
					(end 212.820504 1.996694)
				)
			)
		)
	)
	(zone
		(layer "In16.Cu")
		(hatch none 0.5)
		(connect_pads
			(clearance 0)
		)
		(min_thickness 0.25)
		(keepout
			(tracks not_allowed)
			(vias allowed)
			(pads allowed)
			(copperpour not_allowed)
			(footprints allowed)
		)
		(placement
			(enabled no)
			(sheetname "")
		)
		(fill
			(thermal_gap 0.5)
			(thermal_bridge_width 0.5)
			(island_removal_mode 0)
		)
		(polygon
			(pts
				(arc
					(start 315.314584 8.173974)
					(mid 315.336902 8.227856)
					(end 315.390784 8.250174)
				)
				(arc
					(start 316.002924 8.250174)
					(mid 316.056806 8.227856)
					(end 316.079124 8.173974)
				)
				(arc
					(start 316.079124 7.076694)
					(mid 316.056806 7.022812)
					(end 316.002924 7.000494)
				)
				(arc
					(start 315.390784 7.000494)
					(mid 315.336902 7.022812)
					(end 315.314584 7.076694)
				)
			)
		)
	)
	(zone
		(layer "In16.Cu")
		(hatch none 0.5)
		(connect_pads
			(clearance 0)
		)
		(min_thickness 0.25)
		(keepout
			(tracks not_allowed)
			(vias allowed)
			(pads allowed)
			(copperpour not_allowed)
			(footprints allowed)
		)
		(placement
			(enabled no)
			(sheetname "")
		)
		(fill
			(thermal_gap 0.5)
			(thermal_bridge_width 0.5)
			(island_removal_mode 0)
		)
		(polygon
			(pts
				(arc
					(start 324.141592 -439.760614)
					(mid 324.16391 -439.814496)
					(end 324.217792 -439.836814)
				)
				(arc
					(start 325.157592 -439.836814)
					(mid 325.211474 -439.814496)
					(end 325.233792 -439.760614)
				)
				(arc
					(start 325.233792 -437.21909)
					(mid 325.211474 -437.165208)
					(end 325.157592 -437.14289)
				)
				(arc
					(start 324.217792 -437.14289)
					(mid 324.16391 -437.165208)
					(end 324.141592 -437.21909)
				)
				(arc
					(start 324.141592 -437.946546)
					(mid 324.143591 -437.963887)
					(end 324.149466 -437.980328)
				)
				(arc
					(start 324.382892 -438.456578)
					(mid 324.390675 -438.490106)
					(end 324.382892 -438.523634)
				)
				(arc
					(start 324.149466 -438.999884)
					(mid 324.143571 -439.01632)
					(end 324.141592 -439.033666)
				)
			)
		)
	)
)
